G04 ================== begin FILE IDENTIFICATION RECORD ==================*
G04 Layout Name:  15750-1.brd*
G04 Film Name:    NOTICE*
G04 File Format:  Gerber RS274X*
G04 File Origin:  Cadence Allegro 16.5-S056*
G04 Origin Date:  Fri Dec 30 13:21:34 2016*
G04 *
G04 Layer:  MANUFACTURING/THERMAL*
G04 *
G04 Offset:    (0.00 0.00)*
G04 Mirror:    No*
G04 Mode:      Positive*
G04 Rotation:  0*
G04 FullContactRelief:  No*
G04 UndefLineWidth:     6.00*
G04 ================== end FILE IDENTIFICATION RECORD ====================*
%FSLAX35Y35*MOIN*%
%IR0*IPPOS*OFA0.00000B0.00000*MIA0B0*SFA1.00000B1.00000*%
%ADD10C,.004*%
%ADD11C,.006*%
%ADD12C,.0033*%
%ADD13C,.008*%
%ADD14C,.0055*%
G75*
%LPD*%
G75*
G36*
G01X-159880Y1980D02*
X-151200D01*
G03X-117090Y1970I17058J11442D01*
G01X-109540D01*
X-120410Y-19030D01*
X-148910D01*
X-159880Y1980D01*
G37*
G36*
G01X-156700Y-59110D02*
G02X-106000Y-58850I25558J-40503D01*
G01X-117150Y-80180D01*
X-145650D01*
X-156700Y-59110D01*
G37*
G54D10*
G01X361509Y-105111D02*
X311509D01*
G01D02*
Y-95111D01*
G01D02*
X331509D01*
G01X311509Y-55111D02*
X331509D01*
G01X311509Y-65111D02*
Y-55111D01*
G01X331509Y-65111D02*
X311509D01*
G01Y-25111D02*
Y-15111D01*
G01X331509Y-25111D02*
X311509D01*
G01Y-15111D02*
X331509D01*
G01X311509Y24889D02*
X351509D01*
G01X311509Y14889D02*
Y24889D01*
G01X331509Y14889D02*
X311509D01*
G01X331509Y-95111D02*
Y-65111D01*
G01Y-55111D02*
Y-25111D01*
G01Y-15111D02*
Y14889D01*
G01X350094Y-117132D02*
Y-121132D01*
G01D02*
X362094Y-119132D01*
G01X338094D02*
X362094D01*
G01D02*
X350094Y-117132D01*
G01X351505Y-38256D02*
X351509Y-38260D01*
G01Y24889D02*
Y-38260D01*
G01D02*
X361509Y-48260D01*
G01X352014Y46548D02*
Y26548D01*
G01Y34548D02*
X364014Y32548D01*
G01Y36548D02*
X352014Y34548D01*
G01D02*
X392014D01*
G01X362094Y-111132D02*
Y-131132D01*
G01X361509Y-48260D02*
Y-105111D01*
G01X364014Y32548D02*
Y36548D01*
G01X400954Y-119132D02*
X382094D01*
G01X394094Y-117132D02*
X382094Y-119132D01*
G01Y-131132D02*
Y-111132D01*
G01Y-119132D02*
X394094Y-121132D01*
G01X381509Y-105111D02*
X431509D01*
G01X381509Y-47751D02*
Y-105111D01*
G01X391509Y-37751D02*
X381509Y-47751D01*
G01X380014Y36548D02*
Y32548D01*
G01X392014Y34548D02*
X380014Y36548D01*
G01Y32548D02*
X392014Y34548D01*
G01X394094Y-121132D02*
Y-117132D01*
G01X386509Y-47751D02*
X502500D01*
G01X391509Y24889D02*
Y-37751D01*
G01X392014Y46548D02*
Y26548D01*
G01X431509Y24889D02*
X391509D01*
G01X392014Y34548D02*
X400874D01*
G01X411509Y-95111D02*
Y-65111D01*
G01X431509Y-95111D02*
X411509D01*
G01Y-55111D02*
Y-25111D01*
G01X431509Y-55111D02*
X411509D01*
G01Y-65111D02*
X431509D01*
G01X411509Y-25111D02*
X431509D01*
G01X411509Y-15111D02*
Y14889D01*
G01X431509Y-15111D02*
X411509D01*
G01Y14889D02*
X431509D01*
G01Y-105111D02*
Y-95111D01*
G01Y-65111D02*
X431500Y-55200D01*
G01X431509Y-25111D02*
Y-15111D01*
G01Y14889D02*
Y24889D01*
G01X436509Y-55111D02*
X502500D01*
G01X497500Y-79111D02*
Y-55111D01*
G01X499500Y-67111D02*
X497500Y-55111D01*
X495500Y-67111D01*
X499500D01*
G01X495500Y-35751D02*
X497500Y-47751D01*
X499500Y-35751D01*
X495500D01*
G01X497500Y-23751D02*
Y-47751D01*
G01X623154Y-103612D02*
X663154D01*
G01X623154Y-93612D02*
Y-103612D01*
G01X643154Y-93612D02*
X623154D01*
G01Y-63612D02*
X643154D01*
G01X623154Y-53612D02*
Y-63612D01*
G01X643154Y-53612D02*
X623154D01*
G01Y-23612D02*
X643154D01*
G01X623154Y-13612D02*
Y-23612D01*
G01X643154Y-13612D02*
X623154D01*
G01X673154Y26388D02*
X623154D01*
G01Y16388D02*
X643154D01*
G01X623154Y26388D02*
Y16388D01*
G01X643154Y-63612D02*
Y-93612D01*
G01Y-23612D02*
Y-53612D01*
G01Y16388D02*
Y-13612D01*
G01X649154Y46388D02*
X673154D01*
G01X663154Y-121612D02*
X675154Y-123612D01*
G01Y-119612D02*
X663154Y-121612D01*
G01D02*
X703154D01*
G01X663154Y-109612D02*
Y-129612D01*
G01Y-103612D02*
Y-40972D01*
G01D02*
X673154Y-30972D01*
G01X661154Y48388D02*
Y44388D01*
G01D02*
X673154Y46388D01*
G01D02*
X661154Y48388D01*
G01X675154Y-123612D02*
Y-119612D01*
G01X673154Y-30972D02*
Y26388D01*
G01Y54388D02*
Y34388D01*
G01X691154Y-119612D02*
Y-123612D01*
G01X703154Y-121612D02*
X691154Y-119612D01*
G01Y-123612D02*
X703154Y-121612D01*
G01Y-40463D02*
X693154Y-30463D01*
G01D02*
Y26388D01*
G01D02*
X743154D01*
G01X712014Y46388D02*
X693154D01*
G01D02*
X705154Y44388D01*
G01Y48388D02*
X693154Y46388D01*
G01Y34388D02*
Y54388D01*
G01X703154Y-121612D02*
X712014D01*
G01X703154Y-109612D02*
Y-129612D01*
G01Y-103612D02*
Y-40463D01*
G01X743154Y-103612D02*
X703154D01*
G01X703158Y-40467D02*
X703154Y-40463D01*
G01X705154Y44388D02*
Y48388D01*
G01X723154Y-93612D02*
X743154D01*
G01X723154Y-63612D02*
Y-93612D01*
G01X743154Y-63612D02*
X723154D01*
G01Y-53612D02*
X743154D01*
G01X723154Y-23612D02*
Y-53612D01*
G01X743154Y-23612D02*
X723154D01*
G01Y-13612D02*
X743154D01*
G01X723154Y16388D02*
Y-13612D01*
G01X743154Y16388D02*
X723154D01*
G01X743154Y-93612D02*
Y-103612D01*
G01Y-53612D02*
Y-63612D01*
G01Y-13612D02*
Y-23612D01*
G01Y26388D02*
Y16388D01*
G54D11*
G01X-454200Y251700D02*
X-454250D01*
G01X-404200Y497700D02*
X-404250D01*
G01X-170150Y-64180D02*
X-175150D01*
Y-90180D01*
X-170150D01*
G01X-173410Y-3030D02*
X-178410D01*
Y-29030D01*
X-173410D01*
G01X-174910Y67830D02*
X-179910D01*
Y41830D01*
X-174910D01*
G01Y46830D02*
Y41830D01*
X-97410D01*
Y46830D01*
G01X-174910D02*
X-155410D01*
X-166410Y67830D01*
X-174910D01*
Y72830D01*
X-161410D01*
X-150410Y51830D01*
X-121910D01*
X-110910Y72830D01*
X-97410D01*
Y67830D01*
X-105910D01*
X-116910Y46830D01*
X-97410D01*
G01X-170150Y-85180D02*
Y-90180D01*
X-92650D01*
Y-85180D01*
G01X-170150D02*
X-150650D01*
X-161650Y-64180D01*
X-170150D01*
Y-59180D01*
X-156650D01*
X-145650Y-80180D01*
X-117150D01*
X-106150Y-59180D01*
X-92650D01*
Y-64180D01*
X-101150D01*
X-112150Y-85180D01*
X-92650D01*
G01X-173410Y-24030D02*
X-153910D01*
X-164910Y-3030D01*
X-173410D01*
Y1970D01*
X-159910D01*
X-148910Y-19030D01*
X-120410D01*
X-109410Y1970D01*
X-95910D01*
Y-3030D01*
X-104410D01*
X-115410Y-24030D01*
X-95910D01*
G01X-173410D02*
Y-29030D01*
X-95910D01*
Y-24030D01*
G01X-154410Y81830D02*
X-166410Y79830D01*
X-154410Y77830D01*
Y81830D01*
G01X-147210Y79830D02*
X-166410D01*
G01X-143410Y37830D02*
X-155410Y35830D01*
X-143410Y33830D01*
Y37830D01*
G01X-152210Y35830D02*
X-155410D01*
G01X-118910D02*
X-154410D01*
G01X-126130Y-51690D02*
X-70360D01*
G01X-129210Y-7000D02*
X-70510D01*
G01X-128910Y33830D02*
X-116910Y35830D01*
X-128910Y37830D01*
Y33830D01*
G01X-112290Y2010D02*
X-70510D01*
G01X-118610Y35830D02*
X-116910D01*
G01X-117910Y77830D02*
X-105910Y79830D01*
X-117910Y81830D01*
Y77830D01*
G01X-123610Y79830D02*
X-105910D01*
G01X-92650Y-64180D02*
X-87650D01*
Y-90180D01*
X-92650D01*
G01X-101130Y-58870D02*
X-70360D01*
G01X-95910Y-3030D02*
X-90910D01*
Y-29030D01*
X-95910D01*
G01X-97410Y67830D02*
X-92410D01*
Y41830D01*
X-97410D01*
G01X-73360Y-70870D02*
X-75360Y-58870D01*
X-77360Y-70870D01*
X-73360D01*
G01Y-39690D02*
X-75360Y-51690D01*
X-77360Y-39690D01*
X-73360D01*
G01X-73510Y-19000D02*
X-75510Y-7000D01*
X-77510Y-19000D01*
X-73510D01*
G01Y14010D02*
X-75510Y2010D01*
X-77510Y14010D01*
X-73510D01*
G01X-75360Y-75750D02*
Y-58870D01*
G01Y-35150D02*
Y-51690D01*
G01X-75510Y-22500D02*
Y-7000D01*
G01Y2010D02*
Y17150D01*
G01X391000Y-285451D02*
X362500Y-285500D01*
G01X472840Y351629D02*
X361500D01*
G01X369000Y366629D02*
X371500Y351629D01*
X374000Y366629D01*
X369000D01*
G01X374000Y437829D02*
X371500Y452829D01*
X369000Y437829D01*
X374000D01*
G01X387840Y452829D02*
X361500D01*
G01X379003Y-287472D02*
X391000Y-285451D01*
X378997Y-283472D01*
X379003Y-287472D01*
G01X371500Y388875D02*
Y351629D01*
G01Y420125D02*
Y452829D01*
G01X391000Y-285500D02*
Y-213500D01*
X435000D01*
Y-285500D01*
X391000D01*
G01X406000Y-201000D02*
X391000Y-203500D01*
X406000Y-206000D01*
Y-201000D01*
G01X435000Y-203500D02*
X391000D01*
G01Y-208500D02*
Y-193500D01*
G01X420000Y-206000D02*
X435000Y-203500D01*
X420000Y-201000D01*
Y-206000D01*
G01X442975Y-203500D02*
X435000D01*
G01Y-208500D02*
Y-193500D01*
G01X445000Y-285500D02*
X486000D01*
G01X445000Y-213500D02*
X486000D01*
G01X473500Y-270500D02*
X476000Y-285500D01*
X478500Y-270500D01*
X473500D01*
G01X476000Y-261125D02*
Y-285500D01*
G01X478500Y-228500D02*
X476000Y-213500D01*
X473500Y-228500D01*
X478500D01*
G01X476000Y-229875D02*
Y-213500D01*
G01X656453Y355479D02*
X673000Y344000D01*
X674000D01*
G01X661416Y353861D02*
X656453Y355479D01*
X659706Y351397D01*
X661416Y353861D01*
G01X698154Y-30463D02*
X816000D01*
G01X748154Y-23612D02*
X816000D01*
G01X811000Y-54463D02*
Y-30463D01*
G01X813000Y-42463D02*
X811000Y-30463D01*
X809000Y-42463D01*
X813000D01*
G01X809000Y-11612D02*
X811000Y-23612D01*
X813000Y-11612D01*
X809000D01*
G01X811000Y4200D02*
Y-23612D01*
G01X-458500Y443000D02*
Y-342500D01*
G01D02*
X236000D01*
G01X-458500Y-297500D02*
X236000D01*
G01X-458500Y-253500D02*
X236000D01*
G01X-458500Y-167500D02*
X236000D01*
G01X-458500Y-152500D02*
X236000D01*
G01X-457000Y-97500D02*
X236000D01*
G01X-458500Y326000D02*
X236000D01*
G01X-459500Y381000D02*
X236000D01*
G01X-458500Y406000D02*
X236000D01*
G01X-458500Y577500D02*
Y436000D01*
X236000D01*
Y577500D01*
G01X-458500Y547500D02*
X236000D01*
G01X-458500Y577500D02*
X236000D01*
G01X-446750Y-321833D02*
X-446083Y-322250D01*
X-445333Y-322500D01*
X-444667D01*
X-444000Y-322250D01*
X-443500Y-321833D01*
X-443250Y-321250D01*
X-443417Y-320667D01*
X-443833Y-320167D01*
X-444583Y-319833D01*
X-445583Y-319667D01*
X-446167Y-319333D01*
X-446417Y-318750D01*
X-446250Y-318167D01*
X-445833Y-317750D01*
X-445250Y-317500D01*
X-444667D01*
X-444083Y-317667D01*
X-443583Y-318083D01*
G01X-439400Y-319167D02*
Y-322500D01*
G01Y-317833D02*
X-439567Y-317750D01*
Y-317583D01*
X-439400Y-317500D01*
X-439233Y-317583D01*
Y-317750D01*
X-439400Y-317833D01*
G01X-433800Y-322500D02*
Y-317500D01*
G01X-429617Y-322500D02*
Y-317500D01*
G01X-426950Y-319167D02*
X-429617Y-321083D01*
G01X-428533Y-320333D02*
X-426783Y-322500D01*
G01X-423850Y-321917D02*
X-423433Y-322250D01*
X-422850Y-322500D01*
X-422350D01*
X-421850Y-322333D01*
X-421517Y-322083D01*
X-421350Y-321750D01*
X-421433Y-321250D01*
X-421767Y-321000D01*
X-423267Y-320500D01*
X-423600Y-319917D01*
X-423433Y-319500D01*
X-423100Y-319250D01*
X-422600Y-319167D01*
X-422100Y-319250D01*
X-421600Y-319500D01*
G01X-415667Y-319583D02*
X-416250Y-319250D01*
X-416750Y-319167D01*
X-417417Y-319333D01*
X-417917Y-319667D01*
X-418250Y-320250D01*
X-418333Y-320833D01*
X-418250Y-321417D01*
X-417917Y-321917D01*
X-417417Y-322333D01*
X-416750Y-322500D01*
X-416167Y-322333D01*
X-415667Y-322000D01*
G01X-412567Y-322500D02*
Y-319167D01*
G01Y-319833D02*
X-412150Y-319500D01*
X-411733Y-319250D01*
X-411150Y-319167D01*
X-410733Y-319250D01*
X-410233Y-319500D01*
G01X-407050Y-320250D02*
X-404383D01*
X-404633Y-319667D01*
X-405050Y-319333D01*
X-405633Y-319167D01*
X-406217Y-319250D01*
X-406717Y-319500D01*
X-407050Y-320083D01*
X-407217Y-320583D01*
Y-321083D01*
X-407050Y-321583D01*
X-406633Y-322083D01*
X-406133Y-322417D01*
X-405550Y-322500D01*
X-404967Y-322333D01*
X-404383Y-321833D01*
G01X-401450Y-320250D02*
X-398783D01*
X-399033Y-319667D01*
X-399450Y-319333D01*
X-400033Y-319167D01*
X-400617Y-319250D01*
X-401117Y-319500D01*
X-401450Y-320083D01*
X-401617Y-320583D01*
Y-321083D01*
X-401450Y-321583D01*
X-401033Y-322083D01*
X-400533Y-322417D01*
X-399950Y-322500D01*
X-399367Y-322333D01*
X-398783Y-321833D01*
G01X-396017Y-322500D02*
Y-319167D01*
G01Y-320000D02*
X-395683Y-319583D01*
X-395183Y-319250D01*
X-394517Y-319167D01*
X-393933Y-319250D01*
X-393433Y-319583D01*
X-393183Y-320167D01*
Y-322500D01*
G01X-446750Y-276833D02*
X-446083Y-277250D01*
X-445333Y-277500D01*
X-444667D01*
X-444000Y-277250D01*
X-443500Y-276833D01*
X-443250Y-276250D01*
X-443417Y-275667D01*
X-443833Y-275167D01*
X-444583Y-274833D01*
X-445583Y-274667D01*
X-446167Y-274333D01*
X-446417Y-273750D01*
X-446250Y-273167D01*
X-445833Y-272750D01*
X-445250Y-272500D01*
X-444667D01*
X-444083Y-272667D01*
X-443583Y-273083D01*
G01X-439400Y-277500D02*
X-439900Y-277417D01*
X-440400Y-277083D01*
X-440733Y-276500D01*
X-440900Y-275833D01*
X-440733Y-275167D01*
X-440400Y-274583D01*
X-439900Y-274250D01*
X-439400Y-274167D01*
X-438900Y-274250D01*
X-438400Y-274583D01*
X-438067Y-275167D01*
X-437983Y-275833D01*
X-438067Y-276500D01*
X-438400Y-277083D01*
X-438900Y-277417D01*
X-439400Y-277500D01*
G01X-433800D02*
Y-272500D01*
G01X-426700D02*
Y-277500D01*
G01Y-276750D02*
X-427033Y-277167D01*
X-427533Y-277417D01*
X-428117Y-277500D01*
X-428783Y-277333D01*
X-429283Y-276917D01*
X-429617Y-276417D01*
X-429700Y-275833D01*
X-429617Y-275250D01*
X-429283Y-274750D01*
X-428783Y-274333D01*
X-428117Y-274167D01*
X-427533Y-274250D01*
X-427117Y-274417D01*
X-426700Y-274750D01*
G01X-423850Y-275250D02*
X-421183D01*
X-421433Y-274667D01*
X-421850Y-274333D01*
X-422433Y-274167D01*
X-423017Y-274250D01*
X-423517Y-274500D01*
X-423850Y-275083D01*
X-424017Y-275583D01*
Y-276083D01*
X-423850Y-276583D01*
X-423433Y-277083D01*
X-422933Y-277417D01*
X-422350Y-277500D01*
X-421767Y-277333D01*
X-421183Y-276833D01*
G01X-418167Y-277500D02*
Y-274167D01*
G01Y-274833D02*
X-417750Y-274500D01*
X-417333Y-274250D01*
X-416750Y-274167D01*
X-416333Y-274250D01*
X-415833Y-274500D01*
G01X-408300Y-277500D02*
Y-274167D01*
G01Y-275083D02*
X-408050Y-274667D01*
X-407633Y-274333D01*
X-407050Y-274167D01*
X-406467Y-274333D01*
X-406050Y-274667D01*
X-405800Y-275083D01*
Y-277500D01*
G01Y-275083D02*
X-405550Y-274667D01*
X-405133Y-274333D01*
X-404550Y-274167D01*
X-403967Y-274333D01*
X-403550Y-274667D01*
X-403300Y-275167D01*
Y-277500D01*
G01X-398700D02*
Y-274167D01*
G01Y-274750D02*
X-399033Y-274417D01*
X-399533Y-274250D01*
X-400117Y-274167D01*
X-400700Y-274333D01*
X-401200Y-274667D01*
X-401533Y-275167D01*
X-401700Y-275833D01*
X-401533Y-276500D01*
X-401200Y-277000D01*
X-400700Y-277333D01*
X-400117Y-277500D01*
X-399533Y-277417D01*
X-399033Y-277167D01*
X-398700Y-276833D01*
G01X-395850Y-276917D02*
X-395433Y-277250D01*
X-394850Y-277500D01*
X-394350D01*
X-393850Y-277333D01*
X-393517Y-277083D01*
X-393350Y-276750D01*
X-393433Y-276250D01*
X-393767Y-276000D01*
X-395267Y-275500D01*
X-395600Y-274917D01*
X-395433Y-274500D01*
X-395100Y-274250D01*
X-394600Y-274167D01*
X-394100Y-274250D01*
X-393600Y-274500D01*
G01X-390417Y-277500D02*
Y-272500D01*
G01X-387750Y-274167D02*
X-390417Y-276083D01*
G01X-389333Y-275333D02*
X-387583Y-277500D01*
G01X-443333Y-209000D02*
X-446667D01*
Y-204000D01*
X-443333D01*
G01X-444667Y-206417D02*
X-446667D01*
G01X-439400Y-204000D02*
Y-209000D01*
G01X-440567Y-205667D02*
X-438233D01*
G01X-432467Y-206083D02*
X-433050Y-205750D01*
X-433550Y-205667D01*
X-434217Y-205833D01*
X-434717Y-206167D01*
X-435050Y-206750D01*
X-435133Y-207333D01*
X-435050Y-207917D01*
X-434717Y-208417D01*
X-434217Y-208833D01*
X-433550Y-209000D01*
X-432967Y-208833D01*
X-432467Y-208500D01*
G01X-429617Y-209000D02*
Y-204000D01*
G01Y-206417D02*
X-429200Y-206000D01*
X-428783Y-205750D01*
X-428117Y-205667D01*
X-427617Y-205750D01*
X-427033Y-206083D01*
X-426783Y-206583D01*
Y-209000D01*
G01X-443333Y-161500D02*
X-446667D01*
Y-156500D01*
X-443333D01*
G01X-444667Y-158917D02*
X-446667D01*
G01X-440650Y-158167D02*
X-438150Y-161500D01*
G01Y-158167D02*
X-440650Y-161500D01*
G01X-433800Y-156500D02*
Y-161500D01*
G01X-434967Y-158167D02*
X-432633D01*
G01X-429450Y-159250D02*
X-426783D01*
X-427033Y-158667D01*
X-427450Y-158333D01*
X-428033Y-158167D01*
X-428617Y-158250D01*
X-429117Y-158500D01*
X-429450Y-159083D01*
X-429617Y-159583D01*
Y-160083D01*
X-429450Y-160583D01*
X-429033Y-161083D01*
X-428533Y-161417D01*
X-427950Y-161500D01*
X-427367Y-161333D01*
X-426783Y-160833D01*
G01X-423767Y-161500D02*
Y-158167D01*
G01Y-158833D02*
X-423350Y-158500D01*
X-422933Y-158250D01*
X-422350Y-158167D01*
X-421933Y-158250D01*
X-421433Y-158500D01*
G01X-418417Y-161500D02*
Y-158167D01*
G01Y-159000D02*
X-418083Y-158583D01*
X-417583Y-158250D01*
X-416917Y-158167D01*
X-416333Y-158250D01*
X-415833Y-158583D01*
X-415583Y-159167D01*
Y-161500D01*
G01X-409900D02*
Y-158167D01*
G01Y-158750D02*
X-410233Y-158417D01*
X-410733Y-158250D01*
X-411317Y-158167D01*
X-411900Y-158333D01*
X-412400Y-158667D01*
X-412733Y-159167D01*
X-412900Y-159833D01*
X-412733Y-160500D01*
X-412400Y-161000D01*
X-411900Y-161333D01*
X-411317Y-161500D01*
X-410733Y-161417D01*
X-410233Y-161167D01*
X-409900Y-160833D01*
G01X-405800Y-161500D02*
Y-156500D01*
G01X-394600Y-161500D02*
Y-156500D01*
G01X-387500Y-161500D02*
Y-158167D01*
G01Y-158750D02*
X-387833Y-158417D01*
X-388333Y-158250D01*
X-388917Y-158167D01*
X-389500Y-158333D01*
X-390000Y-158667D01*
X-390333Y-159167D01*
X-390500Y-159833D01*
X-390333Y-160500D01*
X-390000Y-161000D01*
X-389500Y-161333D01*
X-388917Y-161500D01*
X-388333Y-161417D01*
X-387833Y-161167D01*
X-387500Y-160833D01*
G01X-385150Y-163000D02*
X-384650Y-163167D01*
X-383983Y-163000D01*
X-383567Y-162667D01*
X-383233Y-162250D01*
X-382733Y-160917D01*
X-381650Y-158167D01*
G01X-384317D02*
X-382733Y-160917D01*
G01X-379050Y-159250D02*
X-376383D01*
X-376633Y-158667D01*
X-377050Y-158333D01*
X-377633Y-158167D01*
X-378217Y-158250D01*
X-378717Y-158500D01*
X-379050Y-159083D01*
X-379217Y-159583D01*
Y-160083D01*
X-379050Y-160583D01*
X-378633Y-161083D01*
X-378133Y-161417D01*
X-377550Y-161500D01*
X-376967Y-161333D01*
X-376383Y-160833D01*
G01X-373367Y-161500D02*
Y-158167D01*
G01Y-158833D02*
X-372950Y-158500D01*
X-372533Y-158250D01*
X-371950Y-158167D01*
X-371533Y-158250D01*
X-371033Y-158500D01*
G01X-443167Y-126917D02*
X-443667Y-126667D01*
X-444250Y-126500D01*
X-444917D01*
X-445667Y-126750D01*
X-446250Y-127167D01*
X-446667Y-127667D01*
X-447000Y-128500D01*
X-447083Y-129250D01*
X-446917Y-130000D01*
X-446667Y-130500D01*
X-446167Y-131000D01*
X-445583Y-131333D01*
X-445000Y-131500D01*
X-444417D01*
X-443833Y-131333D01*
X-443333Y-131083D01*
X-442917Y-130750D01*
G01X-439400Y-131500D02*
X-439900Y-131417D01*
X-440400Y-131083D01*
X-440733Y-130500D01*
X-440900Y-129833D01*
X-440733Y-129167D01*
X-440400Y-128583D01*
X-439900Y-128250D01*
X-439400Y-128167D01*
X-438900Y-128250D01*
X-438400Y-128583D01*
X-438067Y-129167D01*
X-437983Y-129833D01*
X-438067Y-130500D01*
X-438400Y-131083D01*
X-438900Y-131417D01*
X-439400Y-131500D01*
G01X-435300Y-133167D02*
Y-128167D01*
G01Y-128917D02*
X-434883Y-128500D01*
X-434467Y-128250D01*
X-433800Y-128167D01*
X-433217Y-128250D01*
X-432633Y-128667D01*
X-432383Y-129250D01*
X-432300Y-129833D01*
X-432383Y-130417D01*
X-432633Y-131000D01*
X-433133Y-131333D01*
X-433800Y-131500D01*
X-434383Y-131417D01*
X-434967Y-131167D01*
X-435300Y-130833D01*
G01X-429700Y-133167D02*
Y-128167D01*
G01Y-128917D02*
X-429283Y-128500D01*
X-428867Y-128250D01*
X-428200Y-128167D01*
X-427617Y-128250D01*
X-427033Y-128667D01*
X-426783Y-129250D01*
X-426700Y-129833D01*
X-426783Y-130417D01*
X-427033Y-131000D01*
X-427533Y-131333D01*
X-428200Y-131500D01*
X-428783Y-131417D01*
X-429367Y-131167D01*
X-429700Y-130833D01*
G01X-423850Y-129250D02*
X-421183D01*
X-421433Y-128667D01*
X-421850Y-128333D01*
X-422433Y-128167D01*
X-423017Y-128250D01*
X-423517Y-128500D01*
X-423850Y-129083D01*
X-424017Y-129583D01*
Y-130083D01*
X-423850Y-130583D01*
X-423433Y-131083D01*
X-422933Y-131417D01*
X-422350Y-131500D01*
X-421767Y-131333D01*
X-421183Y-130833D01*
G01X-418167Y-131500D02*
Y-128167D01*
G01Y-128833D02*
X-417750Y-128500D01*
X-417333Y-128250D01*
X-416750Y-128167D01*
X-416333Y-128250D01*
X-415833Y-128500D01*
G01X-407467Y-131500D02*
Y-126500D01*
X-405467D01*
X-404800Y-126750D01*
X-404300Y-127333D01*
X-404133Y-128000D01*
X-404300Y-128667D01*
X-404717Y-129167D01*
X-405467Y-129417D01*
X-407467D01*
G01X-400200Y-131500D02*
Y-126500D01*
G01X-393100Y-131500D02*
Y-128167D01*
G01Y-128750D02*
X-393433Y-128417D01*
X-393933Y-128250D01*
X-394517Y-128167D01*
X-395100Y-128333D01*
X-395600Y-128667D01*
X-395933Y-129167D01*
X-396100Y-129833D01*
X-395933Y-130500D01*
X-395600Y-131000D01*
X-395100Y-131333D01*
X-394517Y-131500D01*
X-393933Y-131417D01*
X-393433Y-131167D01*
X-393100Y-130833D01*
G01X-389000Y-126500D02*
Y-131500D01*
G01X-390167Y-128167D02*
X-387833D01*
G01X-383400D02*
Y-131500D01*
G01Y-126833D02*
X-383567Y-126750D01*
Y-126583D01*
X-383400Y-126500D01*
X-383233Y-126583D01*
Y-126750D01*
X-383400Y-126833D01*
G01X-379217Y-131500D02*
Y-128167D01*
G01Y-129000D02*
X-378883Y-128583D01*
X-378383Y-128250D01*
X-377717Y-128167D01*
X-377133Y-128250D01*
X-376633Y-128583D01*
X-376383Y-129167D01*
Y-131500D01*
G01X-373367Y-132750D02*
X-372783Y-133083D01*
X-372117Y-133167D01*
X-371533Y-133083D01*
X-371033Y-132667D01*
X-370700Y-132083D01*
Y-128167D01*
G01Y-128833D02*
X-371033Y-128500D01*
X-371533Y-128250D01*
X-372117Y-128167D01*
X-372783Y-128333D01*
X-373200Y-128667D01*
X-373533Y-129250D01*
X-373700Y-129833D01*
X-373617Y-130333D01*
X-373283Y-130917D01*
X-372783Y-131333D01*
X-372117Y-131500D01*
X-371617Y-131417D01*
X-371033Y-131083D01*
X-370700Y-130750D01*
G01X-446833Y186000D02*
Y191000D01*
X-445167D01*
X-444500Y190750D01*
X-444000Y190417D01*
X-443583Y189917D01*
X-443250Y189333D01*
X-443167Y188500D01*
X-443250Y187667D01*
X-443583Y187083D01*
X-444000Y186583D01*
X-444500Y186250D01*
X-445167Y186000D01*
X-446833D01*
G01X-440567D02*
Y189333D01*
G01Y188667D02*
X-440150Y189000D01*
X-439733Y189250D01*
X-439150Y189333D01*
X-438733Y189250D01*
X-438233Y189000D01*
G01X-433800Y189333D02*
Y186000D01*
G01Y190667D02*
X-433967Y190750D01*
Y190917D01*
X-433800Y191000D01*
X-433633Y190917D01*
Y190750D01*
X-433800Y190667D01*
G01X-428200Y186000D02*
Y191000D01*
G01X-422600Y186000D02*
Y191000D01*
G01X-448583Y420667D02*
X-448083Y421167D01*
X-447500Y421417D01*
X-446833Y421500D01*
X-446000Y421333D01*
X-445417Y420917D01*
X-445250Y420417D01*
X-445333Y419917D01*
X-445667Y419500D01*
X-447333Y418667D01*
X-448083Y418083D01*
X-448583Y417250D01*
X-448750Y416500D01*
X-445250D01*
G01X-441400Y416333D02*
X-441567Y416417D01*
Y416583D01*
X-441400Y416667D01*
X-441233Y416583D01*
Y416417D01*
X-441400Y416333D01*
G01X-435800Y421500D02*
Y416500D01*
G01X-437717Y421500D02*
X-433883D01*
G01X-430200Y416500D02*
X-430700Y416583D01*
X-431200Y416917D01*
X-431533Y417500D01*
X-431700Y418167D01*
X-431533Y418833D01*
X-431200Y419417D01*
X-430700Y419750D01*
X-430200Y419833D01*
X-429700Y419750D01*
X-429200Y419417D01*
X-428867Y418833D01*
X-428783Y418167D01*
X-428867Y417500D01*
X-429200Y416917D01*
X-429700Y416583D01*
X-430200Y416500D01*
G01X-424600D02*
Y421500D01*
G01X-420250Y418750D02*
X-417583D01*
X-417833Y419333D01*
X-418250Y419667D01*
X-418833Y419833D01*
X-419417Y419750D01*
X-419917Y419500D01*
X-420250Y418917D01*
X-420417Y418417D01*
Y417917D01*
X-420250Y417417D01*
X-419833Y416917D01*
X-419333Y416583D01*
X-418750Y416500D01*
X-418167Y416667D01*
X-417583Y417167D01*
G01X-414567Y416500D02*
Y419833D01*
G01Y419167D02*
X-414150Y419500D01*
X-413733Y419750D01*
X-413150Y419833D01*
X-412733Y419750D01*
X-412233Y419500D01*
G01X-406300Y416500D02*
Y419833D01*
G01Y419250D02*
X-406633Y419583D01*
X-407133Y419750D01*
X-407717Y419833D01*
X-408300Y419667D01*
X-408800Y419333D01*
X-409133Y418833D01*
X-409300Y418167D01*
X-409133Y417500D01*
X-408800Y417000D01*
X-408300Y416667D01*
X-407717Y416500D01*
X-407133Y416583D01*
X-406633Y416833D01*
X-406300Y417167D01*
G01X-403617Y416500D02*
Y419833D01*
G01Y419000D02*
X-403283Y419417D01*
X-402783Y419750D01*
X-402117Y419833D01*
X-401533Y419750D01*
X-401033Y419417D01*
X-400783Y418833D01*
Y416500D01*
G01X-395267Y419417D02*
X-395850Y419750D01*
X-396350Y419833D01*
X-397017Y419667D01*
X-397517Y419333D01*
X-397850Y418750D01*
X-397933Y418167D01*
X-397850Y417583D01*
X-397517Y417083D01*
X-397017Y416667D01*
X-396350Y416500D01*
X-395767Y416667D01*
X-395267Y417000D01*
G01X-392250Y418750D02*
X-389583D01*
X-389833Y419333D01*
X-390250Y419667D01*
X-390833Y419833D01*
X-391417Y419750D01*
X-391917Y419500D01*
X-392250Y418917D01*
X-392417Y418417D01*
Y417917D01*
X-392250Y417417D01*
X-391833Y416917D01*
X-391333Y416583D01*
X-390750Y416500D01*
X-390167Y416667D01*
X-389583Y417167D01*
G01X-379800Y421500D02*
Y416500D01*
G01X-380967Y419833D02*
X-378633D01*
G01X-372700Y416500D02*
Y419833D01*
G01Y419250D02*
X-373033Y419583D01*
X-373533Y419750D01*
X-374117Y419833D01*
X-374700Y419667D01*
X-375200Y419333D01*
X-375533Y418833D01*
X-375700Y418167D01*
X-375533Y417500D01*
X-375200Y417000D01*
X-374700Y416667D01*
X-374117Y416500D01*
X-373533Y416583D01*
X-373033Y416833D01*
X-372700Y417167D01*
G01X-370100Y416500D02*
Y421500D01*
G01Y419000D02*
X-369683Y419500D01*
X-369183Y419750D01*
X-368683Y419833D01*
X-367933Y419667D01*
X-367433Y419333D01*
X-367100Y418750D01*
Y418083D01*
X-367267Y417417D01*
X-367600Y416917D01*
X-368183Y416583D01*
X-368683Y416500D01*
X-369183Y416583D01*
X-369683Y416833D01*
X-370100Y417250D01*
G01X-363000Y416500D02*
Y421500D01*
G01X-358650Y418750D02*
X-355983D01*
X-356233Y419333D01*
X-356650Y419667D01*
X-357233Y419833D01*
X-357817Y419750D01*
X-358317Y419500D01*
X-358650Y418917D01*
X-358817Y418417D01*
Y417917D01*
X-358650Y417417D01*
X-358233Y416917D01*
X-357733Y416583D01*
X-357150Y416500D01*
X-356567Y416667D01*
X-355983Y417167D01*
G01X-351800Y416333D02*
X-351967Y416417D01*
Y416583D01*
X-351800Y416667D01*
X-351633Y416583D01*
Y416417D01*
X-351800Y416333D01*
G01Y418583D02*
X-351967Y418667D01*
Y418833D01*
X-351800Y418917D01*
X-351633Y418833D01*
Y418667D01*
X-351800Y418583D01*
G01X-451500Y559500D02*
Y564500D01*
X-452500Y563500D01*
G01Y559500D02*
X-450500D01*
G01X-445900Y559333D02*
X-446067Y559417D01*
Y559583D01*
X-445900Y559667D01*
X-445733Y559583D01*
Y559417D01*
X-445900Y559333D01*
G01X-442050Y560167D02*
X-441383Y559750D01*
X-440633Y559500D01*
X-439967D01*
X-439300Y559750D01*
X-438800Y560167D01*
X-438550Y560750D01*
X-438717Y561333D01*
X-439133Y561833D01*
X-439883Y562167D01*
X-440883Y562333D01*
X-441467Y562667D01*
X-441717Y563250D01*
X-441550Y563833D01*
X-441133Y564250D01*
X-440550Y564500D01*
X-439967D01*
X-439383Y564333D01*
X-438883Y563917D01*
G01X-436200Y557833D02*
Y562833D01*
G01Y562083D02*
X-435783Y562500D01*
X-435367Y562750D01*
X-434700Y562833D01*
X-434117Y562750D01*
X-433533Y562333D01*
X-433283Y561750D01*
X-433200Y561167D01*
X-433283Y560583D01*
X-433533Y560000D01*
X-434033Y559667D01*
X-434700Y559500D01*
X-435283Y559583D01*
X-435867Y559833D01*
X-436200Y560167D01*
G01X-430350Y561750D02*
X-427683D01*
X-427933Y562333D01*
X-428350Y562667D01*
X-428933Y562833D01*
X-429517Y562750D01*
X-430017Y562500D01*
X-430350Y561917D01*
X-430517Y561417D01*
Y560917D01*
X-430350Y560417D01*
X-429933Y559917D01*
X-429433Y559583D01*
X-428850Y559500D01*
X-428267Y559667D01*
X-427683Y560167D01*
G01X-422167Y562417D02*
X-422750Y562750D01*
X-423250Y562833D01*
X-423917Y562667D01*
X-424417Y562333D01*
X-424750Y561750D01*
X-424833Y561167D01*
X-424750Y560583D01*
X-424417Y560083D01*
X-423917Y559667D01*
X-423250Y559500D01*
X-422667Y559667D01*
X-422167Y560000D01*
G01X-417900Y562833D02*
Y559500D01*
G01Y564167D02*
X-418067Y564250D01*
Y564417D01*
X-417900Y564500D01*
X-417733Y564417D01*
Y564250D01*
X-417900Y564167D01*
G01X-412800Y559500D02*
Y563750D01*
X-412633Y564167D01*
X-412300Y564417D01*
X-411800Y564500D01*
X-411300Y564333D01*
X-411050Y563917D01*
G01X-412050Y562500D02*
X-413717D01*
G01X-406700Y562833D02*
Y559500D01*
G01Y564167D02*
X-406867Y564250D01*
Y564417D01*
X-406700Y564500D01*
X-406533Y564417D01*
Y564250D01*
X-406700Y564167D01*
G01X-399767Y562417D02*
X-400350Y562750D01*
X-400850Y562833D01*
X-401517Y562667D01*
X-402017Y562333D01*
X-402350Y561750D01*
X-402433Y561167D01*
X-402350Y560583D01*
X-402017Y560083D01*
X-401517Y559667D01*
X-400850Y559500D01*
X-400267Y559667D01*
X-399767Y560000D01*
G01X-394000Y559500D02*
Y562833D01*
G01Y562250D02*
X-394333Y562583D01*
X-394833Y562750D01*
X-395417Y562833D01*
X-396000Y562667D01*
X-396500Y562333D01*
X-396833Y561833D01*
X-397000Y561167D01*
X-396833Y560500D01*
X-396500Y560000D01*
X-396000Y559667D01*
X-395417Y559500D01*
X-394833Y559583D01*
X-394333Y559833D01*
X-394000Y560167D01*
G01X-389900Y564500D02*
Y559500D01*
G01X-391067Y562833D02*
X-388733D01*
G01X-384300D02*
Y559500D01*
G01Y564167D02*
X-384467Y564250D01*
Y564417D01*
X-384300Y564500D01*
X-384133Y564417D01*
Y564250D01*
X-384300Y564167D01*
G01X-378700Y559500D02*
X-379200Y559583D01*
X-379700Y559917D01*
X-380033Y560500D01*
X-380200Y561167D01*
X-380033Y561833D01*
X-379700Y562417D01*
X-379200Y562750D01*
X-378700Y562833D01*
X-378200Y562750D01*
X-377700Y562417D01*
X-377367Y561833D01*
X-377283Y561167D01*
X-377367Y560500D01*
X-377700Y559917D01*
X-378200Y559583D01*
X-378700Y559500D01*
G01X-374517D02*
Y562833D01*
G01Y562000D02*
X-374183Y562417D01*
X-373683Y562750D01*
X-373017Y562833D01*
X-372433Y562750D01*
X-371933Y562417D01*
X-371683Y561833D01*
Y559500D01*
G01X-360400Y564500D02*
Y559500D01*
G01Y560250D02*
X-360733Y559833D01*
X-361233Y559583D01*
X-361817Y559500D01*
X-362483Y559667D01*
X-362983Y560083D01*
X-363317Y560583D01*
X-363400Y561167D01*
X-363317Y561750D01*
X-362983Y562250D01*
X-362483Y562667D01*
X-361817Y562833D01*
X-361233Y562750D01*
X-360817Y562583D01*
X-360400Y562250D01*
G01X-356300Y559500D02*
X-356800Y559583D01*
X-357300Y559917D01*
X-357633Y560500D01*
X-357800Y561167D01*
X-357633Y561833D01*
X-357300Y562417D01*
X-356800Y562750D01*
X-356300Y562833D01*
X-355800Y562750D01*
X-355300Y562417D01*
X-354967Y561833D01*
X-354883Y561167D01*
X-354967Y560500D01*
X-355300Y559917D01*
X-355800Y559583D01*
X-356300Y559500D01*
G01X-349367Y562417D02*
X-349950Y562750D01*
X-350450Y562833D01*
X-351117Y562667D01*
X-351617Y562333D01*
X-351950Y561750D01*
X-352033Y561167D01*
X-351950Y560583D01*
X-351617Y560083D01*
X-351117Y559667D01*
X-350450Y559500D01*
X-349867Y559667D01*
X-349367Y560000D01*
G01X-346517Y562833D02*
Y560500D01*
X-346183Y559917D01*
X-345683Y559583D01*
X-345100Y559500D01*
X-344517Y559583D01*
X-344017Y559917D01*
X-343683Y560500D01*
G01Y559500D02*
Y562833D01*
G01X-342000Y559500D02*
Y562833D01*
G01Y561917D02*
X-341750Y562333D01*
X-341333Y562667D01*
X-340750Y562833D01*
X-340167Y562667D01*
X-339750Y562333D01*
X-339500Y561917D01*
Y559500D01*
G01Y561917D02*
X-339250Y562333D01*
X-338833Y562667D01*
X-338250Y562833D01*
X-337667Y562667D01*
X-337250Y562333D01*
X-337000Y561833D01*
Y559500D01*
G01X-335150Y561750D02*
X-332483D01*
X-332733Y562333D01*
X-333150Y562667D01*
X-333733Y562833D01*
X-334317Y562750D01*
X-334817Y562500D01*
X-335150Y561917D01*
X-335317Y561417D01*
Y560917D01*
X-335150Y560417D01*
X-334733Y559917D01*
X-334233Y559583D01*
X-333650Y559500D01*
X-333067Y559667D01*
X-332483Y560167D01*
G01X-329717Y559500D02*
Y562833D01*
G01Y562000D02*
X-329383Y562417D01*
X-328883Y562750D01*
X-328217Y562833D01*
X-327633Y562750D01*
X-327133Y562417D01*
X-326883Y561833D01*
Y559500D01*
G01X-322700Y564500D02*
Y559500D01*
G01X-323867Y562833D02*
X-321533D01*
G01X-317100Y559333D02*
X-317267Y559417D01*
Y559583D01*
X-317100Y559667D01*
X-316933Y559583D01*
Y559417D01*
X-317100Y559333D01*
G01Y561583D02*
X-317267Y561667D01*
Y561833D01*
X-317100Y561917D01*
X-316933Y561833D01*
Y561667D01*
X-317100Y561583D01*
G01X-433540Y353740D02*
X-431540D01*
G01X-432540D02*
Y348740D01*
G01X-433540D02*
X-431540D01*
G01X-428357D02*
Y352073D01*
G01Y351240D02*
X-428023Y351657D01*
X-427523Y351990D01*
X-426857Y352073D01*
X-426273Y351990D01*
X-425773Y351657D01*
X-425523Y351073D01*
Y348740D01*
G01X-422757D02*
Y352073D01*
G01Y351240D02*
X-422423Y351657D01*
X-421923Y351990D01*
X-421257Y352073D01*
X-420673Y351990D01*
X-420173Y351657D01*
X-419923Y351073D01*
Y348740D01*
G01X-416990Y350990D02*
X-414323D01*
X-414573Y351573D01*
X-414990Y351907D01*
X-415573Y352073D01*
X-416157Y351990D01*
X-416657Y351740D01*
X-416990Y351157D01*
X-417157Y350657D01*
Y350157D01*
X-416990Y349657D01*
X-416573Y349157D01*
X-416073Y348823D01*
X-415490Y348740D01*
X-414907Y348907D01*
X-414323Y349407D01*
G01X-411307Y348740D02*
Y352073D01*
G01Y351407D02*
X-410890Y351740D01*
X-410473Y351990D01*
X-409890Y352073D01*
X-409473Y351990D01*
X-408973Y351740D01*
G01X-398940Y348740D02*
Y353740D01*
G01X-391840Y348740D02*
Y352073D01*
G01Y351490D02*
X-392173Y351823D01*
X-392673Y351990D01*
X-393257Y352073D01*
X-393840Y351907D01*
X-394340Y351573D01*
X-394673Y351073D01*
X-394840Y350407D01*
X-394673Y349740D01*
X-394340Y349240D01*
X-393840Y348907D01*
X-393257Y348740D01*
X-392673Y348823D01*
X-392173Y349073D01*
X-391840Y349407D01*
G01X-389490Y347240D02*
X-388990Y347073D01*
X-388323Y347240D01*
X-387907Y347573D01*
X-387573Y347990D01*
X-387073Y349323D01*
X-385990Y352073D01*
G01X-388657D02*
X-387073Y349323D01*
G01X-383390Y350990D02*
X-380723D01*
X-380973Y351573D01*
X-381390Y351907D01*
X-381973Y352073D01*
X-382557Y351990D01*
X-383057Y351740D01*
X-383390Y351157D01*
X-383557Y350657D01*
Y350157D01*
X-383390Y349657D01*
X-382973Y349157D01*
X-382473Y348823D01*
X-381890Y348740D01*
X-381307Y348907D01*
X-380723Y349407D01*
G01X-377707Y348740D02*
Y352073D01*
G01Y351407D02*
X-377290Y351740D01*
X-376873Y351990D01*
X-376290Y352073D01*
X-375873Y351990D01*
X-375373Y351740D01*
G01X-424500Y390333D02*
Y395333D01*
G01Y394583D02*
X-424083Y395000D01*
X-423667Y395250D01*
X-423000Y395333D01*
X-422417Y395250D01*
X-421833Y394833D01*
X-421583Y394250D01*
X-421500Y393667D01*
X-421583Y393083D01*
X-421833Y392500D01*
X-422333Y392167D01*
X-423000Y392000D01*
X-423583Y392083D01*
X-424167Y392333D01*
X-424500Y392667D01*
G01X-418567Y392000D02*
Y395333D01*
G01Y394667D02*
X-418150Y395000D01*
X-417733Y395250D01*
X-417150Y395333D01*
X-416733Y395250D01*
X-416233Y395000D01*
G01X-411800Y392000D02*
X-412300Y392083D01*
X-412800Y392417D01*
X-413133Y393000D01*
X-413300Y393667D01*
X-413133Y394333D01*
X-412800Y394917D01*
X-412300Y395250D01*
X-411800Y395333D01*
X-411300Y395250D01*
X-410800Y394917D01*
X-410467Y394333D01*
X-410383Y393667D01*
X-410467Y393000D01*
X-410800Y392417D01*
X-411300Y392083D01*
X-411800Y392000D01*
G01X-404867Y394917D02*
X-405450Y395250D01*
X-405950Y395333D01*
X-406617Y395167D01*
X-407117Y394833D01*
X-407450Y394250D01*
X-407533Y393667D01*
X-407450Y393083D01*
X-407117Y392583D01*
X-406617Y392167D01*
X-405950Y392000D01*
X-405367Y392167D01*
X-404867Y392500D01*
G01X-401850Y394250D02*
X-399183D01*
X-399433Y394833D01*
X-399850Y395167D01*
X-400433Y395333D01*
X-401017Y395250D01*
X-401517Y395000D01*
X-401850Y394417D01*
X-402017Y393917D01*
Y393417D01*
X-401850Y392917D01*
X-401433Y392417D01*
X-400933Y392083D01*
X-400350Y392000D01*
X-399767Y392167D01*
X-399183Y392667D01*
G01X-396250Y392583D02*
X-395833Y392250D01*
X-395250Y392000D01*
X-394750D01*
X-394250Y392167D01*
X-393917Y392417D01*
X-393750Y392750D01*
X-393833Y393250D01*
X-394167Y393500D01*
X-395667Y394000D01*
X-396000Y394583D01*
X-395833Y395000D01*
X-395500Y395250D01*
X-395000Y395333D01*
X-394500Y395250D01*
X-394000Y395000D01*
G01X-390650Y392583D02*
X-390233Y392250D01*
X-389650Y392000D01*
X-389150D01*
X-388650Y392167D01*
X-388317Y392417D01*
X-388150Y392750D01*
X-388233Y393250D01*
X-388567Y393500D01*
X-390067Y394000D01*
X-390400Y394583D01*
X-390233Y395000D01*
X-389900Y395250D01*
X-389400Y395333D01*
X-388900Y395250D01*
X-388400Y395000D01*
G01X-391500Y452433D02*
X-391667Y452517D01*
Y452683D01*
X-391500Y452767D01*
X-391333Y452683D01*
Y452517D01*
X-391500Y452433D01*
G01Y461433D02*
X-391667Y461517D01*
Y461683D01*
X-391500Y461767D01*
X-391333Y461683D01*
Y461517D01*
X-391500Y461433D01*
G01Y470433D02*
X-391667Y470517D01*
Y470683D01*
X-391500Y470767D01*
X-391333Y470683D01*
Y470517D01*
X-391500Y470433D01*
G01Y479433D02*
X-391667Y479517D01*
Y479683D01*
X-391500Y479767D01*
X-391333Y479683D01*
Y479517D01*
X-391500Y479433D01*
G01Y488433D02*
X-391667Y488517D01*
Y488683D01*
X-391500Y488767D01*
X-391333Y488683D01*
Y488517D01*
X-391500Y488433D01*
G01Y497433D02*
X-391667Y497517D01*
Y497683D01*
X-391500Y497767D01*
X-391333Y497683D01*
Y497517D01*
X-391500Y497433D01*
G01Y506433D02*
X-391667Y506517D01*
Y506683D01*
X-391500Y506767D01*
X-391333Y506683D01*
Y506517D01*
X-391500Y506433D01*
G01X-401500Y529500D02*
X-399500D01*
G01X-400500D02*
Y524500D01*
G01X-401500D02*
X-399500D01*
G01X-395400D02*
Y528750D01*
X-395233Y529167D01*
X-394900Y529417D01*
X-394400Y529500D01*
X-393900Y529333D01*
X-393650Y528917D01*
G01X-394650Y527500D02*
X-396317D01*
G01X-383700Y529500D02*
Y524500D01*
G01X-384867Y527833D02*
X-382533D01*
G01X-379517Y524500D02*
Y529500D01*
G01Y527083D02*
X-379100Y527500D01*
X-378683Y527750D01*
X-378017Y527833D01*
X-377517Y527750D01*
X-376933Y527417D01*
X-376683Y526917D01*
Y524500D01*
G01X-373750Y526750D02*
X-371083D01*
X-371333Y527333D01*
X-371750Y527667D01*
X-372333Y527833D01*
X-372917Y527750D01*
X-373417Y527500D01*
X-373750Y526917D01*
X-373917Y526417D01*
Y525917D01*
X-373750Y525417D01*
X-373333Y524917D01*
X-372833Y524583D01*
X-372250Y524500D01*
X-371667Y524667D01*
X-371083Y525167D01*
G01X-359967Y527417D02*
X-360550Y527750D01*
X-361050Y527833D01*
X-361717Y527667D01*
X-362217Y527333D01*
X-362550Y526750D01*
X-362633Y526167D01*
X-362550Y525583D01*
X-362217Y525083D01*
X-361717Y524667D01*
X-361050Y524500D01*
X-360467Y524667D01*
X-359967Y525000D01*
G01X-356867Y524500D02*
Y527833D01*
G01Y527167D02*
X-356450Y527500D01*
X-356033Y527750D01*
X-355450Y527833D01*
X-355033Y527750D01*
X-354533Y527500D01*
G01X-350100Y527833D02*
Y524500D01*
G01Y529167D02*
X-350267Y529250D01*
Y529417D01*
X-350100Y529500D01*
X-349933Y529417D01*
Y529250D01*
X-350100Y529167D01*
G01X-344500Y529500D02*
Y524500D01*
G01X-345667Y527833D02*
X-343333D01*
G01X-340150Y526750D02*
X-337483D01*
X-337733Y527333D01*
X-338150Y527667D01*
X-338733Y527833D01*
X-339317Y527750D01*
X-339817Y527500D01*
X-340150Y526917D01*
X-340317Y526417D01*
Y525917D01*
X-340150Y525417D01*
X-339733Y524917D01*
X-339233Y524583D01*
X-338650Y524500D01*
X-338067Y524667D01*
X-337483Y525167D01*
G01X-334467Y524500D02*
Y527833D01*
G01Y527167D02*
X-334050Y527500D01*
X-333633Y527750D01*
X-333050Y527833D01*
X-332633Y527750D01*
X-332133Y527500D01*
G01X-327700Y527833D02*
Y524500D01*
G01Y529167D02*
X-327867Y529250D01*
Y529417D01*
X-327700Y529500D01*
X-327533Y529417D01*
Y529250D01*
X-327700Y529167D01*
G01X-320600Y524500D02*
Y527833D01*
G01Y527250D02*
X-320933Y527583D01*
X-321433Y527750D01*
X-322017Y527833D01*
X-322600Y527667D01*
X-323100Y527333D01*
X-323433Y526833D01*
X-323600Y526167D01*
X-323433Y525500D01*
X-323100Y525000D01*
X-322600Y524667D01*
X-322017Y524500D01*
X-321433Y524583D01*
X-320933Y524833D01*
X-320600Y525167D01*
G01X-310900Y527833D02*
Y524500D01*
G01Y529167D02*
X-311067Y529250D01*
Y529417D01*
X-310900Y529500D01*
X-310733Y529417D01*
Y529250D01*
X-310900Y529167D01*
G01X-306550Y525083D02*
X-306133Y524750D01*
X-305550Y524500D01*
X-305050D01*
X-304550Y524667D01*
X-304217Y524917D01*
X-304050Y525250D01*
X-304133Y525750D01*
X-304467Y526000D01*
X-305967Y526500D01*
X-306300Y527083D01*
X-306133Y527500D01*
X-305800Y527750D01*
X-305300Y527833D01*
X-304800Y527750D01*
X-304300Y527500D01*
G01X-295517Y524500D02*
Y527833D01*
G01Y527000D02*
X-295183Y527417D01*
X-294683Y527750D01*
X-294017Y527833D01*
X-293433Y527750D01*
X-292933Y527417D01*
X-292683Y526833D01*
Y524500D01*
G01X-288500D02*
X-289000Y524583D01*
X-289500Y524917D01*
X-289833Y525500D01*
X-290000Y526167D01*
X-289833Y526833D01*
X-289500Y527417D01*
X-289000Y527750D01*
X-288500Y527833D01*
X-288000Y527750D01*
X-287500Y527417D01*
X-287167Y526833D01*
X-287083Y526167D01*
X-287167Y525500D01*
X-287500Y524917D01*
X-288000Y524583D01*
X-288500Y524500D01*
G01X-282900Y529500D02*
Y524500D01*
G01X-284067Y527833D02*
X-281733D01*
G01X-272950Y525083D02*
X-272533Y524750D01*
X-271950Y524500D01*
X-271450D01*
X-270950Y524667D01*
X-270617Y524917D01*
X-270450Y525250D01*
X-270533Y525750D01*
X-270867Y526000D01*
X-272367Y526500D01*
X-272700Y527083D01*
X-272533Y527500D01*
X-272200Y527750D01*
X-271700Y527833D01*
X-271200Y527750D01*
X-270700Y527500D01*
G01X-267600Y522833D02*
Y527833D01*
G01Y527083D02*
X-267183Y527500D01*
X-266767Y527750D01*
X-266100Y527833D01*
X-265517Y527750D01*
X-264933Y527333D01*
X-264683Y526750D01*
X-264600Y526167D01*
X-264683Y525583D01*
X-264933Y525000D01*
X-265433Y524667D01*
X-266100Y524500D01*
X-266683Y524583D01*
X-267267Y524833D01*
X-267600Y525167D01*
G01X-261750Y526750D02*
X-259083D01*
X-259333Y527333D01*
X-259750Y527667D01*
X-260333Y527833D01*
X-260917Y527750D01*
X-261417Y527500D01*
X-261750Y526917D01*
X-261917Y526417D01*
Y525917D01*
X-261750Y525417D01*
X-261333Y524917D01*
X-260833Y524583D01*
X-260250Y524500D01*
X-259667Y524667D01*
X-259083Y525167D01*
G01X-253567Y527417D02*
X-254150Y527750D01*
X-254650Y527833D01*
X-255317Y527667D01*
X-255817Y527333D01*
X-256150Y526750D01*
X-256233Y526167D01*
X-256150Y525583D01*
X-255817Y525083D01*
X-255317Y524667D01*
X-254650Y524500D01*
X-254067Y524667D01*
X-253567Y525000D01*
G01X-249300Y527833D02*
Y524500D01*
G01Y529167D02*
X-249467Y529250D01*
Y529417D01*
X-249300Y529500D01*
X-249133Y529417D01*
Y529250D01*
X-249300Y529167D01*
G01X-244200Y524500D02*
Y528750D01*
X-244033Y529167D01*
X-243700Y529417D01*
X-243200Y529500D01*
X-242700Y529333D01*
X-242450Y528917D01*
G01X-243450Y527500D02*
X-245117D01*
G01X-238100Y527833D02*
Y524500D01*
G01Y529167D02*
X-238267Y529250D01*
Y529417D01*
X-238100Y529500D01*
X-237933Y529417D01*
Y529250D01*
X-238100Y529167D01*
G01X-233750Y526750D02*
X-231083D01*
X-231333Y527333D01*
X-231750Y527667D01*
X-232333Y527833D01*
X-232917Y527750D01*
X-233417Y527500D01*
X-233750Y526917D01*
X-233917Y526417D01*
Y525917D01*
X-233750Y525417D01*
X-233333Y524917D01*
X-232833Y524583D01*
X-232250Y524500D01*
X-231667Y524667D01*
X-231083Y525167D01*
G01X-225400Y529500D02*
Y524500D01*
G01Y525250D02*
X-225733Y524833D01*
X-226233Y524583D01*
X-226817Y524500D01*
X-227483Y524667D01*
X-227983Y525083D01*
X-228317Y525583D01*
X-228400Y526167D01*
X-228317Y526750D01*
X-227983Y527250D01*
X-227483Y527667D01*
X-226817Y527833D01*
X-226233Y527750D01*
X-225817Y527583D01*
X-225400Y527250D01*
G01X-215700Y527833D02*
Y524500D01*
G01Y529167D02*
X-215867Y529250D01*
Y529417D01*
X-215700Y529500D01*
X-215533Y529417D01*
Y529250D01*
X-215700Y529167D01*
G01X-211517Y524500D02*
Y527833D01*
G01Y527000D02*
X-211183Y527417D01*
X-210683Y527750D01*
X-210017Y527833D01*
X-209433Y527750D01*
X-208933Y527417D01*
X-208683Y526833D01*
Y524500D01*
G01X-198900Y529500D02*
Y524500D01*
G01X-200067Y527833D02*
X-197733D01*
G01X-194717Y524500D02*
Y529500D01*
G01Y527083D02*
X-194300Y527500D01*
X-193883Y527750D01*
X-193217Y527833D01*
X-192717Y527750D01*
X-192133Y527417D01*
X-191883Y526917D01*
Y524500D01*
G01X-188950Y526750D02*
X-186283D01*
X-186533Y527333D01*
X-186950Y527667D01*
X-187533Y527833D01*
X-188117Y527750D01*
X-188617Y527500D01*
X-188950Y526917D01*
X-189117Y526417D01*
Y525917D01*
X-188950Y525417D01*
X-188533Y524917D01*
X-188033Y524583D01*
X-187450Y524500D01*
X-186867Y524667D01*
X-186283Y525167D01*
G01X-176500Y529500D02*
Y524500D01*
G01X-177667Y527833D02*
X-175333D01*
G01X-169400Y524500D02*
Y527833D01*
G01Y527250D02*
X-169733Y527583D01*
X-170233Y527750D01*
X-170817Y527833D01*
X-171400Y527667D01*
X-171900Y527333D01*
X-172233Y526833D01*
X-172400Y526167D01*
X-172233Y525500D01*
X-171900Y525000D01*
X-171400Y524667D01*
X-170817Y524500D01*
X-170233Y524583D01*
X-169733Y524833D01*
X-169400Y525167D01*
G01X-166800Y524500D02*
Y529500D01*
G01Y527000D02*
X-166383Y527500D01*
X-165883Y527750D01*
X-165383Y527833D01*
X-164633Y527667D01*
X-164133Y527333D01*
X-163800Y526750D01*
Y526083D01*
X-163967Y525417D01*
X-164300Y524917D01*
X-164883Y524583D01*
X-165383Y524500D01*
X-165883Y524583D01*
X-166383Y524833D01*
X-166800Y525250D01*
G01X-159700Y524500D02*
Y529500D01*
G01X-155350Y526750D02*
X-152683D01*
X-152933Y527333D01*
X-153350Y527667D01*
X-153933Y527833D01*
X-154517Y527750D01*
X-155017Y527500D01*
X-155350Y526917D01*
X-155517Y526417D01*
Y525917D01*
X-155350Y525417D01*
X-154933Y524917D01*
X-154433Y524583D01*
X-153850Y524500D01*
X-153267Y524667D01*
X-152683Y525167D01*
G01X-148500Y524333D02*
X-148667Y524417D01*
Y524583D01*
X-148500Y524667D01*
X-148333Y524583D01*
Y524417D01*
X-148500Y524333D01*
G01Y526583D02*
X-148667Y526667D01*
Y526833D01*
X-148500Y526917D01*
X-148333Y526833D01*
Y526667D01*
X-148500Y526583D01*
G01X-391500Y513333D02*
X-391667Y513417D01*
Y513583D01*
X-391500Y513667D01*
X-391333Y513583D01*
Y513417D01*
X-391500Y513333D01*
G01X-400667Y533500D02*
Y538500D01*
X-398667D01*
X-398000Y538250D01*
X-397500Y537667D01*
X-397333Y537000D01*
X-397500Y536333D01*
X-397917Y535833D01*
X-398667Y535583D01*
X-400667D01*
G01X-393400Y533500D02*
Y538500D01*
G01X-389050Y535750D02*
X-386383D01*
X-386633Y536333D01*
X-387050Y536667D01*
X-387633Y536833D01*
X-388217Y536750D01*
X-388717Y536500D01*
X-389050Y535917D01*
X-389217Y535417D01*
Y534917D01*
X-389050Y534417D01*
X-388633Y533917D01*
X-388133Y533583D01*
X-387550Y533500D01*
X-386967Y533667D01*
X-386383Y534167D01*
G01X-380700Y533500D02*
Y536833D01*
G01Y536250D02*
X-381033Y536583D01*
X-381533Y536750D01*
X-382117Y536833D01*
X-382700Y536667D01*
X-383200Y536333D01*
X-383533Y535833D01*
X-383700Y535167D01*
X-383533Y534500D01*
X-383200Y534000D01*
X-382700Y533667D01*
X-382117Y533500D01*
X-381533Y533583D01*
X-381033Y533833D01*
X-380700Y534167D01*
G01X-377850Y534083D02*
X-377433Y533750D01*
X-376850Y533500D01*
X-376350D01*
X-375850Y533667D01*
X-375517Y533917D01*
X-375350Y534250D01*
X-375433Y534750D01*
X-375767Y535000D01*
X-377267Y535500D01*
X-377600Y536083D01*
X-377433Y536500D01*
X-377100Y536750D01*
X-376600Y536833D01*
X-376100Y536750D01*
X-375600Y536500D01*
G01X-372250Y535750D02*
X-369583D01*
X-369833Y536333D01*
X-370250Y536667D01*
X-370833Y536833D01*
X-371417Y536750D01*
X-371917Y536500D01*
X-372250Y535917D01*
X-372417Y535417D01*
Y534917D01*
X-372250Y534417D01*
X-371833Y533917D01*
X-371333Y533583D01*
X-370750Y533500D01*
X-370167Y533667D01*
X-369583Y534167D01*
G01X-360300Y533500D02*
Y537750D01*
X-360133Y538167D01*
X-359800Y538417D01*
X-359300Y538500D01*
X-358800Y538333D01*
X-358550Y537917D01*
G01X-359550Y536500D02*
X-361217D01*
G01X-354200Y533500D02*
X-354700Y533583D01*
X-355200Y533917D01*
X-355533Y534500D01*
X-355700Y535167D01*
X-355533Y535833D01*
X-355200Y536417D01*
X-354700Y536750D01*
X-354200Y536833D01*
X-353700Y536750D01*
X-353200Y536417D01*
X-352867Y535833D01*
X-352783Y535167D01*
X-352867Y534500D01*
X-353200Y533917D01*
X-353700Y533583D01*
X-354200Y533500D01*
G01X-348600D02*
Y538500D01*
G01X-343000Y533500D02*
Y538500D01*
G01X-337400Y533500D02*
X-337900Y533583D01*
X-338400Y533917D01*
X-338733Y534500D01*
X-338900Y535167D01*
X-338733Y535833D01*
X-338400Y536417D01*
X-337900Y536750D01*
X-337400Y536833D01*
X-336900Y536750D01*
X-336400Y536417D01*
X-336067Y535833D01*
X-335983Y535167D01*
X-336067Y534500D01*
X-336400Y533917D01*
X-336900Y533583D01*
X-337400Y533500D01*
G01X-333883Y536833D02*
X-332883Y533500D01*
X-331800Y536833D01*
X-330717Y533500D01*
X-329717Y536833D01*
G01X-320600Y538500D02*
Y533500D01*
G01X-321767Y536833D02*
X-319433D01*
G01X-316417Y533500D02*
Y538500D01*
G01Y536083D02*
X-316000Y536500D01*
X-315583Y536750D01*
X-314917Y536833D01*
X-314417Y536750D01*
X-313833Y536417D01*
X-313583Y535917D01*
Y533500D01*
G01X-310650Y535750D02*
X-307983D01*
X-308233Y536333D01*
X-308650Y536667D01*
X-309233Y536833D01*
X-309817Y536750D01*
X-310317Y536500D01*
X-310650Y535917D01*
X-310817Y535417D01*
Y534917D01*
X-310650Y534417D01*
X-310233Y533917D01*
X-309733Y533583D01*
X-309150Y533500D01*
X-308567Y533667D01*
X-307983Y534167D01*
G01X-299450Y534083D02*
X-299033Y533750D01*
X-298450Y533500D01*
X-297950D01*
X-297450Y533667D01*
X-297117Y533917D01*
X-296950Y534250D01*
X-297033Y534750D01*
X-297367Y535000D01*
X-298867Y535500D01*
X-299200Y536083D01*
X-299033Y536500D01*
X-298700Y536750D01*
X-298200Y536833D01*
X-297700Y536750D01*
X-297200Y536500D01*
G01X-294100Y531833D02*
Y536833D01*
G01Y536083D02*
X-293683Y536500D01*
X-293267Y536750D01*
X-292600Y536833D01*
X-292017Y536750D01*
X-291433Y536333D01*
X-291183Y535750D01*
X-291100Y535167D01*
X-291183Y534583D01*
X-291433Y534000D01*
X-291933Y533667D01*
X-292600Y533500D01*
X-293183Y533583D01*
X-293767Y533833D01*
X-294100Y534167D01*
G01X-288250Y535750D02*
X-285583D01*
X-285833Y536333D01*
X-286250Y536667D01*
X-286833Y536833D01*
X-287417Y536750D01*
X-287917Y536500D01*
X-288250Y535917D01*
X-288417Y535417D01*
Y534917D01*
X-288250Y534417D01*
X-287833Y533917D01*
X-287333Y533583D01*
X-286750Y533500D01*
X-286167Y533667D01*
X-285583Y534167D01*
G01X-280067Y536417D02*
X-280650Y536750D01*
X-281150Y536833D01*
X-281817Y536667D01*
X-282317Y536333D01*
X-282650Y535750D01*
X-282733Y535167D01*
X-282650Y534583D01*
X-282317Y534083D01*
X-281817Y533667D01*
X-281150Y533500D01*
X-280567Y533667D01*
X-280067Y534000D01*
G01X-275800Y536833D02*
Y533500D01*
G01Y538167D02*
X-275967Y538250D01*
Y538417D01*
X-275800Y538500D01*
X-275633Y538417D01*
Y538250D01*
X-275800Y538167D01*
G01X-270700Y533500D02*
Y537750D01*
X-270533Y538167D01*
X-270200Y538417D01*
X-269700Y538500D01*
X-269200Y538333D01*
X-268950Y537917D01*
G01X-269950Y536500D02*
X-271617D01*
G01X-264600Y536833D02*
Y533500D01*
G01Y538167D02*
X-264767Y538250D01*
Y538417D01*
X-264600Y538500D01*
X-264433Y538417D01*
Y538250D01*
X-264600Y538167D01*
G01X-257667Y536417D02*
X-258250Y536750D01*
X-258750Y536833D01*
X-259417Y536667D01*
X-259917Y536333D01*
X-260250Y535750D01*
X-260333Y535167D01*
X-260250Y534583D01*
X-259917Y534083D01*
X-259417Y533667D01*
X-258750Y533500D01*
X-258167Y533667D01*
X-257667Y534000D01*
G01X-251900Y533500D02*
Y536833D01*
G01Y536250D02*
X-252233Y536583D01*
X-252733Y536750D01*
X-253317Y536833D01*
X-253900Y536667D01*
X-254400Y536333D01*
X-254733Y535833D01*
X-254900Y535167D01*
X-254733Y534500D01*
X-254400Y534000D01*
X-253900Y533667D01*
X-253317Y533500D01*
X-252733Y533583D01*
X-252233Y533833D01*
X-251900Y534167D01*
G01X-247800Y538500D02*
Y533500D01*
G01X-248967Y536833D02*
X-246633D01*
G01X-242200D02*
Y533500D01*
G01Y538167D02*
X-242367Y538250D01*
Y538417D01*
X-242200Y538500D01*
X-242033Y538417D01*
Y538250D01*
X-242200Y538167D01*
G01X-236600Y533500D02*
X-237100Y533583D01*
X-237600Y533917D01*
X-237933Y534500D01*
X-238100Y535167D01*
X-237933Y535833D01*
X-237600Y536417D01*
X-237100Y536750D01*
X-236600Y536833D01*
X-236100Y536750D01*
X-235600Y536417D01*
X-235267Y535833D01*
X-235183Y535167D01*
X-235267Y534500D01*
X-235600Y533917D01*
X-236100Y533583D01*
X-236600Y533500D01*
G01X-232417D02*
Y536833D01*
G01Y536000D02*
X-232083Y536417D01*
X-231583Y536750D01*
X-230917Y536833D01*
X-230333Y536750D01*
X-229833Y536417D01*
X-229583Y535833D01*
Y533500D01*
G01X-218300Y538500D02*
Y533500D01*
G01Y534250D02*
X-218633Y533833D01*
X-219133Y533583D01*
X-219717Y533500D01*
X-220383Y533667D01*
X-220883Y534083D01*
X-221217Y534583D01*
X-221300Y535167D01*
X-221217Y535750D01*
X-220883Y536250D01*
X-220383Y536667D01*
X-219717Y536833D01*
X-219133Y536750D01*
X-218717Y536583D01*
X-218300Y536250D01*
G01X-214200Y533500D02*
X-214700Y533583D01*
X-215200Y533917D01*
X-215533Y534500D01*
X-215700Y535167D01*
X-215533Y535833D01*
X-215200Y536417D01*
X-214700Y536750D01*
X-214200Y536833D01*
X-213700Y536750D01*
X-213200Y536417D01*
X-212867Y535833D01*
X-212783Y535167D01*
X-212867Y534500D01*
X-213200Y533917D01*
X-213700Y533583D01*
X-214200Y533500D01*
G01X-207267Y536417D02*
X-207850Y536750D01*
X-208350Y536833D01*
X-209017Y536667D01*
X-209517Y536333D01*
X-209850Y535750D01*
X-209933Y535167D01*
X-209850Y534583D01*
X-209517Y534083D01*
X-209017Y533667D01*
X-208350Y533500D01*
X-207767Y533667D01*
X-207267Y534000D01*
G01X-204417Y536833D02*
Y534500D01*
X-204083Y533917D01*
X-203583Y533583D01*
X-203000Y533500D01*
X-202417Y533583D01*
X-201917Y533917D01*
X-201583Y534500D01*
G01Y533500D02*
Y536833D01*
G01X-199900Y533500D02*
Y536833D01*
G01Y535917D02*
X-199650Y536333D01*
X-199233Y536667D01*
X-198650Y536833D01*
X-198067Y536667D01*
X-197650Y536333D01*
X-197400Y535917D01*
Y533500D01*
G01Y535917D02*
X-197150Y536333D01*
X-196733Y536667D01*
X-196150Y536833D01*
X-195567Y536667D01*
X-195150Y536333D01*
X-194900Y535833D01*
Y533500D01*
G01X-193050Y535750D02*
X-190383D01*
X-190633Y536333D01*
X-191050Y536667D01*
X-191633Y536833D01*
X-192217Y536750D01*
X-192717Y536500D01*
X-193050Y535917D01*
X-193217Y535417D01*
Y534917D01*
X-193050Y534417D01*
X-192633Y533917D01*
X-192133Y533583D01*
X-191550Y533500D01*
X-190967Y533667D01*
X-190383Y534167D01*
G01X-187617Y533500D02*
Y536833D01*
G01Y536000D02*
X-187283Y536417D01*
X-186783Y536750D01*
X-186117Y536833D01*
X-185533Y536750D01*
X-185033Y536417D01*
X-184783Y535833D01*
Y533500D01*
G01X-180600Y538500D02*
Y533500D01*
G01X-181767Y536833D02*
X-179433D01*
G01X-176250Y534083D02*
X-175833Y533750D01*
X-175250Y533500D01*
X-174750D01*
X-174250Y533667D01*
X-173917Y533917D01*
X-173750Y534250D01*
X-173833Y534750D01*
X-174167Y535000D01*
X-175667Y535500D01*
X-176000Y536083D01*
X-175833Y536500D01*
X-175500Y536750D01*
X-175000Y536833D01*
X-174500Y536750D01*
X-174000Y536500D01*
G01X-163800Y536833D02*
Y533500D01*
G01Y538167D02*
X-163967Y538250D01*
Y538417D01*
X-163800Y538500D01*
X-163633Y538417D01*
Y538250D01*
X-163800Y538167D01*
G01X-159617Y533500D02*
Y536833D01*
G01Y536000D02*
X-159283Y536417D01*
X-158783Y536750D01*
X-158117Y536833D01*
X-157533Y536750D01*
X-157033Y536417D01*
X-156783Y535833D01*
Y533500D01*
G01X-145667Y536417D02*
X-146250Y536750D01*
X-146750Y536833D01*
X-147417Y536667D01*
X-147917Y536333D01*
X-148250Y535750D01*
X-148333Y535167D01*
X-148250Y534583D01*
X-147917Y534083D01*
X-147417Y533667D01*
X-146750Y533500D01*
X-146167Y533667D01*
X-145667Y534000D01*
G01X-141400Y533500D02*
Y538500D01*
G01X-134300Y533500D02*
Y536833D01*
G01Y536250D02*
X-134633Y536583D01*
X-135133Y536750D01*
X-135717Y536833D01*
X-136300Y536667D01*
X-136800Y536333D01*
X-137133Y535833D01*
X-137300Y535167D01*
X-137133Y534500D01*
X-136800Y534000D01*
X-136300Y533667D01*
X-135717Y533500D01*
X-135133Y533583D01*
X-134633Y533833D01*
X-134300Y534167D01*
G01X-131450Y534083D02*
X-131033Y533750D01*
X-130450Y533500D01*
X-129950D01*
X-129450Y533667D01*
X-129117Y533917D01*
X-128950Y534250D01*
X-129033Y534750D01*
X-129367Y535000D01*
X-130867Y535500D01*
X-131200Y536083D01*
X-131033Y536500D01*
X-130700Y536750D01*
X-130200Y536833D01*
X-129700Y536750D01*
X-129200Y536500D01*
G01X-125850Y534083D02*
X-125433Y533750D01*
X-124850Y533500D01*
X-124350D01*
X-123850Y533667D01*
X-123517Y533917D01*
X-123350Y534250D01*
X-123433Y534750D01*
X-123767Y535000D01*
X-125267Y535500D01*
X-125600Y536083D01*
X-125433Y536500D01*
X-125100Y536750D01*
X-124600Y536833D01*
X-124100Y536750D01*
X-123600Y536500D01*
G01X-114983Y537667D02*
X-114483Y538167D01*
X-113900Y538417D01*
X-113233Y538500D01*
X-112400Y538333D01*
X-111817Y537917D01*
X-111650Y537417D01*
X-111733Y536917D01*
X-112067Y536500D01*
X-113733Y535667D01*
X-114483Y535083D01*
X-114983Y534250D01*
X-115150Y533500D01*
X-111650D01*
G01X-100700D02*
Y536833D01*
G01Y536250D02*
X-101033Y536583D01*
X-101533Y536750D01*
X-102117Y536833D01*
X-102700Y536667D01*
X-103200Y536333D01*
X-103533Y535833D01*
X-103700Y535167D01*
X-103533Y534500D01*
X-103200Y534000D01*
X-102700Y533667D01*
X-102117Y533500D01*
X-101533Y533583D01*
X-101033Y533833D01*
X-100700Y534167D01*
G01X-98017Y533500D02*
Y536833D01*
G01Y536000D02*
X-97683Y536417D01*
X-97183Y536750D01*
X-96517Y536833D01*
X-95933Y536750D01*
X-95433Y536417D01*
X-95183Y535833D01*
Y533500D01*
G01X-89500Y538500D02*
Y533500D01*
G01Y534250D02*
X-89833Y533833D01*
X-90333Y533583D01*
X-90917Y533500D01*
X-91583Y533667D01*
X-92083Y534083D01*
X-92417Y534583D01*
X-92500Y535167D01*
X-92417Y535750D01*
X-92083Y536250D01*
X-91583Y536667D01*
X-90917Y536833D01*
X-90333Y536750D01*
X-89917Y536583D01*
X-89500Y536250D01*
G01X-79800Y538500D02*
Y533500D01*
G01X-80967Y536833D02*
X-78633D01*
G01X-75617Y533500D02*
Y538500D01*
G01Y536083D02*
X-75200Y536500D01*
X-74783Y536750D01*
X-74117Y536833D01*
X-73617Y536750D01*
X-73033Y536417D01*
X-72783Y535917D01*
Y533500D01*
G01X-69850Y535750D02*
X-67183D01*
X-67433Y536333D01*
X-67850Y536667D01*
X-68433Y536833D01*
X-69017Y536750D01*
X-69517Y536500D01*
X-69850Y535917D01*
X-70017Y535417D01*
Y534917D01*
X-69850Y534417D01*
X-69433Y533917D01*
X-68933Y533583D01*
X-68350Y533500D01*
X-67767Y533667D01*
X-67183Y534167D01*
G01X-57400Y533500D02*
Y538500D01*
G01X-50300Y533500D02*
Y536833D01*
G01Y536250D02*
X-50633Y536583D01*
X-51133Y536750D01*
X-51717Y536833D01*
X-52300Y536667D01*
X-52800Y536333D01*
X-53133Y535833D01*
X-53300Y535167D01*
X-53133Y534500D01*
X-52800Y534000D01*
X-52300Y533667D01*
X-51717Y533500D01*
X-51133Y533583D01*
X-50633Y533833D01*
X-50300Y534167D01*
G01X-46200Y538500D02*
Y533500D01*
G01X-47367Y536833D02*
X-45033D01*
G01X-41850Y535750D02*
X-39183D01*
X-39433Y536333D01*
X-39850Y536667D01*
X-40433Y536833D01*
X-41017Y536750D01*
X-41517Y536500D01*
X-41850Y535917D01*
X-42017Y535417D01*
Y534917D01*
X-41850Y534417D01*
X-41433Y533917D01*
X-40933Y533583D01*
X-40350Y533500D01*
X-39767Y533667D01*
X-39183Y534167D01*
G01X-36250Y534083D02*
X-35833Y533750D01*
X-35250Y533500D01*
X-34750D01*
X-34250Y533667D01*
X-33917Y533917D01*
X-33750Y534250D01*
X-33833Y534750D01*
X-34167Y535000D01*
X-35667Y535500D01*
X-36000Y536083D01*
X-35833Y536500D01*
X-35500Y536750D01*
X-35000Y536833D01*
X-34500Y536750D01*
X-34000Y536500D01*
G01X-29400Y538500D02*
Y533500D01*
G01X-30567Y536833D02*
X-28233D01*
G01X-19700D02*
X-18200Y533500D01*
X-16700Y536833D01*
G01X-13850Y535750D02*
X-11183D01*
X-11433Y536333D01*
X-11850Y536667D01*
X-12433Y536833D01*
X-13017Y536750D01*
X-13517Y536500D01*
X-13850Y535917D01*
X-14017Y535417D01*
Y534917D01*
X-13850Y534417D01*
X-13433Y533917D01*
X-12933Y533583D01*
X-12350Y533500D01*
X-11767Y533667D01*
X-11183Y534167D01*
G01X-8167Y533500D02*
Y536833D01*
G01Y536167D02*
X-7750Y536500D01*
X-7333Y536750D01*
X-6750Y536833D01*
X-6333Y536750D01*
X-5833Y536500D01*
G01X-2650Y534083D02*
X-2233Y533750D01*
X-1650Y533500D01*
X-1150D01*
X-650Y533667D01*
X-317Y533917D01*
X-150Y534250D01*
X-233Y534750D01*
X-567Y535000D01*
X-2067Y535500D01*
X-2400Y536083D01*
X-2233Y536500D01*
X-1900Y536750D01*
X-1400Y536833D01*
X-900Y536750D01*
X-400Y536500D01*
G01X4200Y536833D02*
Y533500D01*
G01Y538167D02*
X4033Y538250D01*
Y538417D01*
X4200Y538500D01*
X4367Y538417D01*
Y538250D01*
X4200Y538167D01*
G01X9800Y533500D02*
X9300Y533583D01*
X8800Y533917D01*
X8467Y534500D01*
X8300Y535167D01*
X8467Y535833D01*
X8800Y536417D01*
X9300Y536750D01*
X9800Y536833D01*
X10300Y536750D01*
X10800Y536417D01*
X11133Y535833D01*
X11217Y535167D01*
X11133Y534500D01*
X10800Y533917D01*
X10300Y533583D01*
X9800Y533500D01*
G01X13983D02*
Y536833D01*
G01Y536000D02*
X14317Y536417D01*
X14817Y536750D01*
X15483Y536833D01*
X16067Y536750D01*
X16567Y536417D01*
X16817Y535833D01*
Y533500D01*
G01X26600Y536833D02*
Y533500D01*
G01Y538167D02*
X26433Y538250D01*
Y538417D01*
X26600Y538500D01*
X26767Y538417D01*
Y538250D01*
X26600Y538167D01*
G01X30950Y534083D02*
X31367Y533750D01*
X31950Y533500D01*
X32450D01*
X32950Y533667D01*
X33283Y533917D01*
X33450Y534250D01*
X33367Y534750D01*
X33033Y535000D01*
X31533Y535500D01*
X31200Y536083D01*
X31367Y536500D01*
X31700Y536750D01*
X32200Y536833D01*
X32700Y536750D01*
X33200Y536500D01*
G01X42233Y533500D02*
Y536833D01*
G01Y536167D02*
X42650Y536500D01*
X43067Y536750D01*
X43650Y536833D01*
X44067Y536750D01*
X44567Y536500D01*
G01X47750Y535750D02*
X50417D01*
X50167Y536333D01*
X49750Y536667D01*
X49167Y536833D01*
X48583Y536750D01*
X48083Y536500D01*
X47750Y535917D01*
X47583Y535417D01*
Y534917D01*
X47750Y534417D01*
X48167Y533917D01*
X48667Y533583D01*
X49250Y533500D01*
X49833Y533667D01*
X50417Y534167D01*
G01X56100Y531833D02*
Y536833D01*
G01Y536083D02*
X55683Y536500D01*
X55183Y536750D01*
X54600Y536833D01*
X54100Y536750D01*
X53517Y536333D01*
X53183Y535750D01*
X53100Y535167D01*
X53183Y534583D01*
X53517Y534000D01*
X54100Y533583D01*
X54600Y533500D01*
X55183Y533583D01*
X55683Y533833D01*
X56100Y534250D01*
G01X58783Y536833D02*
Y534500D01*
X59117Y533917D01*
X59617Y533583D01*
X60200Y533500D01*
X60783Y533583D01*
X61283Y533917D01*
X61617Y534500D01*
G01Y533500D02*
Y536833D01*
G01X65800D02*
Y533500D01*
G01Y538167D02*
X65633Y538250D01*
Y538417D01*
X65800Y538500D01*
X65967Y538417D01*
Y538250D01*
X65800Y538167D01*
G01X70233Y533500D02*
Y536833D01*
G01Y536167D02*
X70650Y536500D01*
X71067Y536750D01*
X71650Y536833D01*
X72067Y536750D01*
X72567Y536500D01*
G01X75750Y535750D02*
X78417D01*
X78167Y536333D01*
X77750Y536667D01*
X77167Y536833D01*
X76583Y536750D01*
X76083Y536500D01*
X75750Y535917D01*
X75583Y535417D01*
Y534917D01*
X75750Y534417D01*
X76167Y533917D01*
X76667Y533583D01*
X77250Y533500D01*
X77833Y533667D01*
X78417Y534167D01*
G01X84100Y538500D02*
Y533500D01*
G01Y534250D02*
X83767Y533833D01*
X83267Y533583D01*
X82683Y533500D01*
X82017Y533667D01*
X81517Y534083D01*
X81183Y534583D01*
X81100Y535167D01*
X81183Y535750D01*
X81517Y536250D01*
X82017Y536667D01*
X82683Y536833D01*
X83267Y536750D01*
X83683Y536583D01*
X84100Y536250D01*
G01X88033Y532583D02*
X88367Y533667D01*
G01X-387500Y456600D02*
X-385500D01*
G01X-386500D02*
Y451600D01*
G01X-387500D02*
X-385500D01*
G01X-382567D02*
Y456600D01*
X-380567D01*
X-379900Y456350D01*
X-379400Y455767D01*
X-379233Y455100D01*
X-379400Y454433D01*
X-379817Y453933D01*
X-380567Y453683D01*
X-382567D01*
G01X-373467Y456183D02*
X-373967Y456433D01*
X-374550Y456600D01*
X-375217D01*
X-375967Y456350D01*
X-376550Y455933D01*
X-376967Y455433D01*
X-377300Y454600D01*
X-377383Y453850D01*
X-377217Y453100D01*
X-376967Y452600D01*
X-376467Y452100D01*
X-375883Y451767D01*
X-375300Y451600D01*
X-374717D01*
X-374133Y451767D01*
X-373633Y452017D01*
X-373217Y452350D01*
G01X-370783Y453267D02*
X-368617D01*
G01X-365767Y456600D02*
Y451600D01*
X-362433D01*
G01X-359583Y453267D02*
X-357417D01*
G01X-352900Y451600D02*
Y456600D01*
X-353900Y455600D01*
G01Y451600D02*
X-351900D01*
G01X-347300Y456600D02*
X-347967Y456433D01*
X-348467Y456017D01*
X-348800Y455517D01*
X-349050Y454850D01*
X-349133Y454100D01*
X-349050Y453350D01*
X-348800Y452683D01*
X-348467Y452183D01*
X-347967Y451767D01*
X-347300Y451600D01*
X-346633Y451767D01*
X-346133Y452183D01*
X-345800Y452683D01*
X-345550Y453350D01*
X-345467Y454100D01*
X-345550Y454850D01*
X-345800Y455517D01*
X-346133Y456017D01*
X-346633Y456433D01*
X-347300Y456600D01*
G01X-343117Y452183D02*
X-342533Y451767D01*
X-341867Y451600D01*
X-341200Y451767D01*
X-340617Y452267D01*
X-340200Y453017D01*
X-340033Y453767D01*
Y454683D01*
X-340200Y455433D01*
X-340617Y456100D01*
X-341117Y456433D01*
X-341700Y456600D01*
X-342367Y456433D01*
X-342867Y456100D01*
X-343200Y455600D01*
X-343367Y454933D01*
X-343200Y454350D01*
X-342783Y453767D01*
X-342283Y453433D01*
X-341700Y453350D01*
X-341033Y453517D01*
X-340533Y453933D01*
X-340033Y454683D01*
G01X-332250Y452267D02*
X-331583Y451850D01*
X-330833Y451600D01*
X-330167D01*
X-329500Y451850D01*
X-329000Y452267D01*
X-328750Y452850D01*
X-328917Y453433D01*
X-329333Y453933D01*
X-330083Y454267D01*
X-331083Y454433D01*
X-331667Y454767D01*
X-331917Y455350D01*
X-331750Y455933D01*
X-331333Y456350D01*
X-330750Y456600D01*
X-330167D01*
X-329583Y456433D01*
X-329083Y456017D01*
G01X-326400Y449933D02*
Y454933D01*
G01Y454183D02*
X-325983Y454600D01*
X-325567Y454850D01*
X-324900Y454933D01*
X-324317Y454850D01*
X-323733Y454433D01*
X-323483Y453850D01*
X-323400Y453267D01*
X-323483Y452683D01*
X-323733Y452100D01*
X-324233Y451767D01*
X-324900Y451600D01*
X-325483Y451683D01*
X-326067Y451933D01*
X-326400Y452267D01*
G01X-320550Y453850D02*
X-317883D01*
X-318133Y454433D01*
X-318550Y454767D01*
X-319133Y454933D01*
X-319717Y454850D01*
X-320217Y454600D01*
X-320550Y454017D01*
X-320717Y453517D01*
Y453017D01*
X-320550Y452517D01*
X-320133Y452017D01*
X-319633Y451683D01*
X-319050Y451600D01*
X-318467Y451767D01*
X-317883Y452267D01*
G01X-312367Y454517D02*
X-312950Y454850D01*
X-313450Y454933D01*
X-314117Y454767D01*
X-314617Y454433D01*
X-314950Y453850D01*
X-315033Y453267D01*
X-314950Y452683D01*
X-314617Y452183D01*
X-314117Y451767D01*
X-313450Y451600D01*
X-312867Y451767D01*
X-312367Y452100D01*
G01X-308100Y454933D02*
Y451600D01*
G01Y456267D02*
X-308267Y456350D01*
Y456517D01*
X-308100Y456600D01*
X-307933Y456517D01*
Y456350D01*
X-308100Y456267D01*
G01X-303000Y451600D02*
Y455850D01*
X-302833Y456267D01*
X-302500Y456517D01*
X-302000Y456600D01*
X-301500Y456433D01*
X-301250Y456017D01*
G01X-302250Y454600D02*
X-303917D01*
G01X-296900Y454933D02*
Y451600D01*
G01Y456267D02*
X-297067Y456350D01*
Y456517D01*
X-296900Y456600D01*
X-296733Y456517D01*
Y456350D01*
X-296900Y456267D01*
G01X-289967Y454517D02*
X-290550Y454850D01*
X-291050Y454933D01*
X-291717Y454767D01*
X-292217Y454433D01*
X-292550Y453850D01*
X-292633Y453267D01*
X-292550Y452683D01*
X-292217Y452183D01*
X-291717Y451767D01*
X-291050Y451600D01*
X-290467Y451767D01*
X-289967Y452100D01*
G01X-284200Y451600D02*
Y454933D01*
G01Y454350D02*
X-284533Y454683D01*
X-285033Y454850D01*
X-285617Y454933D01*
X-286200Y454767D01*
X-286700Y454433D01*
X-287033Y453933D01*
X-287200Y453267D01*
X-287033Y452600D01*
X-286700Y452100D01*
X-286200Y451767D01*
X-285617Y451600D01*
X-285033Y451683D01*
X-284533Y451933D01*
X-284200Y452267D01*
G01X-280100Y456600D02*
Y451600D01*
G01X-281267Y454933D02*
X-278933D01*
G01X-274500D02*
Y451600D01*
G01Y456267D02*
X-274667Y456350D01*
Y456517D01*
X-274500Y456600D01*
X-274333Y456517D01*
Y456350D01*
X-274500Y456267D01*
G01X-268900Y451600D02*
X-269400Y451683D01*
X-269900Y452017D01*
X-270233Y452600D01*
X-270400Y453267D01*
X-270233Y453933D01*
X-269900Y454517D01*
X-269400Y454850D01*
X-268900Y454933D01*
X-268400Y454850D01*
X-267900Y454517D01*
X-267567Y453933D01*
X-267483Y453267D01*
X-267567Y452600D01*
X-267900Y452017D01*
X-268400Y451683D01*
X-268900Y451600D01*
G01X-264717D02*
Y454933D01*
G01Y454100D02*
X-264383Y454517D01*
X-263883Y454850D01*
X-263217Y454933D01*
X-262633Y454850D01*
X-262133Y454517D01*
X-261883Y453933D01*
Y451600D01*
G01X-252600D02*
Y455850D01*
X-252433Y456267D01*
X-252100Y456517D01*
X-251600Y456600D01*
X-251100Y456433D01*
X-250850Y456017D01*
G01X-251850Y454600D02*
X-253517D01*
G01X-246500Y451600D02*
X-247000Y451683D01*
X-247500Y452017D01*
X-247833Y452600D01*
X-248000Y453267D01*
X-247833Y453933D01*
X-247500Y454517D01*
X-247000Y454850D01*
X-246500Y454933D01*
X-246000Y454850D01*
X-245500Y454517D01*
X-245167Y453933D01*
X-245083Y453267D01*
X-245167Y452600D01*
X-245500Y452017D01*
X-246000Y451683D01*
X-246500Y451600D01*
G01X-242067D02*
Y454933D01*
G01Y454267D02*
X-241650Y454600D01*
X-241233Y454850D01*
X-240650Y454933D01*
X-240233Y454850D01*
X-239733Y454600D01*
G01X-231367Y451600D02*
Y456600D01*
X-229283D01*
X-228617Y456350D01*
X-228200Y456017D01*
X-228033Y455350D01*
X-228200Y454683D01*
X-228700Y454267D01*
X-229283Y454017D01*
X-231367D01*
G01X-229283D02*
X-228033Y451600D01*
G01X-225350Y453850D02*
X-222683D01*
X-222933Y454433D01*
X-223350Y454767D01*
X-223933Y454933D01*
X-224517Y454850D01*
X-225017Y454600D01*
X-225350Y454017D01*
X-225517Y453517D01*
Y453017D01*
X-225350Y452517D01*
X-224933Y452017D01*
X-224433Y451683D01*
X-223850Y451600D01*
X-223267Y451767D01*
X-222683Y452267D01*
G01X-219750Y452183D02*
X-219333Y451850D01*
X-218750Y451600D01*
X-218250D01*
X-217750Y451767D01*
X-217417Y452017D01*
X-217250Y452350D01*
X-217333Y452850D01*
X-217667Y453100D01*
X-219167Y453600D01*
X-219500Y454183D01*
X-219333Y454600D01*
X-219000Y454850D01*
X-218500Y454933D01*
X-218000Y454850D01*
X-217500Y454600D01*
G01X-212900Y454933D02*
Y451600D01*
G01Y456267D02*
X-213067Y456350D01*
Y456517D01*
X-212900Y456600D01*
X-212733Y456517D01*
Y456350D01*
X-212900Y456267D01*
G01X-208717Y451600D02*
Y454933D01*
G01Y454100D02*
X-208383Y454517D01*
X-207883Y454850D01*
X-207217Y454933D01*
X-206633Y454850D01*
X-206133Y454517D01*
X-205883Y453933D01*
Y451600D01*
G01X-197100Y456600D02*
X-195100D01*
G01X-196100D02*
Y451600D01*
G01X-197100D02*
X-195100D01*
G01X-193000D02*
Y454933D01*
G01Y454017D02*
X-192750Y454433D01*
X-192333Y454767D01*
X-191750Y454933D01*
X-191167Y454767D01*
X-190750Y454433D01*
X-190500Y454017D01*
Y451600D01*
G01Y454017D02*
X-190250Y454433D01*
X-189833Y454767D01*
X-189250Y454933D01*
X-188667Y454767D01*
X-188250Y454433D01*
X-188000Y453933D01*
Y451600D01*
G01X-186400Y449933D02*
Y454933D01*
G01Y454183D02*
X-185983Y454600D01*
X-185567Y454850D01*
X-184900Y454933D01*
X-184317Y454850D01*
X-183733Y454433D01*
X-183483Y453850D01*
X-183400Y453267D01*
X-183483Y452683D01*
X-183733Y452100D01*
X-184233Y451767D01*
X-184900Y451600D01*
X-185483Y451683D01*
X-186067Y451933D01*
X-186400Y452267D01*
G01X-180467Y451600D02*
Y454933D01*
G01Y454267D02*
X-180050Y454600D01*
X-179633Y454850D01*
X-179050Y454933D01*
X-178633Y454850D01*
X-178133Y454600D01*
G01X-174950Y453850D02*
X-172283D01*
X-172533Y454433D01*
X-172950Y454767D01*
X-173533Y454933D01*
X-174117Y454850D01*
X-174617Y454600D01*
X-174950Y454017D01*
X-175117Y453517D01*
Y453017D01*
X-174950Y452517D01*
X-174533Y452017D01*
X-174033Y451683D01*
X-173450Y451600D01*
X-172867Y451767D01*
X-172283Y452267D01*
G01X-169267Y450350D02*
X-168683Y450017D01*
X-168017Y449933D01*
X-167433Y450017D01*
X-166933Y450433D01*
X-166600Y451017D01*
Y454933D01*
G01Y454267D02*
X-166933Y454600D01*
X-167433Y454850D01*
X-168017Y454933D01*
X-168683Y454767D01*
X-169100Y454433D01*
X-169433Y453850D01*
X-169600Y453267D01*
X-169517Y452767D01*
X-169183Y452183D01*
X-168683Y451767D01*
X-168017Y451600D01*
X-167517Y451683D01*
X-166933Y452017D01*
X-166600Y452350D01*
G01X-163917Y451600D02*
Y454933D01*
G01Y454100D02*
X-163583Y454517D01*
X-163083Y454850D01*
X-162417Y454933D01*
X-161833Y454850D01*
X-161333Y454517D01*
X-161083Y453933D01*
Y451600D01*
G01X-155400D02*
Y454933D01*
G01Y454350D02*
X-155733Y454683D01*
X-156233Y454850D01*
X-156817Y454933D01*
X-157400Y454767D01*
X-157900Y454433D01*
X-158233Y453933D01*
X-158400Y453267D01*
X-158233Y452600D01*
X-157900Y452100D01*
X-157400Y451767D01*
X-156817Y451600D01*
X-156233Y451683D01*
X-155733Y451933D01*
X-155400Y452267D01*
G01X-151300Y456600D02*
Y451600D01*
G01X-152467Y454933D02*
X-150133D01*
G01X-146950Y453850D02*
X-144283D01*
X-144533Y454433D01*
X-144950Y454767D01*
X-145533Y454933D01*
X-146117Y454850D01*
X-146617Y454600D01*
X-146950Y454017D01*
X-147117Y453517D01*
Y453017D01*
X-146950Y452517D01*
X-146533Y452017D01*
X-146033Y451683D01*
X-145450Y451600D01*
X-144867Y451767D01*
X-144283Y452267D01*
G01X-138600Y456600D02*
Y451600D01*
G01Y452350D02*
X-138933Y451933D01*
X-139433Y451683D01*
X-140017Y451600D01*
X-140683Y451767D01*
X-141183Y452183D01*
X-141517Y452683D01*
X-141600Y453267D01*
X-141517Y453850D01*
X-141183Y454350D01*
X-140683Y454767D01*
X-140017Y454933D01*
X-139433Y454850D01*
X-139017Y454683D01*
X-138600Y454350D01*
G01X-130483Y451600D02*
Y456600D01*
X-127317D01*
G01X-128483Y454183D02*
X-130483D01*
G01X-121800Y451600D02*
Y454933D01*
G01Y454350D02*
X-122133Y454683D01*
X-122633Y454850D01*
X-123217Y454933D01*
X-123800Y454767D01*
X-124300Y454433D01*
X-124633Y453933D01*
X-124800Y453267D01*
X-124633Y452600D01*
X-124300Y452100D01*
X-123800Y451767D01*
X-123217Y451600D01*
X-122633Y451683D01*
X-122133Y451933D01*
X-121800Y452267D01*
G01X-119200Y451600D02*
Y456600D01*
G01Y454100D02*
X-118783Y454600D01*
X-118283Y454850D01*
X-117783Y454933D01*
X-117033Y454767D01*
X-116533Y454433D01*
X-116200Y453850D01*
Y453183D01*
X-116367Y452517D01*
X-116700Y452017D01*
X-117283Y451683D01*
X-117783Y451600D01*
X-118283Y451683D01*
X-118783Y451933D01*
X-119200Y452350D01*
G01X-113267Y451600D02*
Y454933D01*
G01Y454267D02*
X-112850Y454600D01*
X-112433Y454850D01*
X-111850Y454933D01*
X-111433Y454850D01*
X-110933Y454600D01*
G01X-106500Y454933D02*
Y451600D01*
G01Y456267D02*
X-106667Y456350D01*
Y456517D01*
X-106500Y456600D01*
X-106333Y456517D01*
Y456350D01*
X-106500Y456267D01*
G01X-99567Y454517D02*
X-100150Y454850D01*
X-100650Y454933D01*
X-101317Y454767D01*
X-101817Y454433D01*
X-102150Y453850D01*
X-102233Y453267D01*
X-102150Y452683D01*
X-101817Y452183D01*
X-101317Y451767D01*
X-100650Y451600D01*
X-100067Y451767D01*
X-99567Y452100D01*
G01X-95717Y449933D02*
X-96550Y450767D01*
X-96967Y451600D01*
Y454933D01*
X-96550Y455767D01*
X-95717Y456600D01*
G01X-91367Y451600D02*
Y456600D01*
X-89367D01*
X-88700Y456350D01*
X-88200Y455767D01*
X-88033Y455100D01*
X-88200Y454433D01*
X-88617Y453933D01*
X-89367Y453683D01*
X-91367D01*
G01X-85267Y451600D02*
Y454933D01*
G01Y454267D02*
X-84850Y454600D01*
X-84433Y454850D01*
X-83850Y454933D01*
X-83433Y454850D01*
X-82933Y454600D01*
G01X-79750Y453850D02*
X-77083D01*
X-77333Y454433D01*
X-77750Y454767D01*
X-78333Y454933D01*
X-78917Y454850D01*
X-79417Y454600D01*
X-79750Y454017D01*
X-79917Y453517D01*
Y453017D01*
X-79750Y452517D01*
X-79333Y452017D01*
X-78833Y451683D01*
X-78250Y451600D01*
X-77667Y451767D01*
X-77083Y452267D01*
G01X-74400Y449933D02*
Y454933D01*
G01Y454183D02*
X-73983Y454600D01*
X-73567Y454850D01*
X-72900Y454933D01*
X-72317Y454850D01*
X-71733Y454433D01*
X-71483Y453850D01*
X-71400Y453267D01*
X-71483Y452683D01*
X-71733Y452100D01*
X-72233Y451767D01*
X-72900Y451600D01*
X-73483Y451683D01*
X-74067Y451933D01*
X-74400Y452267D01*
G01X-68467Y451600D02*
Y454933D01*
G01Y454267D02*
X-68050Y454600D01*
X-67633Y454850D01*
X-67050Y454933D01*
X-66633Y454850D01*
X-66133Y454600D01*
G01X-62950Y453850D02*
X-60283D01*
X-60533Y454433D01*
X-60950Y454767D01*
X-61533Y454933D01*
X-62117Y454850D01*
X-62617Y454600D01*
X-62950Y454017D01*
X-63117Y453517D01*
Y453017D01*
X-62950Y452517D01*
X-62533Y452017D01*
X-62033Y451683D01*
X-61450Y451600D01*
X-60867Y451767D01*
X-60283Y452267D01*
G01X-57267Y450350D02*
X-56683Y450017D01*
X-56017Y449933D01*
X-55433Y450017D01*
X-54933Y450433D01*
X-54600Y451017D01*
Y454933D01*
G01Y454267D02*
X-54933Y454600D01*
X-55433Y454850D01*
X-56017Y454933D01*
X-56683Y454767D01*
X-57100Y454433D01*
X-57433Y453850D01*
X-57600Y453267D01*
X-57517Y452767D01*
X-57183Y452183D01*
X-56683Y451767D01*
X-56017Y451600D01*
X-55517Y451683D01*
X-54933Y452017D01*
X-54600Y452350D01*
G01X-50083Y449933D02*
X-49250Y450767D01*
X-48833Y451600D01*
Y454933D01*
X-49250Y455767D01*
X-50083Y456600D01*
G01X-39800Y451600D02*
Y455850D01*
X-39633Y456267D01*
X-39300Y456517D01*
X-38800Y456600D01*
X-38300Y456433D01*
X-38050Y456017D01*
G01X-39050Y454600D02*
X-40717D01*
G01X-33700Y451600D02*
X-34200Y451683D01*
X-34700Y452017D01*
X-35033Y452600D01*
X-35200Y453267D01*
X-35033Y453933D01*
X-34700Y454517D01*
X-34200Y454850D01*
X-33700Y454933D01*
X-33200Y454850D01*
X-32700Y454517D01*
X-32367Y453933D01*
X-32283Y453267D01*
X-32367Y452600D01*
X-32700Y452017D01*
X-33200Y451683D01*
X-33700Y451600D01*
G01X-29267D02*
Y454933D01*
G01Y454267D02*
X-28850Y454600D01*
X-28433Y454850D01*
X-27850Y454933D01*
X-27433Y454850D01*
X-26933Y454600D01*
G01X-19067Y451600D02*
Y456600D01*
X-16900Y452433D01*
X-14733Y456600D01*
Y451600D01*
G01X-12717Y454933D02*
Y452600D01*
X-12383Y452017D01*
X-11883Y451683D01*
X-11300Y451600D01*
X-10717Y451683D01*
X-10217Y452017D01*
X-9883Y452600D01*
G01Y451600D02*
Y454933D01*
G01X-5700Y451600D02*
Y456600D01*
G01X-100D02*
Y451600D01*
G01X-1267Y454933D02*
X1067D01*
G01X5500D02*
Y451600D01*
G01Y456267D02*
X5333Y456350D01*
Y456517D01*
X5500Y456600D01*
X5667Y456517D01*
Y456350D01*
X5500Y456267D01*
G01X11100Y451600D02*
Y456600D01*
G01X18200Y451600D02*
Y454933D01*
G01Y454350D02*
X17867Y454683D01*
X17367Y454850D01*
X16783Y454933D01*
X16200Y454767D01*
X15700Y454433D01*
X15367Y453933D01*
X15200Y453267D01*
X15367Y452600D01*
X15700Y452100D01*
X16200Y451767D01*
X16783Y451600D01*
X17367Y451683D01*
X17867Y451933D01*
X18200Y452267D01*
G01X20550Y450100D02*
X21050Y449933D01*
X21717Y450100D01*
X22133Y450433D01*
X22467Y450850D01*
X22967Y452183D01*
X24050Y454933D01*
G01X21383D02*
X22967Y452183D01*
G01X26650Y453850D02*
X29317D01*
X29067Y454433D01*
X28650Y454767D01*
X28067Y454933D01*
X27483Y454850D01*
X26983Y454600D01*
X26650Y454017D01*
X26483Y453517D01*
Y453017D01*
X26650Y452517D01*
X27067Y452017D01*
X27567Y451683D01*
X28150Y451600D01*
X28733Y451767D01*
X29317Y452267D01*
G01X32333Y451600D02*
Y454933D01*
G01Y454267D02*
X32750Y454600D01*
X33167Y454850D01*
X33750Y454933D01*
X34167Y454850D01*
X34667Y454600D01*
G01X43033Y451600D02*
Y456600D01*
X45033D01*
X45700Y456350D01*
X46200Y455767D01*
X46367Y455100D01*
X46200Y454433D01*
X45783Y453933D01*
X45033Y453683D01*
X43033D01*
G01X49133Y451600D02*
Y454933D01*
G01Y454267D02*
X49550Y454600D01*
X49967Y454850D01*
X50550Y454933D01*
X50967Y454850D01*
X51467Y454600D01*
G01X55900Y454933D02*
Y451600D01*
G01Y456267D02*
X55733Y456350D01*
Y456517D01*
X55900Y456600D01*
X56067Y456517D01*
Y456350D01*
X55900Y456267D01*
G01X60083Y451600D02*
Y454933D01*
G01Y454100D02*
X60417Y454517D01*
X60917Y454850D01*
X61583Y454933D01*
X62167Y454850D01*
X62667Y454517D01*
X62917Y453933D01*
Y451600D01*
G01X67100Y456600D02*
Y451600D01*
G01X65933Y454933D02*
X68267D01*
G01X71450Y453850D02*
X74117D01*
X73867Y454433D01*
X73450Y454767D01*
X72867Y454933D01*
X72283Y454850D01*
X71783Y454600D01*
X71450Y454017D01*
X71283Y453517D01*
Y453017D01*
X71450Y452517D01*
X71867Y452017D01*
X72367Y451683D01*
X72950Y451600D01*
X73533Y451767D01*
X74117Y452267D01*
G01X79800Y456600D02*
Y451600D01*
G01Y452350D02*
X79467Y451933D01*
X78967Y451683D01*
X78383Y451600D01*
X77717Y451767D01*
X77217Y452183D01*
X76883Y452683D01*
X76800Y453267D01*
X76883Y453850D01*
X77217Y454350D01*
X77717Y454767D01*
X78383Y454933D01*
X78967Y454850D01*
X79383Y454683D01*
X79800Y454350D01*
G01X90167Y454267D02*
X90500Y454517D01*
X90750Y454933D01*
X90917Y455517D01*
X90750Y456017D01*
X90417Y456350D01*
X89833Y456600D01*
X87583D01*
Y451600D01*
X90333D01*
X90917Y451933D01*
X91250Y452433D01*
X91417Y453017D01*
X91250Y453600D01*
X90750Y454100D01*
X90167Y454267D01*
X87583D01*
G01X95100Y451600D02*
X94600Y451683D01*
X94100Y452017D01*
X93767Y452600D01*
X93600Y453267D01*
X93767Y453933D01*
X94100Y454517D01*
X94600Y454850D01*
X95100Y454933D01*
X95600Y454850D01*
X96100Y454517D01*
X96433Y453933D01*
X96517Y453267D01*
X96433Y452600D01*
X96100Y452017D01*
X95600Y451683D01*
X95100Y451600D01*
G01X102200D02*
Y454933D01*
G01Y454350D02*
X101867Y454683D01*
X101367Y454850D01*
X100783Y454933D01*
X100200Y454767D01*
X99700Y454433D01*
X99367Y453933D01*
X99200Y453267D01*
X99367Y452600D01*
X99700Y452100D01*
X100200Y451767D01*
X100783Y451600D01*
X101367Y451683D01*
X101867Y451933D01*
X102200Y452267D01*
G01X105133Y451600D02*
Y454933D01*
G01Y454267D02*
X105550Y454600D01*
X105967Y454850D01*
X106550Y454933D01*
X106967Y454850D01*
X107467Y454600D01*
G01X113400Y456600D02*
Y451600D01*
G01Y452350D02*
X113067Y451933D01*
X112567Y451683D01*
X111983Y451600D01*
X111317Y451767D01*
X110817Y452183D01*
X110483Y452683D01*
X110400Y453267D01*
X110483Y453850D01*
X110817Y454350D01*
X111317Y454767D01*
X111983Y454933D01*
X112567Y454850D01*
X112983Y454683D01*
X113400Y454350D01*
G01X116250Y452183D02*
X116667Y451850D01*
X117250Y451600D01*
X117750D01*
X118250Y451767D01*
X118583Y452017D01*
X118750Y452350D01*
X118667Y452850D01*
X118333Y453100D01*
X116833Y453600D01*
X116500Y454183D01*
X116667Y454600D01*
X117000Y454850D01*
X117500Y454933D01*
X118000Y454850D01*
X118500Y454600D01*
G01X-387500Y465600D02*
X-385500D01*
G01X-386500D02*
Y460600D01*
G01X-387500D02*
X-385500D01*
G01X-382567D02*
Y465600D01*
X-380567D01*
X-379900Y465350D01*
X-379400Y464767D01*
X-379233Y464100D01*
X-379400Y463433D01*
X-379817Y462933D01*
X-380567Y462683D01*
X-382567D01*
G01X-373467Y465183D02*
X-373967Y465433D01*
X-374550Y465600D01*
X-375217D01*
X-375967Y465350D01*
X-376550Y464933D01*
X-376967Y464433D01*
X-377300Y463600D01*
X-377383Y462850D01*
X-377217Y462100D01*
X-376967Y461600D01*
X-376467Y461100D01*
X-375883Y460767D01*
X-375300Y460600D01*
X-374717D01*
X-374133Y460767D01*
X-373633Y461017D01*
X-373217Y461350D01*
G01X-370783Y462267D02*
X-368617D01*
G01X-366267Y460600D02*
Y465600D01*
X-364100Y461433D01*
X-361933Y465600D01*
Y460600D01*
G01X-360083D02*
Y465600D01*
X-356917D01*
G01X-358083Y463183D02*
X-360083D01*
G01X-353983Y462267D02*
X-351817D01*
G01X-347300Y460600D02*
Y465600D01*
X-348300Y464600D01*
G01Y460600D02*
X-346300D01*
G01X-343533Y461350D02*
X-343033Y460933D01*
X-342450Y460683D01*
X-341700Y460600D01*
X-340950Y460767D01*
X-340367Y461100D01*
X-339950Y461683D01*
X-339867Y462350D01*
X-340033Y463017D01*
X-340450Y463433D01*
X-341033Y463767D01*
X-341617Y463850D01*
X-342200Y463767D01*
X-342950Y463433D01*
X-342700Y465600D01*
X-340450D01*
G01X-336100D02*
X-336767Y465433D01*
X-337267Y465017D01*
X-337600Y464517D01*
X-337850Y463850D01*
X-337933Y463100D01*
X-337850Y462350D01*
X-337600Y461683D01*
X-337267Y461183D01*
X-336767Y460767D01*
X-336100Y460600D01*
X-335433Y460767D01*
X-334933Y461183D01*
X-334600Y461683D01*
X-334350Y462350D01*
X-334267Y463100D01*
X-334350Y463850D01*
X-334600Y464517D01*
X-334933Y465017D01*
X-335433Y465433D01*
X-336100Y465600D01*
G01X-327067Y460600D02*
Y465600D01*
X-324900Y461433D01*
X-322733Y465600D01*
Y460600D01*
G01X-320550Y462850D02*
X-317883D01*
X-318133Y463433D01*
X-318550Y463767D01*
X-319133Y463933D01*
X-319717Y463850D01*
X-320217Y463600D01*
X-320550Y463017D01*
X-320717Y462517D01*
Y462017D01*
X-320550Y461517D01*
X-320133Y461017D01*
X-319633Y460683D01*
X-319050Y460600D01*
X-318467Y460767D01*
X-317883Y461267D01*
G01X-313700Y465600D02*
Y460600D01*
G01X-314867Y463933D02*
X-312533D01*
G01X-306600Y460600D02*
Y463933D01*
G01Y463350D02*
X-306933Y463683D01*
X-307433Y463850D01*
X-308017Y463933D01*
X-308600Y463767D01*
X-309100Y463433D01*
X-309433Y462933D01*
X-309600Y462267D01*
X-309433Y461600D01*
X-309100Y461100D01*
X-308600Y460767D01*
X-308017Y460600D01*
X-307433Y460683D01*
X-306933Y460933D01*
X-306600Y461267D01*
G01X-302500Y460600D02*
Y465600D01*
G01X-292883Y460600D02*
Y465600D01*
X-289717D01*
G01X-290883Y463183D02*
X-292883D01*
G01X-285700Y460600D02*
X-286200Y460683D01*
X-286700Y461017D01*
X-287033Y461600D01*
X-287200Y462267D01*
X-287033Y462933D01*
X-286700Y463517D01*
X-286200Y463850D01*
X-285700Y463933D01*
X-285200Y463850D01*
X-284700Y463517D01*
X-284367Y462933D01*
X-284283Y462267D01*
X-284367Y461600D01*
X-284700Y461017D01*
X-285200Y460683D01*
X-285700Y460600D01*
G01X-280100Y463933D02*
Y460600D01*
G01Y465267D02*
X-280267Y465350D01*
Y465517D01*
X-280100Y465600D01*
X-279933Y465517D01*
Y465350D01*
X-280100Y465267D01*
G01X-274500Y460600D02*
Y465600D01*
G01X-263800Y460600D02*
Y464850D01*
X-263633Y465267D01*
X-263300Y465517D01*
X-262800Y465600D01*
X-262300Y465433D01*
X-262050Y465017D01*
G01X-263050Y463600D02*
X-264717D01*
G01X-257700Y460600D02*
X-258200Y460683D01*
X-258700Y461017D01*
X-259033Y461600D01*
X-259200Y462267D01*
X-259033Y462933D01*
X-258700Y463517D01*
X-258200Y463850D01*
X-257700Y463933D01*
X-257200Y463850D01*
X-256700Y463517D01*
X-256367Y462933D01*
X-256283Y462267D01*
X-256367Y461600D01*
X-256700Y461017D01*
X-257200Y460683D01*
X-257700Y460600D01*
G01X-253267D02*
Y463933D01*
G01Y463267D02*
X-252850Y463600D01*
X-252433Y463850D01*
X-251850Y463933D01*
X-251433Y463850D01*
X-250933Y463600D01*
G01X-242567Y460600D02*
Y465600D01*
X-240567D01*
X-239900Y465350D01*
X-239400Y464767D01*
X-239233Y464100D01*
X-239400Y463433D01*
X-239817Y462933D01*
X-240567Y462683D01*
X-242567D01*
G01X-236467Y460600D02*
Y463933D01*
G01Y463267D02*
X-236050Y463600D01*
X-235633Y463850D01*
X-235050Y463933D01*
X-234633Y463850D01*
X-234133Y463600D01*
G01X-229700Y463933D02*
Y460600D01*
G01Y465267D02*
X-229867Y465350D01*
Y465517D01*
X-229700Y465600D01*
X-229533Y465517D01*
Y465350D01*
X-229700Y465267D01*
G01X-225517Y460600D02*
Y463933D01*
G01Y463100D02*
X-225183Y463517D01*
X-224683Y463850D01*
X-224017Y463933D01*
X-223433Y463850D01*
X-222933Y463517D01*
X-222683Y462933D01*
Y460600D01*
G01X-218500Y465600D02*
Y460600D01*
G01X-219667Y463933D02*
X-217333D01*
G01X-214150Y462850D02*
X-211483D01*
X-211733Y463433D01*
X-212150Y463767D01*
X-212733Y463933D01*
X-213317Y463850D01*
X-213817Y463600D01*
X-214150Y463017D01*
X-214317Y462517D01*
Y462017D01*
X-214150Y461517D01*
X-213733Y461017D01*
X-213233Y460683D01*
X-212650Y460600D01*
X-212067Y460767D01*
X-211483Y461267D01*
G01X-205800Y465600D02*
Y460600D01*
G01Y461350D02*
X-206133Y460933D01*
X-206633Y460683D01*
X-207217Y460600D01*
X-207883Y460767D01*
X-208383Y461183D01*
X-208717Y461683D01*
X-208800Y462267D01*
X-208717Y462850D01*
X-208383Y463350D01*
X-207883Y463767D01*
X-207217Y463933D01*
X-206633Y463850D01*
X-206217Y463683D01*
X-205800Y463350D01*
G01X-198600Y465600D02*
X-197433Y460600D01*
X-196100Y465600D01*
X-194767Y460600D01*
X-193600Y465600D01*
G01X-190500Y463933D02*
Y460600D01*
G01Y465267D02*
X-190667Y465350D01*
Y465517D01*
X-190500Y465600D01*
X-190333Y465517D01*
Y465350D01*
X-190500Y465267D01*
G01X-186067Y460600D02*
Y463933D01*
G01Y463267D02*
X-185650Y463600D01*
X-185233Y463850D01*
X-184650Y463933D01*
X-184233Y463850D01*
X-183733Y463600D01*
G01X-179300Y463933D02*
Y460600D01*
G01Y465267D02*
X-179467Y465350D01*
Y465517D01*
X-179300Y465600D01*
X-179133Y465517D01*
Y465350D01*
X-179300Y465267D01*
G01X-175117Y460600D02*
Y463933D01*
G01Y463100D02*
X-174783Y463517D01*
X-174283Y463850D01*
X-173617Y463933D01*
X-173033Y463850D01*
X-172533Y463517D01*
X-172283Y462933D01*
Y460600D01*
G01X-169267Y459350D02*
X-168683Y459017D01*
X-168017Y458933D01*
X-167433Y459017D01*
X-166933Y459433D01*
X-166600Y460017D01*
Y463933D01*
G01Y463267D02*
X-166933Y463600D01*
X-167433Y463850D01*
X-168017Y463933D01*
X-168683Y463767D01*
X-169100Y463433D01*
X-169433Y462850D01*
X-169600Y462267D01*
X-169517Y461767D01*
X-169183Y461183D01*
X-168683Y460767D01*
X-168017Y460600D01*
X-167517Y460683D01*
X-166933Y461017D01*
X-166600Y461350D01*
G01X-158983Y460600D02*
X-156900Y465600D01*
X-154817Y460600D01*
G01X-155567Y462350D02*
X-158233D01*
G01X-152800Y458933D02*
Y463933D01*
G01Y463183D02*
X-152383Y463600D01*
X-151967Y463850D01*
X-151300Y463933D01*
X-150717Y463850D01*
X-150133Y463433D01*
X-149883Y462850D01*
X-149800Y462267D01*
X-149883Y461683D01*
X-150133Y461100D01*
X-150633Y460767D01*
X-151300Y460600D01*
X-151883Y460683D01*
X-152467Y460933D01*
X-152800Y461267D01*
G01X-147200Y458933D02*
Y463933D01*
G01Y463183D02*
X-146783Y463600D01*
X-146367Y463850D01*
X-145700Y463933D01*
X-145117Y463850D01*
X-144533Y463433D01*
X-144283Y462850D01*
X-144200Y462267D01*
X-144283Y461683D01*
X-144533Y461100D01*
X-145033Y460767D01*
X-145700Y460600D01*
X-146283Y460683D01*
X-146867Y460933D01*
X-147200Y461267D01*
G01X-140100Y460600D02*
Y465600D01*
G01X-134500Y463933D02*
Y460600D01*
G01Y465267D02*
X-134667Y465350D01*
Y465517D01*
X-134500Y465600D01*
X-134333Y465517D01*
Y465350D01*
X-134500Y465267D01*
G01X-127567Y463517D02*
X-128150Y463850D01*
X-128650Y463933D01*
X-129317Y463767D01*
X-129817Y463433D01*
X-130150Y462850D01*
X-130233Y462267D01*
X-130150Y461683D01*
X-129817Y461183D01*
X-129317Y460767D01*
X-128650Y460600D01*
X-128067Y460767D01*
X-127567Y461100D01*
G01X-121800Y460600D02*
Y463933D01*
G01Y463350D02*
X-122133Y463683D01*
X-122633Y463850D01*
X-123217Y463933D01*
X-123800Y463767D01*
X-124300Y463433D01*
X-124633Y462933D01*
X-124800Y462267D01*
X-124633Y461600D01*
X-124300Y461100D01*
X-123800Y460767D01*
X-123217Y460600D01*
X-122633Y460683D01*
X-122133Y460933D01*
X-121800Y461267D01*
G01X-117700Y465600D02*
Y460600D01*
G01X-118867Y463933D02*
X-116533D01*
G01X-112100D02*
Y460600D01*
G01Y465267D02*
X-112267Y465350D01*
Y465517D01*
X-112100Y465600D01*
X-111933Y465517D01*
Y465350D01*
X-112100Y465267D01*
G01X-106500Y460600D02*
X-107000Y460683D01*
X-107500Y461017D01*
X-107833Y461600D01*
X-108000Y462267D01*
X-107833Y462933D01*
X-107500Y463517D01*
X-107000Y463850D01*
X-106500Y463933D01*
X-106000Y463850D01*
X-105500Y463517D01*
X-105167Y462933D01*
X-105083Y462267D01*
X-105167Y461600D01*
X-105500Y461017D01*
X-106000Y460683D01*
X-106500Y460600D01*
G01X-102317D02*
Y463933D01*
G01Y463100D02*
X-101983Y463517D01*
X-101483Y463850D01*
X-100817Y463933D01*
X-100233Y463850D01*
X-99733Y463517D01*
X-99483Y462933D01*
Y460600D01*
G01X-96550Y461183D02*
X-96133Y460850D01*
X-95550Y460600D01*
X-95050D01*
X-94550Y460767D01*
X-94217Y461017D01*
X-94050Y461350D01*
X-94133Y461850D01*
X-94467Y462100D01*
X-95967Y462600D01*
X-96300Y463183D01*
X-96133Y463600D01*
X-95800Y463850D01*
X-95300Y463933D01*
X-94800Y463850D01*
X-94300Y463600D01*
G01X-387500Y474600D02*
X-385500D01*
G01X-386500D02*
Y469600D01*
G01X-387500D02*
X-385500D01*
G01X-382567D02*
Y474600D01*
X-380567D01*
X-379900Y474350D01*
X-379400Y473767D01*
X-379233Y473100D01*
X-379400Y472433D01*
X-379817Y471933D01*
X-380567Y471683D01*
X-382567D01*
G01X-373467Y474183D02*
X-373967Y474433D01*
X-374550Y474600D01*
X-375217D01*
X-375967Y474350D01*
X-376550Y473933D01*
X-376967Y473433D01*
X-377300Y472600D01*
X-377383Y471850D01*
X-377217Y471100D01*
X-376967Y470600D01*
X-376467Y470100D01*
X-375883Y469767D01*
X-375300Y469600D01*
X-374717D01*
X-374133Y469767D01*
X-373633Y470017D01*
X-373217Y470350D01*
G01X-370783Y471267D02*
X-368617D01*
G01X-363100Y469600D02*
Y474600D01*
X-366183Y471017D01*
X-362017D01*
G01X-358500Y469600D02*
Y474600D01*
X-359500Y473600D01*
G01Y469600D02*
X-357500D01*
G01X-352900Y474600D02*
X-353567Y474433D01*
X-354067Y474017D01*
X-354400Y473517D01*
X-354650Y472850D01*
X-354733Y472100D01*
X-354650Y471350D01*
X-354400Y470683D01*
X-354067Y470183D01*
X-353567Y469767D01*
X-352900Y469600D01*
X-352233Y469767D01*
X-351733Y470183D01*
X-351400Y470683D01*
X-351150Y471350D01*
X-351067Y472100D01*
X-351150Y472850D01*
X-351400Y473517D01*
X-351733Y474017D01*
X-352233Y474433D01*
X-352900Y474600D01*
G01X-347300Y469600D02*
Y474600D01*
X-348300Y473600D01*
G01Y469600D02*
X-346300D01*
G01X-337850Y470267D02*
X-337183Y469850D01*
X-336433Y469600D01*
X-335767D01*
X-335100Y469850D01*
X-334600Y470267D01*
X-334350Y470850D01*
X-334517Y471433D01*
X-334933Y471933D01*
X-335683Y472267D01*
X-336683Y472433D01*
X-337267Y472767D01*
X-337517Y473350D01*
X-337350Y473933D01*
X-336933Y474350D01*
X-336350Y474600D01*
X-335767D01*
X-335183Y474433D01*
X-334683Y474017D01*
G01X-332000Y467933D02*
Y472933D01*
G01Y472183D02*
X-331583Y472600D01*
X-331167Y472850D01*
X-330500Y472933D01*
X-329917Y472850D01*
X-329333Y472433D01*
X-329083Y471850D01*
X-329000Y471267D01*
X-329083Y470683D01*
X-329333Y470100D01*
X-329833Y469767D01*
X-330500Y469600D01*
X-331083Y469683D01*
X-331667Y469933D01*
X-332000Y470267D01*
G01X-326150Y471850D02*
X-323483D01*
X-323733Y472433D01*
X-324150Y472767D01*
X-324733Y472933D01*
X-325317Y472850D01*
X-325817Y472600D01*
X-326150Y472017D01*
X-326317Y471517D01*
Y471017D01*
X-326150Y470517D01*
X-325733Y470017D01*
X-325233Y469683D01*
X-324650Y469600D01*
X-324067Y469767D01*
X-323483Y470267D01*
G01X-317967Y472517D02*
X-318550Y472850D01*
X-319050Y472933D01*
X-319717Y472767D01*
X-320217Y472433D01*
X-320550Y471850D01*
X-320633Y471267D01*
X-320550Y470683D01*
X-320217Y470183D01*
X-319717Y469767D01*
X-319050Y469600D01*
X-318467Y469767D01*
X-317967Y470100D01*
G01X-313700Y472933D02*
Y469600D01*
G01Y474267D02*
X-313867Y474350D01*
Y474517D01*
X-313700Y474600D01*
X-313533Y474517D01*
Y474350D01*
X-313700Y474267D01*
G01X-308600Y469600D02*
Y473850D01*
X-308433Y474267D01*
X-308100Y474517D01*
X-307600Y474600D01*
X-307100Y474433D01*
X-306850Y474017D01*
G01X-307850Y472600D02*
X-309517D01*
G01X-302500Y472933D02*
Y469600D01*
G01Y474267D02*
X-302667Y474350D01*
Y474517D01*
X-302500Y474600D01*
X-302333Y474517D01*
Y474350D01*
X-302500Y474267D01*
G01X-295567Y472517D02*
X-296150Y472850D01*
X-296650Y472933D01*
X-297317Y472767D01*
X-297817Y472433D01*
X-298150Y471850D01*
X-298233Y471267D01*
X-298150Y470683D01*
X-297817Y470183D01*
X-297317Y469767D01*
X-296650Y469600D01*
X-296067Y469767D01*
X-295567Y470100D01*
G01X-289800Y469600D02*
Y472933D01*
G01Y472350D02*
X-290133Y472683D01*
X-290633Y472850D01*
X-291217Y472933D01*
X-291800Y472767D01*
X-292300Y472433D01*
X-292633Y471933D01*
X-292800Y471267D01*
X-292633Y470600D01*
X-292300Y470100D01*
X-291800Y469767D01*
X-291217Y469600D01*
X-290633Y469683D01*
X-290133Y469933D01*
X-289800Y470267D01*
G01X-285700Y474600D02*
Y469600D01*
G01X-286867Y472933D02*
X-284533D01*
G01X-280100D02*
Y469600D01*
G01Y474267D02*
X-280267Y474350D01*
Y474517D01*
X-280100Y474600D01*
X-279933Y474517D01*
Y474350D01*
X-280100Y474267D01*
G01X-274500Y469600D02*
X-275000Y469683D01*
X-275500Y470017D01*
X-275833Y470600D01*
X-276000Y471267D01*
X-275833Y471933D01*
X-275500Y472517D01*
X-275000Y472850D01*
X-274500Y472933D01*
X-274000Y472850D01*
X-273500Y472517D01*
X-273167Y471933D01*
X-273083Y471267D01*
X-273167Y470600D01*
X-273500Y470017D01*
X-274000Y469683D01*
X-274500Y469600D01*
G01X-270317D02*
Y472933D01*
G01Y472100D02*
X-269983Y472517D01*
X-269483Y472850D01*
X-268817Y472933D01*
X-268233Y472850D01*
X-267733Y472517D01*
X-267483Y471933D01*
Y469600D01*
G01X-258200D02*
Y473850D01*
X-258033Y474267D01*
X-257700Y474517D01*
X-257200Y474600D01*
X-256700Y474433D01*
X-256450Y474017D01*
G01X-257450Y472600D02*
X-259117D01*
G01X-252100Y469600D02*
X-252600Y469683D01*
X-253100Y470017D01*
X-253433Y470600D01*
X-253600Y471267D01*
X-253433Y471933D01*
X-253100Y472517D01*
X-252600Y472850D01*
X-252100Y472933D01*
X-251600Y472850D01*
X-251100Y472517D01*
X-250767Y471933D01*
X-250683Y471267D01*
X-250767Y470600D01*
X-251100Y470017D01*
X-251600Y469683D01*
X-252100Y469600D01*
G01X-247667D02*
Y472933D01*
G01Y472267D02*
X-247250Y472600D01*
X-246833Y472850D01*
X-246250Y472933D01*
X-245833Y472850D01*
X-245333Y472600D01*
G01X-234633Y472267D02*
X-234300Y472517D01*
X-234050Y472933D01*
X-233883Y473517D01*
X-234050Y474017D01*
X-234383Y474350D01*
X-234967Y474600D01*
X-237217D01*
Y469600D01*
X-234467D01*
X-233883Y469933D01*
X-233550Y470433D01*
X-233383Y471017D01*
X-233550Y471600D01*
X-234050Y472100D01*
X-234633Y472267D01*
X-237217D01*
G01X-228200Y469600D02*
Y472933D01*
G01Y472350D02*
X-228533Y472683D01*
X-229033Y472850D01*
X-229617Y472933D01*
X-230200Y472767D01*
X-230700Y472433D01*
X-231033Y471933D01*
X-231200Y471267D01*
X-231033Y470600D01*
X-230700Y470100D01*
X-230200Y469767D01*
X-229617Y469600D01*
X-229033Y469683D01*
X-228533Y469933D01*
X-228200Y470267D01*
G01X-225350Y470183D02*
X-224933Y469850D01*
X-224350Y469600D01*
X-223850D01*
X-223350Y469767D01*
X-223017Y470017D01*
X-222850Y470350D01*
X-222933Y470850D01*
X-223267Y471100D01*
X-224767Y471600D01*
X-225100Y472183D01*
X-224933Y472600D01*
X-224600Y472850D01*
X-224100Y472933D01*
X-223600Y472850D01*
X-223100Y472600D01*
G01X-219750Y471850D02*
X-217083D01*
X-217333Y472433D01*
X-217750Y472767D01*
X-218333Y472933D01*
X-218917Y472850D01*
X-219417Y472600D01*
X-219750Y472017D01*
X-219917Y471517D01*
Y471017D01*
X-219750Y470517D01*
X-219333Y470017D01*
X-218833Y469683D01*
X-218250Y469600D01*
X-217667Y469767D01*
X-217083Y470267D01*
G01X-209467Y469600D02*
Y474600D01*
X-207300Y470433D01*
X-205133Y474600D01*
Y469600D01*
G01X-200200D02*
Y472933D01*
G01Y472350D02*
X-200533Y472683D01*
X-201033Y472850D01*
X-201617Y472933D01*
X-202200Y472767D01*
X-202700Y472433D01*
X-203033Y471933D01*
X-203200Y471267D01*
X-203033Y470600D01*
X-202700Y470100D01*
X-202200Y469767D01*
X-201617Y469600D01*
X-201033Y469683D01*
X-200533Y469933D01*
X-200200Y470267D01*
G01X-196100Y474600D02*
Y469600D01*
G01X-197267Y472933D02*
X-194933D01*
G01X-191750Y471850D02*
X-189083D01*
X-189333Y472433D01*
X-189750Y472767D01*
X-190333Y472933D01*
X-190917Y472850D01*
X-191417Y472600D01*
X-191750Y472017D01*
X-191917Y471517D01*
Y471017D01*
X-191750Y470517D01*
X-191333Y470017D01*
X-190833Y469683D01*
X-190250Y469600D01*
X-189667Y469767D01*
X-189083Y470267D01*
G01X-186067Y469600D02*
Y472933D01*
G01Y472267D02*
X-185650Y472600D01*
X-185233Y472850D01*
X-184650Y472933D01*
X-184233Y472850D01*
X-183733Y472600D01*
G01X-179300Y472933D02*
Y469600D01*
G01Y474267D02*
X-179467Y474350D01*
Y474517D01*
X-179300Y474600D01*
X-179133Y474517D01*
Y474350D01*
X-179300Y474267D01*
G01X-172200Y469600D02*
Y472933D01*
G01Y472350D02*
X-172533Y472683D01*
X-173033Y472850D01*
X-173617Y472933D01*
X-174200Y472767D01*
X-174700Y472433D01*
X-175033Y471933D01*
X-175200Y471267D01*
X-175033Y470600D01*
X-174700Y470100D01*
X-174200Y469767D01*
X-173617Y469600D01*
X-173033Y469683D01*
X-172533Y469933D01*
X-172200Y470267D01*
G01X-168100Y469600D02*
Y474600D01*
G01X-163750Y470183D02*
X-163333Y469850D01*
X-162750Y469600D01*
X-162250D01*
X-161750Y469767D01*
X-161417Y470017D01*
X-161250Y470350D01*
X-161333Y470850D01*
X-161667Y471100D01*
X-163167Y471600D01*
X-163500Y472183D01*
X-163333Y472600D01*
X-163000Y472850D01*
X-162500Y472933D01*
X-162000Y472850D01*
X-161500Y472600D01*
G01X-151800Y469600D02*
Y473850D01*
X-151633Y474267D01*
X-151300Y474517D01*
X-150800Y474600D01*
X-150300Y474433D01*
X-150050Y474017D01*
G01X-151050Y472600D02*
X-152717D01*
G01X-145700Y469600D02*
X-146200Y469683D01*
X-146700Y470017D01*
X-147033Y470600D01*
X-147200Y471267D01*
X-147033Y471933D01*
X-146700Y472517D01*
X-146200Y472850D01*
X-145700Y472933D01*
X-145200Y472850D01*
X-144700Y472517D01*
X-144367Y471933D01*
X-144283Y471267D01*
X-144367Y470600D01*
X-144700Y470017D01*
X-145200Y469683D01*
X-145700Y469600D01*
G01X-141267D02*
Y472933D01*
G01Y472267D02*
X-140850Y472600D01*
X-140433Y472850D01*
X-139850Y472933D01*
X-139433Y472850D01*
X-138933Y472600D01*
G01X-130567Y469600D02*
Y474600D01*
X-128483D01*
X-127817Y474350D01*
X-127400Y474017D01*
X-127233Y473350D01*
X-127400Y472683D01*
X-127900Y472267D01*
X-128483Y472017D01*
X-130567D01*
G01X-128483D02*
X-127233Y469600D01*
G01X-123300Y472933D02*
Y469600D01*
G01Y474267D02*
X-123467Y474350D01*
Y474517D01*
X-123300Y474600D01*
X-123133Y474517D01*
Y474350D01*
X-123300Y474267D01*
G01X-118867Y468350D02*
X-118283Y468017D01*
X-117617Y467933D01*
X-117033Y468017D01*
X-116533Y468433D01*
X-116200Y469017D01*
Y472933D01*
G01Y472267D02*
X-116533Y472600D01*
X-117033Y472850D01*
X-117617Y472933D01*
X-118283Y472767D01*
X-118700Y472433D01*
X-119033Y471850D01*
X-119200Y471267D01*
X-119117Y470767D01*
X-118783Y470183D01*
X-118283Y469767D01*
X-117617Y469600D01*
X-117117Y469683D01*
X-116533Y470017D01*
X-116200Y470350D01*
G01X-112100Y472933D02*
Y469600D01*
G01Y474267D02*
X-112267Y474350D01*
Y474517D01*
X-112100Y474600D01*
X-111933Y474517D01*
Y474350D01*
X-112100Y474267D01*
G01X-105000Y474600D02*
Y469600D01*
G01Y470350D02*
X-105333Y469933D01*
X-105833Y469683D01*
X-106417Y469600D01*
X-107083Y469767D01*
X-107583Y470183D01*
X-107917Y470683D01*
X-108000Y471267D01*
X-107917Y471850D01*
X-107583Y472350D01*
X-107083Y472767D01*
X-106417Y472933D01*
X-105833Y472850D01*
X-105417Y472683D01*
X-105000Y472350D01*
G01X-93800Y469600D02*
Y472933D01*
G01Y472350D02*
X-94133Y472683D01*
X-94633Y472850D01*
X-95217Y472933D01*
X-95800Y472767D01*
X-96300Y472433D01*
X-96633Y471933D01*
X-96800Y471267D01*
X-96633Y470600D01*
X-96300Y470100D01*
X-95800Y469767D01*
X-95217Y469600D01*
X-94633Y469683D01*
X-94133Y469933D01*
X-93800Y470267D01*
G01X-91117Y469600D02*
Y472933D01*
G01Y472100D02*
X-90783Y472517D01*
X-90283Y472850D01*
X-89617Y472933D01*
X-89033Y472850D01*
X-88533Y472517D01*
X-88283Y471933D01*
Y469600D01*
G01X-82600Y474600D02*
Y469600D01*
G01Y470350D02*
X-82933Y469933D01*
X-83433Y469683D01*
X-84017Y469600D01*
X-84683Y469767D01*
X-85183Y470183D01*
X-85517Y470683D01*
X-85600Y471267D01*
X-85517Y471850D01*
X-85183Y472350D01*
X-84683Y472767D01*
X-84017Y472933D01*
X-83433Y472850D01*
X-83017Y472683D01*
X-82600Y472350D01*
G01X-75067Y469600D02*
Y474600D01*
X-72900Y470433D01*
X-70733Y474600D01*
Y469600D01*
G01X-68717Y472933D02*
Y470600D01*
X-68383Y470017D01*
X-67883Y469683D01*
X-67300Y469600D01*
X-66717Y469683D01*
X-66217Y470017D01*
X-65883Y470600D01*
G01Y469600D02*
Y472933D01*
G01X-61700Y469600D02*
Y474600D01*
G01X-56100D02*
Y469600D01*
G01X-57267Y472933D02*
X-54933D01*
G01X-50500D02*
Y469600D01*
G01Y474267D02*
X-50667Y474350D01*
Y474517D01*
X-50500Y474600D01*
X-50333Y474517D01*
Y474350D01*
X-50500Y474267D01*
G01X-44900Y469600D02*
Y474600D01*
G01X-37800Y469600D02*
Y472933D01*
G01Y472350D02*
X-38133Y472683D01*
X-38633Y472850D01*
X-39217Y472933D01*
X-39800Y472767D01*
X-40300Y472433D01*
X-40633Y471933D01*
X-40800Y471267D01*
X-40633Y470600D01*
X-40300Y470100D01*
X-39800Y469767D01*
X-39217Y469600D01*
X-38633Y469683D01*
X-38133Y469933D01*
X-37800Y470267D01*
G01X-35450Y468100D02*
X-34950Y467933D01*
X-34283Y468100D01*
X-33867Y468433D01*
X-33533Y468850D01*
X-33033Y470183D01*
X-31950Y472933D01*
G01X-34617D02*
X-33033Y470183D01*
G01X-29350Y471850D02*
X-26683D01*
X-26933Y472433D01*
X-27350Y472767D01*
X-27933Y472933D01*
X-28517Y472850D01*
X-29017Y472600D01*
X-29350Y472017D01*
X-29517Y471517D01*
Y471017D01*
X-29350Y470517D01*
X-28933Y470017D01*
X-28433Y469683D01*
X-27850Y469600D01*
X-27267Y469767D01*
X-26683Y470267D01*
G01X-23667Y469600D02*
Y472933D01*
G01Y472267D02*
X-23250Y472600D01*
X-22833Y472850D01*
X-22250Y472933D01*
X-21833Y472850D01*
X-21333Y472600D01*
G01X-12967Y469600D02*
Y474600D01*
X-10967D01*
X-10300Y474350D01*
X-9800Y473767D01*
X-9633Y473100D01*
X-9800Y472433D01*
X-10217Y471933D01*
X-10967Y471683D01*
X-12967D01*
G01X-6867Y469600D02*
Y472933D01*
G01Y472267D02*
X-6450Y472600D01*
X-6033Y472850D01*
X-5450Y472933D01*
X-5033Y472850D01*
X-4533Y472600D01*
G01X-100Y472933D02*
Y469600D01*
G01Y474267D02*
X-267Y474350D01*
Y474517D01*
X-100Y474600D01*
X67Y474517D01*
Y474350D01*
X-100Y474267D01*
G01X4083Y469600D02*
Y472933D01*
G01Y472100D02*
X4417Y472517D01*
X4917Y472850D01*
X5583Y472933D01*
X6167Y472850D01*
X6667Y472517D01*
X6917Y471933D01*
Y469600D01*
G01X11100Y474600D02*
Y469600D01*
G01X9933Y472933D02*
X12267D01*
G01X15450Y471850D02*
X18117D01*
X17867Y472433D01*
X17450Y472767D01*
X16867Y472933D01*
X16283Y472850D01*
X15783Y472600D01*
X15450Y472017D01*
X15283Y471517D01*
Y471017D01*
X15450Y470517D01*
X15867Y470017D01*
X16367Y469683D01*
X16950Y469600D01*
X17533Y469767D01*
X18117Y470267D01*
G01X23800Y474600D02*
Y469600D01*
G01Y470350D02*
X23467Y469933D01*
X22967Y469683D01*
X22383Y469600D01*
X21717Y469767D01*
X21217Y470183D01*
X20883Y470683D01*
X20800Y471267D01*
X20883Y471850D01*
X21217Y472350D01*
X21717Y472767D01*
X22383Y472933D01*
X22967Y472850D01*
X23383Y472683D01*
X23800Y472350D01*
G01X34167Y472267D02*
X34500Y472517D01*
X34750Y472933D01*
X34917Y473517D01*
X34750Y474017D01*
X34417Y474350D01*
X33833Y474600D01*
X31583D01*
Y469600D01*
X34333D01*
X34917Y469933D01*
X35250Y470433D01*
X35417Y471017D01*
X35250Y471600D01*
X34750Y472100D01*
X34167Y472267D01*
X31583D01*
G01X39100Y469600D02*
X38600Y469683D01*
X38100Y470017D01*
X37767Y470600D01*
X37600Y471267D01*
X37767Y471933D01*
X38100Y472517D01*
X38600Y472850D01*
X39100Y472933D01*
X39600Y472850D01*
X40100Y472517D01*
X40433Y471933D01*
X40517Y471267D01*
X40433Y470600D01*
X40100Y470017D01*
X39600Y469683D01*
X39100Y469600D01*
G01X46200D02*
Y472933D01*
G01Y472350D02*
X45867Y472683D01*
X45367Y472850D01*
X44783Y472933D01*
X44200Y472767D01*
X43700Y472433D01*
X43367Y471933D01*
X43200Y471267D01*
X43367Y470600D01*
X43700Y470100D01*
X44200Y469767D01*
X44783Y469600D01*
X45367Y469683D01*
X45867Y469933D01*
X46200Y470267D01*
G01X49133Y469600D02*
Y472933D01*
G01Y472267D02*
X49550Y472600D01*
X49967Y472850D01*
X50550Y472933D01*
X50967Y472850D01*
X51467Y472600D01*
G01X57400Y474600D02*
Y469600D01*
G01Y470350D02*
X57067Y469933D01*
X56567Y469683D01*
X55983Y469600D01*
X55317Y469767D01*
X54817Y470183D01*
X54483Y470683D01*
X54400Y471267D01*
X54483Y471850D01*
X54817Y472350D01*
X55317Y472767D01*
X55983Y472933D01*
X56567Y472850D01*
X56983Y472683D01*
X57400Y472350D01*
G01X60250Y470183D02*
X60667Y469850D01*
X61250Y469600D01*
X61750D01*
X62250Y469767D01*
X62583Y470017D01*
X62750Y470350D01*
X62667Y470850D01*
X62333Y471100D01*
X60833Y471600D01*
X60500Y472183D01*
X60667Y472600D01*
X61000Y472850D01*
X61500Y472933D01*
X62000Y472850D01*
X62500Y472600D01*
G01X-387500Y483600D02*
X-385500D01*
G01X-386500D02*
Y478600D01*
G01X-387500D02*
X-385500D01*
G01X-382567D02*
Y483600D01*
X-380567D01*
X-379900Y483350D01*
X-379400Y482767D01*
X-379233Y482100D01*
X-379400Y481433D01*
X-379817Y480933D01*
X-380567Y480683D01*
X-382567D01*
G01X-373467Y483183D02*
X-373967Y483433D01*
X-374550Y483600D01*
X-375217D01*
X-375967Y483350D01*
X-376550Y482933D01*
X-376967Y482433D01*
X-377300Y481600D01*
X-377383Y480850D01*
X-377217Y480100D01*
X-376967Y479600D01*
X-376467Y479100D01*
X-375883Y478767D01*
X-375300Y478600D01*
X-374717D01*
X-374133Y478767D01*
X-373633Y479017D01*
X-373217Y479350D01*
G01X-370783Y480267D02*
X-368617D01*
G01X-364100Y483600D02*
Y478600D01*
G01X-366017Y483600D02*
X-362183D01*
G01X-360667Y478600D02*
Y483600D01*
X-358500Y479433D01*
X-356333Y483600D01*
Y478600D01*
G01X-353983Y480267D02*
X-351817D01*
G01X-348883Y480683D02*
X-348300Y481267D01*
X-347800Y481600D01*
X-347133Y481767D01*
X-346550Y481600D01*
X-346133Y481267D01*
X-345800Y480767D01*
X-345717Y480183D01*
X-345800Y479683D01*
X-346133Y479183D01*
X-346633Y478767D01*
X-347217Y478600D01*
X-347883Y478767D01*
X-348467Y479267D01*
X-348800Y480017D01*
X-348883Y480850D01*
X-348717Y481933D01*
X-348467Y482517D01*
X-348050Y483100D01*
X-347467Y483517D01*
X-346883Y483600D01*
X-346300Y483433D01*
X-345883Y483017D01*
G01X-343533Y479350D02*
X-343033Y478933D01*
X-342450Y478683D01*
X-341700Y478600D01*
X-340950Y478767D01*
X-340367Y479100D01*
X-339950Y479683D01*
X-339867Y480350D01*
X-340033Y481017D01*
X-340450Y481433D01*
X-341033Y481767D01*
X-341617Y481850D01*
X-342200Y481767D01*
X-342950Y481433D01*
X-342700Y483600D01*
X-340450D01*
G01X-336100D02*
X-336767Y483433D01*
X-337267Y483017D01*
X-337600Y482517D01*
X-337850Y481850D01*
X-337933Y481100D01*
X-337850Y480350D01*
X-337600Y479683D01*
X-337267Y479183D01*
X-336767Y478767D01*
X-336100Y478600D01*
X-335433Y478767D01*
X-334933Y479183D01*
X-334600Y479683D01*
X-334350Y480350D01*
X-334267Y481100D01*
X-334350Y481850D01*
X-334600Y482517D01*
X-334933Y483017D01*
X-335433Y483433D01*
X-336100Y483600D01*
G01X-324900D02*
Y478600D01*
G01X-326817Y483600D02*
X-322983D01*
G01X-320550Y480850D02*
X-317883D01*
X-318133Y481433D01*
X-318550Y481767D01*
X-319133Y481933D01*
X-319717Y481850D01*
X-320217Y481600D01*
X-320550Y481017D01*
X-320717Y480517D01*
Y480017D01*
X-320550Y479517D01*
X-320133Y479017D01*
X-319633Y478683D01*
X-319050Y478600D01*
X-318467Y478767D01*
X-317883Y479267D01*
G01X-314950Y479183D02*
X-314533Y478850D01*
X-313950Y478600D01*
X-313450D01*
X-312950Y478767D01*
X-312617Y479017D01*
X-312450Y479350D01*
X-312533Y479850D01*
X-312867Y480100D01*
X-314367Y480600D01*
X-314700Y481183D01*
X-314533Y481600D01*
X-314200Y481850D01*
X-313700Y481933D01*
X-313200Y481850D01*
X-312700Y481600D01*
G01X-308100Y483600D02*
Y478600D01*
G01X-309267Y481933D02*
X-306933D01*
G01X-299067Y478600D02*
Y483600D01*
X-296900Y479433D01*
X-294733Y483600D01*
Y478600D01*
G01X-292550Y480850D02*
X-289883D01*
X-290133Y481433D01*
X-290550Y481767D01*
X-291133Y481933D01*
X-291717Y481850D01*
X-292217Y481600D01*
X-292550Y481017D01*
X-292717Y480517D01*
Y480017D01*
X-292550Y479517D01*
X-292133Y479017D01*
X-291633Y478683D01*
X-291050Y478600D01*
X-290467Y478767D01*
X-289883Y479267D01*
G01X-285700Y483600D02*
Y478600D01*
G01X-286867Y481933D02*
X-284533D01*
G01X-281517Y478600D02*
Y483600D01*
G01Y481183D02*
X-281100Y481600D01*
X-280683Y481850D01*
X-280017Y481933D01*
X-279517Y481850D01*
X-278933Y481517D01*
X-278683Y481017D01*
Y478600D01*
G01X-274500D02*
X-275000Y478683D01*
X-275500Y479017D01*
X-275833Y479600D01*
X-276000Y480267D01*
X-275833Y480933D01*
X-275500Y481517D01*
X-275000Y481850D01*
X-274500Y481933D01*
X-274000Y481850D01*
X-273500Y481517D01*
X-273167Y480933D01*
X-273083Y480267D01*
X-273167Y479600D01*
X-273500Y479017D01*
X-274000Y478683D01*
X-274500Y478600D01*
G01X-267400Y483600D02*
Y478600D01*
G01Y479350D02*
X-267733Y478933D01*
X-268233Y478683D01*
X-268817Y478600D01*
X-269483Y478767D01*
X-269983Y479183D01*
X-270317Y479683D01*
X-270400Y480267D01*
X-270317Y480850D01*
X-269983Y481350D01*
X-269483Y481767D01*
X-268817Y481933D01*
X-268233Y481850D01*
X-267817Y481683D01*
X-267400Y481350D01*
G01X-264550Y479183D02*
X-264133Y478850D01*
X-263550Y478600D01*
X-263050D01*
X-262550Y478767D01*
X-262217Y479017D01*
X-262050Y479350D01*
X-262133Y479850D01*
X-262467Y480100D01*
X-263967Y480600D01*
X-264300Y481183D01*
X-264133Y481600D01*
X-263800Y481850D01*
X-263300Y481933D01*
X-262800Y481850D01*
X-262300Y481600D01*
G01X-254267Y478600D02*
Y483600D01*
X-252100Y479433D01*
X-249933Y483600D01*
Y478600D01*
G01X-245000D02*
Y481933D01*
G01Y481350D02*
X-245333Y481683D01*
X-245833Y481850D01*
X-246417Y481933D01*
X-247000Y481767D01*
X-247500Y481433D01*
X-247833Y480933D01*
X-248000Y480267D01*
X-247833Y479600D01*
X-247500Y479100D01*
X-247000Y478767D01*
X-246417Y478600D01*
X-245833Y478683D01*
X-245333Y478933D01*
X-245000Y479267D01*
G01X-242317Y478600D02*
Y481933D01*
G01Y481100D02*
X-241983Y481517D01*
X-241483Y481850D01*
X-240817Y481933D01*
X-240233Y481850D01*
X-239733Y481517D01*
X-239483Y480933D01*
Y478600D01*
G01X-236717Y481933D02*
Y479600D01*
X-236383Y479017D01*
X-235883Y478683D01*
X-235300Y478600D01*
X-234717Y478683D01*
X-234217Y479017D01*
X-233883Y479600D01*
G01Y478600D02*
Y481933D01*
G01X-228200Y478600D02*
Y481933D01*
G01Y481350D02*
X-228533Y481683D01*
X-229033Y481850D01*
X-229617Y481933D01*
X-230200Y481767D01*
X-230700Y481433D01*
X-231033Y480933D01*
X-231200Y480267D01*
X-231033Y479600D01*
X-230700Y479100D01*
X-230200Y478767D01*
X-229617Y478600D01*
X-229033Y478683D01*
X-228533Y478933D01*
X-228200Y479267D01*
G01X-224100Y478600D02*
Y483600D01*
G01X-387500Y492600D02*
X-385500D01*
G01X-386500D02*
Y487600D01*
G01X-387500D02*
X-385500D01*
G01X-382567D02*
Y492600D01*
X-380567D01*
X-379900Y492350D01*
X-379400Y491767D01*
X-379233Y491100D01*
X-379400Y490433D01*
X-379817Y489933D01*
X-380567Y489683D01*
X-382567D01*
G01X-373467Y492183D02*
X-373967Y492433D01*
X-374550Y492600D01*
X-375217D01*
X-375967Y492350D01*
X-376550Y491933D01*
X-376967Y491433D01*
X-377300Y490600D01*
X-377383Y489850D01*
X-377217Y489100D01*
X-376967Y488600D01*
X-376467Y488100D01*
X-375883Y487767D01*
X-375300Y487600D01*
X-374717D01*
X-374133Y487767D01*
X-373633Y488017D01*
X-373217Y488350D01*
G01X-370783Y489267D02*
X-368617D01*
G01X-365683Y489683D02*
X-365100Y490267D01*
X-364600Y490600D01*
X-363933Y490767D01*
X-363350Y490600D01*
X-362933Y490267D01*
X-362600Y489767D01*
X-362517Y489183D01*
X-362600Y488683D01*
X-362933Y488183D01*
X-363433Y487767D01*
X-364017Y487600D01*
X-364683Y487767D01*
X-365267Y488267D01*
X-365600Y489017D01*
X-365683Y489850D01*
X-365517Y490933D01*
X-365267Y491517D01*
X-364850Y492100D01*
X-364267Y492517D01*
X-363683Y492600D01*
X-363100Y492433D01*
X-362683Y492017D01*
G01X-358500Y492600D02*
X-359167Y492433D01*
X-359667Y492017D01*
X-360000Y491517D01*
X-360250Y490850D01*
X-360333Y490100D01*
X-360250Y489350D01*
X-360000Y488683D01*
X-359667Y488183D01*
X-359167Y487767D01*
X-358500Y487600D01*
X-357833Y487767D01*
X-357333Y488183D01*
X-357000Y488683D01*
X-356750Y489350D01*
X-356667Y490100D01*
X-356750Y490850D01*
X-357000Y491517D01*
X-357333Y492017D01*
X-357833Y492433D01*
X-358500Y492600D01*
G01X-352900Y487600D02*
Y492600D01*
X-353900Y491600D01*
G01Y487600D02*
X-351900D01*
G01X-348883Y489683D02*
X-348300Y490267D01*
X-347800Y490600D01*
X-347133Y490767D01*
X-346550Y490600D01*
X-346133Y490267D01*
X-345800Y489767D01*
X-345717Y489183D01*
X-345800Y488683D01*
X-346133Y488183D01*
X-346633Y487767D01*
X-347217Y487600D01*
X-347883Y487767D01*
X-348467Y488267D01*
X-348800Y489017D01*
X-348883Y489850D01*
X-348717Y490933D01*
X-348467Y491517D01*
X-348050Y492100D01*
X-347467Y492517D01*
X-346883Y492600D01*
X-346300Y492433D01*
X-345883Y492017D01*
G01X-336100Y487600D02*
X-336767Y487683D01*
X-337350Y488017D01*
X-337850Y488517D01*
X-338183Y489100D01*
X-338350Y489767D01*
Y490433D01*
X-338183Y491100D01*
X-337850Y491683D01*
X-337350Y492183D01*
X-336767Y492517D01*
X-336100Y492600D01*
X-335433Y492517D01*
X-334850Y492183D01*
X-334350Y491683D01*
X-334017Y491100D01*
X-333850Y490433D01*
Y489767D01*
X-334017Y489100D01*
X-334350Y488517D01*
X-334850Y488017D01*
X-335433Y487683D01*
X-336100Y487600D01*
G01X-335433Y488933D02*
X-334433Y487600D01*
G01X-331917Y490933D02*
Y488600D01*
X-331583Y488017D01*
X-331083Y487683D01*
X-330500Y487600D01*
X-329917Y487683D01*
X-329417Y488017D01*
X-329083Y488600D01*
G01Y487600D02*
Y490933D01*
G01X-323400Y487600D02*
Y490933D01*
G01Y490350D02*
X-323733Y490683D01*
X-324233Y490850D01*
X-324817Y490933D01*
X-325400Y490767D01*
X-325900Y490433D01*
X-326233Y489933D01*
X-326400Y489267D01*
X-326233Y488600D01*
X-325900Y488100D01*
X-325400Y487767D01*
X-324817Y487600D01*
X-324233Y487683D01*
X-323733Y487933D01*
X-323400Y488267D01*
G01X-319300Y487600D02*
Y492600D01*
G01X-313700Y490933D02*
Y487600D01*
G01Y492267D02*
X-313867Y492350D01*
Y492517D01*
X-313700Y492600D01*
X-313533Y492517D01*
Y492350D01*
X-313700Y492267D01*
G01X-308600Y487600D02*
Y491850D01*
X-308433Y492267D01*
X-308100Y492517D01*
X-307600Y492600D01*
X-307100Y492433D01*
X-306850Y492017D01*
G01X-307850Y490600D02*
X-309517D01*
G01X-302500Y490933D02*
Y487600D01*
G01Y492267D02*
X-302667Y492350D01*
Y492517D01*
X-302500Y492600D01*
X-302333Y492517D01*
Y492350D01*
X-302500Y492267D01*
G01X-295567Y490517D02*
X-296150Y490850D01*
X-296650Y490933D01*
X-297317Y490767D01*
X-297817Y490433D01*
X-298150Y489850D01*
X-298233Y489267D01*
X-298150Y488683D01*
X-297817Y488183D01*
X-297317Y487767D01*
X-296650Y487600D01*
X-296067Y487767D01*
X-295567Y488100D01*
G01X-289800Y487600D02*
Y490933D01*
G01Y490350D02*
X-290133Y490683D01*
X-290633Y490850D01*
X-291217Y490933D01*
X-291800Y490767D01*
X-292300Y490433D01*
X-292633Y489933D01*
X-292800Y489267D01*
X-292633Y488600D01*
X-292300Y488100D01*
X-291800Y487767D01*
X-291217Y487600D01*
X-290633Y487683D01*
X-290133Y487933D01*
X-289800Y488267D01*
G01X-285700Y492600D02*
Y487600D01*
G01X-286867Y490933D02*
X-284533D01*
G01X-280100D02*
Y487600D01*
G01Y492267D02*
X-280267Y492350D01*
Y492517D01*
X-280100Y492600D01*
X-279933Y492517D01*
Y492350D01*
X-280100Y492267D01*
G01X-274500Y487600D02*
X-275000Y487683D01*
X-275500Y488017D01*
X-275833Y488600D01*
X-276000Y489267D01*
X-275833Y489933D01*
X-275500Y490517D01*
X-275000Y490850D01*
X-274500Y490933D01*
X-274000Y490850D01*
X-273500Y490517D01*
X-273167Y489933D01*
X-273083Y489267D01*
X-273167Y488600D01*
X-273500Y488017D01*
X-274000Y487683D01*
X-274500Y487600D01*
G01X-270317D02*
Y490933D01*
G01Y490100D02*
X-269983Y490517D01*
X-269483Y490850D01*
X-268817Y490933D01*
X-268233Y490850D01*
X-267733Y490517D01*
X-267483Y489933D01*
Y487600D01*
G01X-255200Y485933D02*
X-259367Y490933D01*
Y491767D01*
X-258533Y492600D01*
X-257700D01*
X-256867Y491767D01*
Y490933D01*
X-257700Y490100D01*
X-259367Y489267D01*
X-260200Y488433D01*
Y486767D01*
X-259367Y485933D01*
X-256867D01*
X-255200Y487600D01*
G01X-248167D02*
Y492600D01*
X-246167D01*
X-245500Y492350D01*
X-245000Y491767D01*
X-244833Y491100D01*
X-245000Y490433D01*
X-245417Y489933D01*
X-246167Y489683D01*
X-248167D01*
G01X-242150Y489850D02*
X-239483D01*
X-239733Y490433D01*
X-240150Y490767D01*
X-240733Y490933D01*
X-241317Y490850D01*
X-241817Y490600D01*
X-242150Y490017D01*
X-242317Y489517D01*
Y489017D01*
X-242150Y488517D01*
X-241733Y488017D01*
X-241233Y487683D01*
X-240650Y487600D01*
X-240067Y487767D01*
X-239483Y488267D01*
G01X-236467Y487600D02*
Y490933D01*
G01Y490267D02*
X-236050Y490600D01*
X-235633Y490850D01*
X-235050Y490933D01*
X-234633Y490850D01*
X-234133Y490600D01*
G01X-230200Y487600D02*
Y491850D01*
X-230033Y492267D01*
X-229700Y492517D01*
X-229200Y492600D01*
X-228700Y492433D01*
X-228450Y492017D01*
G01X-229450Y490600D02*
X-231117D01*
G01X-224100Y487600D02*
X-224600Y487683D01*
X-225100Y488017D01*
X-225433Y488600D01*
X-225600Y489267D01*
X-225433Y489933D01*
X-225100Y490517D01*
X-224600Y490850D01*
X-224100Y490933D01*
X-223600Y490850D01*
X-223100Y490517D01*
X-222767Y489933D01*
X-222683Y489267D01*
X-222767Y488600D01*
X-223100Y488017D01*
X-223600Y487683D01*
X-224100Y487600D01*
G01X-219667D02*
Y490933D01*
G01Y490267D02*
X-219250Y490600D01*
X-218833Y490850D01*
X-218250Y490933D01*
X-217833Y490850D01*
X-217333Y490600D01*
G01X-215400Y487600D02*
Y490933D01*
G01Y490017D02*
X-215150Y490433D01*
X-214733Y490767D01*
X-214150Y490933D01*
X-213567Y490767D01*
X-213150Y490433D01*
X-212900Y490017D01*
Y487600D01*
G01Y490017D02*
X-212650Y490433D01*
X-212233Y490767D01*
X-211650Y490933D01*
X-211067Y490767D01*
X-210650Y490433D01*
X-210400Y489933D01*
Y487600D01*
G01X-205800D02*
Y490933D01*
G01Y490350D02*
X-206133Y490683D01*
X-206633Y490850D01*
X-207217Y490933D01*
X-207800Y490767D01*
X-208300Y490433D01*
X-208633Y489933D01*
X-208800Y489267D01*
X-208633Y488600D01*
X-208300Y488100D01*
X-207800Y487767D01*
X-207217Y487600D01*
X-206633Y487683D01*
X-206133Y487933D01*
X-205800Y488267D01*
G01X-203117Y487600D02*
Y490933D01*
G01Y490100D02*
X-202783Y490517D01*
X-202283Y490850D01*
X-201617Y490933D01*
X-201033Y490850D01*
X-200533Y490517D01*
X-200283Y489933D01*
Y487600D01*
G01X-194767Y490517D02*
X-195350Y490850D01*
X-195850Y490933D01*
X-196517Y490767D01*
X-197017Y490433D01*
X-197350Y489850D01*
X-197433Y489267D01*
X-197350Y488683D01*
X-197017Y488183D01*
X-196517Y487767D01*
X-195850Y487600D01*
X-195267Y487767D01*
X-194767Y488100D01*
G01X-191750Y489850D02*
X-189083D01*
X-189333Y490433D01*
X-189750Y490767D01*
X-190333Y490933D01*
X-190917Y490850D01*
X-191417Y490600D01*
X-191750Y490017D01*
X-191917Y489517D01*
Y489017D01*
X-191750Y488517D01*
X-191333Y488017D01*
X-190833Y487683D01*
X-190250Y487600D01*
X-189667Y487767D01*
X-189083Y488267D01*
G01X-181050D02*
X-180383Y487850D01*
X-179633Y487600D01*
X-178967D01*
X-178300Y487850D01*
X-177800Y488267D01*
X-177550Y488850D01*
X-177717Y489433D01*
X-178133Y489933D01*
X-178883Y490267D01*
X-179883Y490433D01*
X-180467Y490767D01*
X-180717Y491350D01*
X-180550Y491933D01*
X-180133Y492350D01*
X-179550Y492600D01*
X-178967D01*
X-178383Y492433D01*
X-177883Y492017D01*
G01X-175200Y485933D02*
Y490933D01*
G01Y490183D02*
X-174783Y490600D01*
X-174367Y490850D01*
X-173700Y490933D01*
X-173117Y490850D01*
X-172533Y490433D01*
X-172283Y489850D01*
X-172200Y489267D01*
X-172283Y488683D01*
X-172533Y488100D01*
X-173033Y487767D01*
X-173700Y487600D01*
X-174283Y487683D01*
X-174867Y487933D01*
X-175200Y488267D01*
G01X-169350Y489850D02*
X-166683D01*
X-166933Y490433D01*
X-167350Y490767D01*
X-167933Y490933D01*
X-168517Y490850D01*
X-169017Y490600D01*
X-169350Y490017D01*
X-169517Y489517D01*
Y489017D01*
X-169350Y488517D01*
X-168933Y488017D01*
X-168433Y487683D01*
X-167850Y487600D01*
X-167267Y487767D01*
X-166683Y488267D01*
G01X-161167Y490517D02*
X-161750Y490850D01*
X-162250Y490933D01*
X-162917Y490767D01*
X-163417Y490433D01*
X-163750Y489850D01*
X-163833Y489267D01*
X-163750Y488683D01*
X-163417Y488183D01*
X-162917Y487767D01*
X-162250Y487600D01*
X-161667Y487767D01*
X-161167Y488100D01*
G01X-156900Y490933D02*
Y487600D01*
G01Y492267D02*
X-157067Y492350D01*
Y492517D01*
X-156900Y492600D01*
X-156733Y492517D01*
Y492350D01*
X-156900Y492267D01*
G01X-151800Y487600D02*
Y491850D01*
X-151633Y492267D01*
X-151300Y492517D01*
X-150800Y492600D01*
X-150300Y492433D01*
X-150050Y492017D01*
G01X-151050Y490600D02*
X-152717D01*
G01X-145700Y490933D02*
Y487600D01*
G01Y492267D02*
X-145867Y492350D01*
Y492517D01*
X-145700Y492600D01*
X-145533Y492517D01*
Y492350D01*
X-145700Y492267D01*
G01X-138767Y490517D02*
X-139350Y490850D01*
X-139850Y490933D01*
X-140517Y490767D01*
X-141017Y490433D01*
X-141350Y489850D01*
X-141433Y489267D01*
X-141350Y488683D01*
X-141017Y488183D01*
X-140517Y487767D01*
X-139850Y487600D01*
X-139267Y487767D01*
X-138767Y488100D01*
G01X-133000Y487600D02*
Y490933D01*
G01Y490350D02*
X-133333Y490683D01*
X-133833Y490850D01*
X-134417Y490933D01*
X-135000Y490767D01*
X-135500Y490433D01*
X-135833Y489933D01*
X-136000Y489267D01*
X-135833Y488600D01*
X-135500Y488100D01*
X-135000Y487767D01*
X-134417Y487600D01*
X-133833Y487683D01*
X-133333Y487933D01*
X-133000Y488267D01*
G01X-128900Y492600D02*
Y487600D01*
G01X-130067Y490933D02*
X-127733D01*
G01X-123300D02*
Y487600D01*
G01Y492267D02*
X-123467Y492350D01*
Y492517D01*
X-123300Y492600D01*
X-123133Y492517D01*
Y492350D01*
X-123300Y492267D01*
G01X-117700Y487600D02*
X-118200Y487683D01*
X-118700Y488017D01*
X-119033Y488600D01*
X-119200Y489267D01*
X-119033Y489933D01*
X-118700Y490517D01*
X-118200Y490850D01*
X-117700Y490933D01*
X-117200Y490850D01*
X-116700Y490517D01*
X-116367Y489933D01*
X-116283Y489267D01*
X-116367Y488600D01*
X-116700Y488017D01*
X-117200Y487683D01*
X-117700Y487600D01*
G01X-113517D02*
Y490933D01*
G01Y490100D02*
X-113183Y490517D01*
X-112683Y490850D01*
X-112017Y490933D01*
X-111433Y490850D01*
X-110933Y490517D01*
X-110683Y489933D01*
Y487600D01*
G01X-101400D02*
Y491850D01*
X-101233Y492267D01*
X-100900Y492517D01*
X-100400Y492600D01*
X-99900Y492433D01*
X-99650Y492017D01*
G01X-100650Y490600D02*
X-102317D01*
G01X-95300Y487600D02*
X-95800Y487683D01*
X-96300Y488017D01*
X-96633Y488600D01*
X-96800Y489267D01*
X-96633Y489933D01*
X-96300Y490517D01*
X-95800Y490850D01*
X-95300Y490933D01*
X-94800Y490850D01*
X-94300Y490517D01*
X-93967Y489933D01*
X-93883Y489267D01*
X-93967Y488600D01*
X-94300Y488017D01*
X-94800Y487683D01*
X-95300Y487600D01*
G01X-90867D02*
Y490933D01*
G01Y490267D02*
X-90450Y490600D01*
X-90033Y490850D01*
X-89450Y490933D01*
X-89033Y490850D01*
X-88533Y490600D01*
G01X-80250Y487600D02*
Y492600D01*
G01X-76750D02*
Y487600D01*
G01Y490100D02*
X-80250D01*
G01X-72900Y490933D02*
Y487600D01*
G01Y492267D02*
X-73067Y492350D01*
Y492517D01*
X-72900Y492600D01*
X-72733Y492517D01*
Y492350D01*
X-72900Y492267D01*
G01X-68467Y486350D02*
X-67883Y486017D01*
X-67217Y485933D01*
X-66633Y486017D01*
X-66133Y486433D01*
X-65800Y487017D01*
Y490933D01*
G01Y490267D02*
X-66133Y490600D01*
X-66633Y490850D01*
X-67217Y490933D01*
X-67883Y490767D01*
X-68300Y490433D01*
X-68633Y489850D01*
X-68800Y489267D01*
X-68717Y488767D01*
X-68383Y488183D01*
X-67883Y487767D01*
X-67217Y487600D01*
X-66717Y487683D01*
X-66133Y488017D01*
X-65800Y488350D01*
G01X-63117Y487600D02*
Y492600D01*
G01Y490183D02*
X-62700Y490600D01*
X-62283Y490850D01*
X-61617Y490933D01*
X-61117Y490850D01*
X-60533Y490517D01*
X-60283Y490017D01*
Y487600D01*
G01X-52333D02*
Y492600D01*
X-50667D01*
X-50000Y492350D01*
X-49500Y492017D01*
X-49083Y491517D01*
X-48750Y490933D01*
X-48667Y490100D01*
X-48750Y489267D01*
X-49083Y488683D01*
X-49500Y488183D01*
X-50000Y487850D01*
X-50667Y487600D01*
X-52333D01*
G01X-46150Y489850D02*
X-43483D01*
X-43733Y490433D01*
X-44150Y490767D01*
X-44733Y490933D01*
X-45317Y490850D01*
X-45817Y490600D01*
X-46150Y490017D01*
X-46317Y489517D01*
Y489017D01*
X-46150Y488517D01*
X-45733Y488017D01*
X-45233Y487683D01*
X-44650Y487600D01*
X-44067Y487767D01*
X-43483Y488267D01*
G01X-40717Y487600D02*
Y490933D01*
G01Y490100D02*
X-40383Y490517D01*
X-39883Y490850D01*
X-39217Y490933D01*
X-38633Y490850D01*
X-38133Y490517D01*
X-37883Y489933D01*
Y487600D01*
G01X-34950Y488183D02*
X-34533Y487850D01*
X-33950Y487600D01*
X-33450D01*
X-32950Y487767D01*
X-32617Y488017D01*
X-32450Y488350D01*
X-32533Y488850D01*
X-32867Y489100D01*
X-34367Y489600D01*
X-34700Y490183D01*
X-34533Y490600D01*
X-34200Y490850D01*
X-33700Y490933D01*
X-33200Y490850D01*
X-32700Y490600D01*
G01X-28100Y490933D02*
Y487600D01*
G01Y492267D02*
X-28267Y492350D01*
Y492517D01*
X-28100Y492600D01*
X-27933Y492517D01*
Y492350D01*
X-28100Y492267D01*
G01X-22500Y492600D02*
Y487600D01*
G01X-23667Y490933D02*
X-21333D01*
G01X-18650Y486100D02*
X-18150Y485933D01*
X-17483Y486100D01*
X-17067Y486433D01*
X-16733Y486850D01*
X-16233Y488183D01*
X-15150Y490933D01*
G01X-17817D02*
X-16233Y488183D01*
G01X-6700Y492600D02*
X-4700D01*
G01X-5700D02*
Y487600D01*
G01X-6700D02*
X-4700D01*
G01X-1517D02*
Y490933D01*
G01Y490100D02*
X-1183Y490517D01*
X-683Y490850D01*
X-17Y490933D01*
X567Y490850D01*
X1067Y490517D01*
X1317Y489933D01*
Y487600D01*
G01X5500Y492600D02*
Y487600D01*
G01X4333Y490933D02*
X6667D01*
G01X9850Y489850D02*
X12517D01*
X12267Y490433D01*
X11850Y490767D01*
X11267Y490933D01*
X10683Y490850D01*
X10183Y490600D01*
X9850Y490017D01*
X9683Y489517D01*
Y489017D01*
X9850Y488517D01*
X10267Y488017D01*
X10767Y487683D01*
X11350Y487600D01*
X11933Y487767D01*
X12517Y488267D01*
G01X15533Y487600D02*
Y490933D01*
G01Y490267D02*
X15950Y490600D01*
X16367Y490850D01*
X16950Y490933D01*
X17367Y490850D01*
X17867Y490600D01*
G01X23633Y490517D02*
X23050Y490850D01*
X22550Y490933D01*
X21883Y490767D01*
X21383Y490433D01*
X21050Y489850D01*
X20967Y489267D01*
X21050Y488683D01*
X21383Y488183D01*
X21883Y487767D01*
X22550Y487600D01*
X23133Y487767D01*
X23633Y488100D01*
G01X27900Y487600D02*
X27400Y487683D01*
X26900Y488017D01*
X26567Y488600D01*
X26400Y489267D01*
X26567Y489933D01*
X26900Y490517D01*
X27400Y490850D01*
X27900Y490933D01*
X28400Y490850D01*
X28900Y490517D01*
X29233Y489933D01*
X29317Y489267D01*
X29233Y488600D01*
X28900Y488017D01*
X28400Y487683D01*
X27900Y487600D01*
G01X32083D02*
Y490933D01*
G01Y490100D02*
X32417Y490517D01*
X32917Y490850D01*
X33583Y490933D01*
X34167Y490850D01*
X34667Y490517D01*
X34917Y489933D01*
Y487600D01*
G01X37683D02*
Y490933D01*
G01Y490100D02*
X38017Y490517D01*
X38517Y490850D01*
X39183Y490933D01*
X39767Y490850D01*
X40267Y490517D01*
X40517Y489933D01*
Y487600D01*
G01X43450Y489850D02*
X46117D01*
X45867Y490433D01*
X45450Y490767D01*
X44867Y490933D01*
X44283Y490850D01*
X43783Y490600D01*
X43450Y490017D01*
X43283Y489517D01*
Y489017D01*
X43450Y488517D01*
X43867Y488017D01*
X44367Y487683D01*
X44950Y487600D01*
X45533Y487767D01*
X46117Y488267D01*
G01X51633Y490517D02*
X51050Y490850D01*
X50550Y490933D01*
X49883Y490767D01*
X49383Y490433D01*
X49050Y489850D01*
X48967Y489267D01*
X49050Y488683D01*
X49383Y488183D01*
X49883Y487767D01*
X50550Y487600D01*
X51133Y487767D01*
X51633Y488100D01*
G01X55900Y492600D02*
Y487600D01*
G01X54733Y490933D02*
X57067D01*
G01X61083Y485933D02*
X60250Y486767D01*
X59833Y487600D01*
Y490933D01*
X60250Y491767D01*
X61083Y492600D01*
G01X65350Y487600D02*
Y492600D01*
G01X68850D02*
Y487600D01*
G01Y490100D02*
X65350D01*
G01X70867Y487600D02*
Y492600D01*
X72533D01*
X73200Y492350D01*
X73700Y492017D01*
X74117Y491517D01*
X74450Y490933D01*
X74533Y490100D01*
X74450Y489267D01*
X74117Y488683D01*
X73700Y488183D01*
X73200Y487850D01*
X72533Y487600D01*
X70867D01*
G01X77300Y492600D02*
X79300D01*
G01X78300D02*
Y487600D01*
G01X77300D02*
X79300D01*
G01X84317Y485933D02*
X85150Y486767D01*
X85567Y487600D01*
Y490933D01*
X85150Y491767D01*
X84317Y492600D01*
G01X93433D02*
Y487600D01*
X96767D01*
G01X102200D02*
Y490933D01*
G01Y490350D02*
X101867Y490683D01*
X101367Y490850D01*
X100783Y490933D01*
X100200Y490767D01*
X99700Y490433D01*
X99367Y489933D01*
X99200Y489267D01*
X99367Y488600D01*
X99700Y488100D01*
X100200Y487767D01*
X100783Y487600D01*
X101367Y487683D01*
X101867Y487933D01*
X102200Y488267D01*
G01X104550Y486100D02*
X105050Y485933D01*
X105717Y486100D01*
X106133Y486433D01*
X106467Y486850D01*
X106967Y488183D01*
X108050Y490933D01*
G01X105383D02*
X106967Y488183D01*
G01X110650Y489850D02*
X113317D01*
X113067Y490433D01*
X112650Y490767D01*
X112067Y490933D01*
X111483Y490850D01*
X110983Y490600D01*
X110650Y490017D01*
X110483Y489517D01*
Y489017D01*
X110650Y488517D01*
X111067Y488017D01*
X111567Y487683D01*
X112150Y487600D01*
X112733Y487767D01*
X113317Y488267D01*
G01X116333Y487600D02*
Y490933D01*
G01Y490267D02*
X116750Y490600D01*
X117167Y490850D01*
X117750Y490933D01*
X118167Y490850D01*
X118667Y490600D01*
G01X121850Y488183D02*
X122267Y487850D01*
X122850Y487600D01*
X123350D01*
X123850Y487767D01*
X124183Y488017D01*
X124350Y488350D01*
X124267Y488850D01*
X123933Y489100D01*
X122433Y489600D01*
X122100Y490183D01*
X122267Y490600D01*
X122600Y490850D01*
X123100Y490933D01*
X123600Y490850D01*
X124100Y490600D01*
G01X134300Y487600D02*
X133800Y487683D01*
X133300Y488017D01*
X132967Y488600D01*
X132800Y489267D01*
X132967Y489933D01*
X133300Y490517D01*
X133800Y490850D01*
X134300Y490933D01*
X134800Y490850D01*
X135300Y490517D01*
X135633Y489933D01*
X135717Y489267D01*
X135633Y488600D01*
X135300Y488017D01*
X134800Y487683D01*
X134300Y487600D01*
G01X138733D02*
Y490933D01*
G01Y490267D02*
X139150Y490600D01*
X139567Y490850D01*
X140150Y490933D01*
X140567Y490850D01*
X141067Y490600D01*
G01X151767Y490267D02*
X152100Y490517D01*
X152350Y490933D01*
X152517Y491517D01*
X152350Y492017D01*
X152017Y492350D01*
X151433Y492600D01*
X149183D01*
Y487600D01*
X151933D01*
X152517Y487933D01*
X152850Y488433D01*
X153017Y489017D01*
X152850Y489600D01*
X152350Y490100D01*
X151767Y490267D01*
X149183D01*
G01X156700Y487600D02*
X156200Y487683D01*
X155700Y488017D01*
X155367Y488600D01*
X155200Y489267D01*
X155367Y489933D01*
X155700Y490517D01*
X156200Y490850D01*
X156700Y490933D01*
X157200Y490850D01*
X157700Y490517D01*
X158033Y489933D01*
X158117Y489267D01*
X158033Y488600D01*
X157700Y488017D01*
X157200Y487683D01*
X156700Y487600D01*
G01X163800D02*
Y490933D01*
G01Y490350D02*
X163467Y490683D01*
X162967Y490850D01*
X162383Y490933D01*
X161800Y490767D01*
X161300Y490433D01*
X160967Y489933D01*
X160800Y489267D01*
X160967Y488600D01*
X161300Y488100D01*
X161800Y487767D01*
X162383Y487600D01*
X162967Y487683D01*
X163467Y487933D01*
X163800Y488267D01*
G01X166733Y487600D02*
Y490933D01*
G01Y490267D02*
X167150Y490600D01*
X167567Y490850D01*
X168150Y490933D01*
X168567Y490850D01*
X169067Y490600D01*
G01X175000Y492600D02*
Y487600D01*
G01Y488350D02*
X174667Y487933D01*
X174167Y487683D01*
X173583Y487600D01*
X172917Y487767D01*
X172417Y488183D01*
X172083Y488683D01*
X172000Y489267D01*
X172083Y489850D01*
X172417Y490350D01*
X172917Y490767D01*
X173583Y490933D01*
X174167Y490850D01*
X174583Y490683D01*
X175000Y490350D01*
G01X177850Y488183D02*
X178267Y487850D01*
X178850Y487600D01*
X179350D01*
X179850Y487767D01*
X180183Y488017D01*
X180350Y488350D01*
X180267Y488850D01*
X179933Y489100D01*
X178433Y489600D01*
X178100Y490183D01*
X178267Y490600D01*
X178600Y490850D01*
X179100Y490933D01*
X179600Y490850D01*
X180100Y490600D01*
G01X185117Y485933D02*
X185950Y486767D01*
X186367Y487600D01*
Y490933D01*
X185950Y491767D01*
X185117Y492600D01*
G01X-387500Y501600D02*
X-385500D01*
G01X-386500D02*
Y496600D01*
G01X-387500D02*
X-385500D01*
G01X-382567D02*
Y501600D01*
X-380567D01*
X-379900Y501350D01*
X-379400Y500767D01*
X-379233Y500100D01*
X-379400Y499433D01*
X-379817Y498933D01*
X-380567Y498683D01*
X-382567D01*
G01X-373467Y501183D02*
X-373967Y501433D01*
X-374550Y501600D01*
X-375217D01*
X-375967Y501350D01*
X-376550Y500933D01*
X-376967Y500433D01*
X-377300Y499600D01*
X-377383Y498850D01*
X-377217Y498100D01*
X-376967Y497600D01*
X-376467Y497100D01*
X-375883Y496767D01*
X-375300Y496600D01*
X-374717D01*
X-374133Y496767D01*
X-373633Y497017D01*
X-373217Y497350D01*
G01X-370783Y498267D02*
X-368617D01*
G01X-365683Y498683D02*
X-365100Y499267D01*
X-364600Y499600D01*
X-363933Y499767D01*
X-363350Y499600D01*
X-362933Y499267D01*
X-362600Y498767D01*
X-362517Y498183D01*
X-362600Y497683D01*
X-362933Y497183D01*
X-363433Y496767D01*
X-364017Y496600D01*
X-364683Y496767D01*
X-365267Y497267D01*
X-365600Y498017D01*
X-365683Y498850D01*
X-365517Y499933D01*
X-365267Y500517D01*
X-364850Y501100D01*
X-364267Y501517D01*
X-363683Y501600D01*
X-363100Y501433D01*
X-362683Y501017D01*
G01X-358500Y501600D02*
X-359167Y501433D01*
X-359667Y501017D01*
X-360000Y500517D01*
X-360250Y499850D01*
X-360333Y499100D01*
X-360250Y498350D01*
X-360000Y497683D01*
X-359667Y497183D01*
X-359167Y496767D01*
X-358500Y496600D01*
X-357833Y496767D01*
X-357333Y497183D01*
X-357000Y497683D01*
X-356750Y498350D01*
X-356667Y499100D01*
X-356750Y499850D01*
X-357000Y500517D01*
X-357333Y501017D01*
X-357833Y501433D01*
X-358500Y501600D01*
G01X-352900Y496600D02*
Y501600D01*
X-353900Y500600D01*
G01Y496600D02*
X-351900D01*
G01X-348883Y500767D02*
X-348383Y501267D01*
X-347800Y501517D01*
X-347133Y501600D01*
X-346300Y501433D01*
X-345717Y501017D01*
X-345550Y500517D01*
X-345633Y500017D01*
X-345967Y499600D01*
X-347633Y498767D01*
X-348383Y498183D01*
X-348883Y497350D01*
X-349050Y496600D01*
X-345550D01*
G01X-336100D02*
X-336767Y496683D01*
X-337350Y497017D01*
X-337850Y497517D01*
X-338183Y498100D01*
X-338350Y498767D01*
Y499433D01*
X-338183Y500100D01*
X-337850Y500683D01*
X-337350Y501183D01*
X-336767Y501517D01*
X-336100Y501600D01*
X-335433Y501517D01*
X-334850Y501183D01*
X-334350Y500683D01*
X-334017Y500100D01*
X-333850Y499433D01*
Y498767D01*
X-334017Y498100D01*
X-334350Y497517D01*
X-334850Y497017D01*
X-335433Y496683D01*
X-336100Y496600D01*
G01X-335433Y497933D02*
X-334433Y496600D01*
G01X-331917Y499933D02*
Y497600D01*
X-331583Y497017D01*
X-331083Y496683D01*
X-330500Y496600D01*
X-329917Y496683D01*
X-329417Y497017D01*
X-329083Y497600D01*
G01Y496600D02*
Y499933D01*
G01X-323400Y496600D02*
Y499933D01*
G01Y499350D02*
X-323733Y499683D01*
X-324233Y499850D01*
X-324817Y499933D01*
X-325400Y499767D01*
X-325900Y499433D01*
X-326233Y498933D01*
X-326400Y498267D01*
X-326233Y497600D01*
X-325900Y497100D01*
X-325400Y496767D01*
X-324817Y496600D01*
X-324233Y496683D01*
X-323733Y496933D01*
X-323400Y497267D01*
G01X-319300Y496600D02*
Y501600D01*
G01X-313700Y499933D02*
Y496600D01*
G01Y501267D02*
X-313867Y501350D01*
Y501517D01*
X-313700Y501600D01*
X-313533Y501517D01*
Y501350D01*
X-313700Y501267D01*
G01X-308600Y496600D02*
Y500850D01*
X-308433Y501267D01*
X-308100Y501517D01*
X-307600Y501600D01*
X-307100Y501433D01*
X-306850Y501017D01*
G01X-307850Y499600D02*
X-309517D01*
G01X-302500Y499933D02*
Y496600D01*
G01Y501267D02*
X-302667Y501350D01*
Y501517D01*
X-302500Y501600D01*
X-302333Y501517D01*
Y501350D01*
X-302500Y501267D01*
G01X-295567Y499517D02*
X-296150Y499850D01*
X-296650Y499933D01*
X-297317Y499767D01*
X-297817Y499433D01*
X-298150Y498850D01*
X-298233Y498267D01*
X-298150Y497683D01*
X-297817Y497183D01*
X-297317Y496767D01*
X-296650Y496600D01*
X-296067Y496767D01*
X-295567Y497100D01*
G01X-289800Y496600D02*
Y499933D01*
G01Y499350D02*
X-290133Y499683D01*
X-290633Y499850D01*
X-291217Y499933D01*
X-291800Y499767D01*
X-292300Y499433D01*
X-292633Y498933D01*
X-292800Y498267D01*
X-292633Y497600D01*
X-292300Y497100D01*
X-291800Y496767D01*
X-291217Y496600D01*
X-290633Y496683D01*
X-290133Y496933D01*
X-289800Y497267D01*
G01X-285700Y501600D02*
Y496600D01*
G01X-286867Y499933D02*
X-284533D01*
G01X-280100D02*
Y496600D01*
G01Y501267D02*
X-280267Y501350D01*
Y501517D01*
X-280100Y501600D01*
X-279933Y501517D01*
Y501350D01*
X-280100Y501267D01*
G01X-274500Y496600D02*
X-275000Y496683D01*
X-275500Y497017D01*
X-275833Y497600D01*
X-276000Y498267D01*
X-275833Y498933D01*
X-275500Y499517D01*
X-275000Y499850D01*
X-274500Y499933D01*
X-274000Y499850D01*
X-273500Y499517D01*
X-273167Y498933D01*
X-273083Y498267D01*
X-273167Y497600D01*
X-273500Y497017D01*
X-274000Y496683D01*
X-274500Y496600D01*
G01X-270317D02*
Y499933D01*
G01Y499100D02*
X-269983Y499517D01*
X-269483Y499850D01*
X-268817Y499933D01*
X-268233Y499850D01*
X-267733Y499517D01*
X-267483Y498933D01*
Y496600D01*
G01X-256200D02*
Y499933D01*
G01Y499350D02*
X-256533Y499683D01*
X-257033Y499850D01*
X-257617Y499933D01*
X-258200Y499767D01*
X-258700Y499433D01*
X-259033Y498933D01*
X-259200Y498267D01*
X-259033Y497600D01*
X-258700Y497100D01*
X-258200Y496767D01*
X-257617Y496600D01*
X-257033Y496683D01*
X-256533Y496933D01*
X-256200Y497267D01*
G01X-253517Y496600D02*
Y499933D01*
G01Y499100D02*
X-253183Y499517D01*
X-252683Y499850D01*
X-252017Y499933D01*
X-251433Y499850D01*
X-250933Y499517D01*
X-250683Y498933D01*
Y496600D01*
G01X-245000Y501600D02*
Y496600D01*
G01Y497350D02*
X-245333Y496933D01*
X-245833Y496683D01*
X-246417Y496600D01*
X-247083Y496767D01*
X-247583Y497183D01*
X-247917Y497683D01*
X-248000Y498267D01*
X-247917Y498850D01*
X-247583Y499350D01*
X-247083Y499767D01*
X-246417Y499933D01*
X-245833Y499850D01*
X-245417Y499683D01*
X-245000Y499350D01*
G01X-236967Y496600D02*
Y501600D01*
X-234967D01*
X-234300Y501350D01*
X-233800Y500767D01*
X-233633Y500100D01*
X-233800Y499433D01*
X-234217Y498933D01*
X-234967Y498683D01*
X-236967D01*
G01X-230950Y498850D02*
X-228283D01*
X-228533Y499433D01*
X-228950Y499767D01*
X-229533Y499933D01*
X-230117Y499850D01*
X-230617Y499600D01*
X-230950Y499017D01*
X-231117Y498517D01*
Y498017D01*
X-230950Y497517D01*
X-230533Y497017D01*
X-230033Y496683D01*
X-229450Y496600D01*
X-228867Y496767D01*
X-228283Y497267D01*
G01X-225267Y496600D02*
Y499933D01*
G01Y499267D02*
X-224850Y499600D01*
X-224433Y499850D01*
X-223850Y499933D01*
X-223433Y499850D01*
X-222933Y499600D01*
G01X-219000Y496600D02*
Y500850D01*
X-218833Y501267D01*
X-218500Y501517D01*
X-218000Y501600D01*
X-217500Y501433D01*
X-217250Y501017D01*
G01X-218250Y499600D02*
X-219917D01*
G01X-212900Y496600D02*
X-213400Y496683D01*
X-213900Y497017D01*
X-214233Y497600D01*
X-214400Y498267D01*
X-214233Y498933D01*
X-213900Y499517D01*
X-213400Y499850D01*
X-212900Y499933D01*
X-212400Y499850D01*
X-211900Y499517D01*
X-211567Y498933D01*
X-211483Y498267D01*
X-211567Y497600D01*
X-211900Y497017D01*
X-212400Y496683D01*
X-212900Y496600D01*
G01X-208467D02*
Y499933D01*
G01Y499267D02*
X-208050Y499600D01*
X-207633Y499850D01*
X-207050Y499933D01*
X-206633Y499850D01*
X-206133Y499600D01*
G01X-204200Y496600D02*
Y499933D01*
G01Y499017D02*
X-203950Y499433D01*
X-203533Y499767D01*
X-202950Y499933D01*
X-202367Y499767D01*
X-201950Y499433D01*
X-201700Y499017D01*
Y496600D01*
G01Y499017D02*
X-201450Y499433D01*
X-201033Y499767D01*
X-200450Y499933D01*
X-199867Y499767D01*
X-199450Y499433D01*
X-199200Y498933D01*
Y496600D01*
G01X-194600D02*
Y499933D01*
G01Y499350D02*
X-194933Y499683D01*
X-195433Y499850D01*
X-196017Y499933D01*
X-196600Y499767D01*
X-197100Y499433D01*
X-197433Y498933D01*
X-197600Y498267D01*
X-197433Y497600D01*
X-197100Y497100D01*
X-196600Y496767D01*
X-196017Y496600D01*
X-195433Y496683D01*
X-194933Y496933D01*
X-194600Y497267D01*
G01X-191917Y496600D02*
Y499933D01*
G01Y499100D02*
X-191583Y499517D01*
X-191083Y499850D01*
X-190417Y499933D01*
X-189833Y499850D01*
X-189333Y499517D01*
X-189083Y498933D01*
Y496600D01*
G01X-183567Y499517D02*
X-184150Y499850D01*
X-184650Y499933D01*
X-185317Y499767D01*
X-185817Y499433D01*
X-186150Y498850D01*
X-186233Y498267D01*
X-186150Y497683D01*
X-185817Y497183D01*
X-185317Y496767D01*
X-184650Y496600D01*
X-184067Y496767D01*
X-183567Y497100D01*
G01X-180550Y498850D02*
X-177883D01*
X-178133Y499433D01*
X-178550Y499767D01*
X-179133Y499933D01*
X-179717Y499850D01*
X-180217Y499600D01*
X-180550Y499017D01*
X-180717Y498517D01*
Y498017D01*
X-180550Y497517D01*
X-180133Y497017D01*
X-179633Y496683D01*
X-179050Y496600D01*
X-178467Y496767D01*
X-177883Y497267D01*
G01X-169850D02*
X-169183Y496850D01*
X-168433Y496600D01*
X-167767D01*
X-167100Y496850D01*
X-166600Y497267D01*
X-166350Y497850D01*
X-166517Y498433D01*
X-166933Y498933D01*
X-167683Y499267D01*
X-168683Y499433D01*
X-169267Y499767D01*
X-169517Y500350D01*
X-169350Y500933D01*
X-168933Y501350D01*
X-168350Y501600D01*
X-167767D01*
X-167183Y501433D01*
X-166683Y501017D01*
G01X-164000Y494933D02*
Y499933D01*
G01Y499183D02*
X-163583Y499600D01*
X-163167Y499850D01*
X-162500Y499933D01*
X-161917Y499850D01*
X-161333Y499433D01*
X-161083Y498850D01*
X-161000Y498267D01*
X-161083Y497683D01*
X-161333Y497100D01*
X-161833Y496767D01*
X-162500Y496600D01*
X-163083Y496683D01*
X-163667Y496933D01*
X-164000Y497267D01*
G01X-158150Y498850D02*
X-155483D01*
X-155733Y499433D01*
X-156150Y499767D01*
X-156733Y499933D01*
X-157317Y499850D01*
X-157817Y499600D01*
X-158150Y499017D01*
X-158317Y498517D01*
Y498017D01*
X-158150Y497517D01*
X-157733Y497017D01*
X-157233Y496683D01*
X-156650Y496600D01*
X-156067Y496767D01*
X-155483Y497267D01*
G01X-149967Y499517D02*
X-150550Y499850D01*
X-151050Y499933D01*
X-151717Y499767D01*
X-152217Y499433D01*
X-152550Y498850D01*
X-152633Y498267D01*
X-152550Y497683D01*
X-152217Y497183D01*
X-151717Y496767D01*
X-151050Y496600D01*
X-150467Y496767D01*
X-149967Y497100D01*
G01X-145700Y499933D02*
Y496600D01*
G01Y501267D02*
X-145867Y501350D01*
Y501517D01*
X-145700Y501600D01*
X-145533Y501517D01*
Y501350D01*
X-145700Y501267D01*
G01X-140600Y496600D02*
Y500850D01*
X-140433Y501267D01*
X-140100Y501517D01*
X-139600Y501600D01*
X-139100Y501433D01*
X-138850Y501017D01*
G01X-139850Y499600D02*
X-141517D01*
G01X-134500Y499933D02*
Y496600D01*
G01Y501267D02*
X-134667Y501350D01*
Y501517D01*
X-134500Y501600D01*
X-134333Y501517D01*
Y501350D01*
X-134500Y501267D01*
G01X-127567Y499517D02*
X-128150Y499850D01*
X-128650Y499933D01*
X-129317Y499767D01*
X-129817Y499433D01*
X-130150Y498850D01*
X-130233Y498267D01*
X-130150Y497683D01*
X-129817Y497183D01*
X-129317Y496767D01*
X-128650Y496600D01*
X-128067Y496767D01*
X-127567Y497100D01*
G01X-121800Y496600D02*
Y499933D01*
G01Y499350D02*
X-122133Y499683D01*
X-122633Y499850D01*
X-123217Y499933D01*
X-123800Y499767D01*
X-124300Y499433D01*
X-124633Y498933D01*
X-124800Y498267D01*
X-124633Y497600D01*
X-124300Y497100D01*
X-123800Y496767D01*
X-123217Y496600D01*
X-122633Y496683D01*
X-122133Y496933D01*
X-121800Y497267D01*
G01X-117700Y501600D02*
Y496600D01*
G01X-118867Y499933D02*
X-116533D01*
G01X-112100D02*
Y496600D01*
G01Y501267D02*
X-112267Y501350D01*
Y501517D01*
X-112100Y501600D01*
X-111933Y501517D01*
Y501350D01*
X-112100Y501267D01*
G01X-106500Y496600D02*
X-107000Y496683D01*
X-107500Y497017D01*
X-107833Y497600D01*
X-108000Y498267D01*
X-107833Y498933D01*
X-107500Y499517D01*
X-107000Y499850D01*
X-106500Y499933D01*
X-106000Y499850D01*
X-105500Y499517D01*
X-105167Y498933D01*
X-105083Y498267D01*
X-105167Y497600D01*
X-105500Y497017D01*
X-106000Y496683D01*
X-106500Y496600D01*
G01X-102317D02*
Y499933D01*
G01Y499100D02*
X-101983Y499517D01*
X-101483Y499850D01*
X-100817Y499933D01*
X-100233Y499850D01*
X-99733Y499517D01*
X-99483Y498933D01*
Y496600D01*
G01X-90200D02*
Y500850D01*
X-90033Y501267D01*
X-89700Y501517D01*
X-89200Y501600D01*
X-88700Y501433D01*
X-88450Y501017D01*
G01X-89450Y499600D02*
X-91117D01*
G01X-84100Y496600D02*
X-84600Y496683D01*
X-85100Y497017D01*
X-85433Y497600D01*
X-85600Y498267D01*
X-85433Y498933D01*
X-85100Y499517D01*
X-84600Y499850D01*
X-84100Y499933D01*
X-83600Y499850D01*
X-83100Y499517D01*
X-82767Y498933D01*
X-82683Y498267D01*
X-82767Y497600D01*
X-83100Y497017D01*
X-83600Y496683D01*
X-84100Y496600D01*
G01X-79667D02*
Y499933D01*
G01Y499267D02*
X-79250Y499600D01*
X-78833Y499850D01*
X-78250Y499933D01*
X-77833Y499850D01*
X-77333Y499600D01*
G01X-68967Y496600D02*
Y501600D01*
X-66883D01*
X-66217Y501350D01*
X-65800Y501017D01*
X-65633Y500350D01*
X-65800Y499683D01*
X-66300Y499267D01*
X-66883Y499017D01*
X-68967D01*
G01X-66883D02*
X-65633Y496600D01*
G01X-61700Y499933D02*
Y496600D01*
G01Y501267D02*
X-61867Y501350D01*
Y501517D01*
X-61700Y501600D01*
X-61533Y501517D01*
Y501350D01*
X-61700Y501267D01*
G01X-57267Y495350D02*
X-56683Y495017D01*
X-56017Y494933D01*
X-55433Y495017D01*
X-54933Y495433D01*
X-54600Y496017D01*
Y499933D01*
G01Y499267D02*
X-54933Y499600D01*
X-55433Y499850D01*
X-56017Y499933D01*
X-56683Y499767D01*
X-57100Y499433D01*
X-57433Y498850D01*
X-57600Y498267D01*
X-57517Y497767D01*
X-57183Y497183D01*
X-56683Y496767D01*
X-56017Y496600D01*
X-55517Y496683D01*
X-54933Y497017D01*
X-54600Y497350D01*
G01X-50500Y499933D02*
Y496600D01*
G01Y501267D02*
X-50667Y501350D01*
Y501517D01*
X-50500Y501600D01*
X-50333Y501517D01*
Y501350D01*
X-50500Y501267D01*
G01X-43400Y501600D02*
Y496600D01*
G01Y497350D02*
X-43733Y496933D01*
X-44233Y496683D01*
X-44817Y496600D01*
X-45483Y496767D01*
X-45983Y497183D01*
X-46317Y497683D01*
X-46400Y498267D01*
X-46317Y498850D01*
X-45983Y499350D01*
X-45483Y499767D01*
X-44817Y499933D01*
X-44233Y499850D01*
X-43817Y499683D01*
X-43400Y499350D01*
G01X-35367Y496600D02*
Y501600D01*
X-33367D01*
X-32700Y501350D01*
X-32200Y500767D01*
X-32033Y500100D01*
X-32200Y499433D01*
X-32617Y498933D01*
X-33367Y498683D01*
X-35367D01*
G01X-29267Y496600D02*
Y499933D01*
G01Y499267D02*
X-28850Y499600D01*
X-28433Y499850D01*
X-27850Y499933D01*
X-27433Y499850D01*
X-26933Y499600D01*
G01X-22500Y499933D02*
Y496600D01*
G01Y501267D02*
X-22667Y501350D01*
Y501517D01*
X-22500Y501600D01*
X-22333Y501517D01*
Y501350D01*
X-22500Y501267D01*
G01X-18317Y496600D02*
Y499933D01*
G01Y499100D02*
X-17983Y499517D01*
X-17483Y499850D01*
X-16817Y499933D01*
X-16233Y499850D01*
X-15733Y499517D01*
X-15483Y498933D01*
Y496600D01*
G01X-11300Y501600D02*
Y496600D01*
G01X-12467Y499933D02*
X-10133D01*
G01X-6950Y498850D02*
X-4283D01*
X-4533Y499433D01*
X-4950Y499767D01*
X-5533Y499933D01*
X-6117Y499850D01*
X-6617Y499600D01*
X-6950Y499017D01*
X-7117Y498517D01*
Y498017D01*
X-6950Y497517D01*
X-6533Y497017D01*
X-6033Y496683D01*
X-5450Y496600D01*
X-4867Y496767D01*
X-4283Y497267D01*
G01X1400Y501600D02*
Y496600D01*
G01Y497350D02*
X1067Y496933D01*
X567Y496683D01*
X-17Y496600D01*
X-683Y496767D01*
X-1183Y497183D01*
X-1517Y497683D01*
X-1600Y498267D01*
X-1517Y498850D01*
X-1183Y499350D01*
X-683Y499767D01*
X-17Y499933D01*
X567Y499850D01*
X983Y499683D01*
X1400Y499350D01*
G01X11767Y499267D02*
X12100Y499517D01*
X12350Y499933D01*
X12517Y500517D01*
X12350Y501017D01*
X12017Y501350D01*
X11433Y501600D01*
X9183D01*
Y496600D01*
X11933D01*
X12517Y496933D01*
X12850Y497433D01*
X13017Y498017D01*
X12850Y498600D01*
X12350Y499100D01*
X11767Y499267D01*
X9183D01*
G01X16700Y496600D02*
X16200Y496683D01*
X15700Y497017D01*
X15367Y497600D01*
X15200Y498267D01*
X15367Y498933D01*
X15700Y499517D01*
X16200Y499850D01*
X16700Y499933D01*
X17200Y499850D01*
X17700Y499517D01*
X18033Y498933D01*
X18117Y498267D01*
X18033Y497600D01*
X17700Y497017D01*
X17200Y496683D01*
X16700Y496600D01*
G01X23800D02*
Y499933D01*
G01Y499350D02*
X23467Y499683D01*
X22967Y499850D01*
X22383Y499933D01*
X21800Y499767D01*
X21300Y499433D01*
X20967Y498933D01*
X20800Y498267D01*
X20967Y497600D01*
X21300Y497100D01*
X21800Y496767D01*
X22383Y496600D01*
X22967Y496683D01*
X23467Y496933D01*
X23800Y497267D01*
G01X26733Y496600D02*
Y499933D01*
G01Y499267D02*
X27150Y499600D01*
X27567Y499850D01*
X28150Y499933D01*
X28567Y499850D01*
X29067Y499600D01*
G01X35000Y501600D02*
Y496600D01*
G01Y497350D02*
X34667Y496933D01*
X34167Y496683D01*
X33583Y496600D01*
X32917Y496767D01*
X32417Y497183D01*
X32083Y497683D01*
X32000Y498267D01*
X32083Y498850D01*
X32417Y499350D01*
X32917Y499767D01*
X33583Y499933D01*
X34167Y499850D01*
X34583Y499683D01*
X35000Y499350D01*
G01X37850Y497183D02*
X38267Y496850D01*
X38850Y496600D01*
X39350D01*
X39850Y496767D01*
X40183Y497017D01*
X40350Y497350D01*
X40267Y497850D01*
X39933Y498100D01*
X38433Y498600D01*
X38100Y499183D01*
X38267Y499600D01*
X38600Y499850D01*
X39100Y499933D01*
X39600Y499850D01*
X40100Y499600D01*
G01X-387500Y510600D02*
X-385500D01*
G01X-386500D02*
Y505600D01*
G01X-387500D02*
X-385500D01*
G01X-382567D02*
Y510600D01*
X-380567D01*
X-379900Y510350D01*
X-379400Y509767D01*
X-379233Y509100D01*
X-379400Y508433D01*
X-379817Y507933D01*
X-380567Y507683D01*
X-382567D01*
G01X-373467Y510183D02*
X-373967Y510433D01*
X-374550Y510600D01*
X-375217D01*
X-375967Y510350D01*
X-376550Y509933D01*
X-376967Y509433D01*
X-377300Y508600D01*
X-377383Y507850D01*
X-377217Y507100D01*
X-376967Y506600D01*
X-376467Y506100D01*
X-375883Y505767D01*
X-375300Y505600D01*
X-374717D01*
X-374133Y505767D01*
X-373633Y506017D01*
X-373217Y506350D01*
G01X-370783Y507267D02*
X-368617D01*
G01X-365683Y507683D02*
X-365100Y508267D01*
X-364600Y508600D01*
X-363933Y508767D01*
X-363350Y508600D01*
X-362933Y508267D01*
X-362600Y507767D01*
X-362517Y507183D01*
X-362600Y506683D01*
X-362933Y506183D01*
X-363433Y505767D01*
X-364017Y505600D01*
X-364683Y505767D01*
X-365267Y506267D01*
X-365600Y507017D01*
X-365683Y507850D01*
X-365517Y508933D01*
X-365267Y509517D01*
X-364850Y510100D01*
X-364267Y510517D01*
X-363683Y510600D01*
X-363100Y510433D01*
X-362683Y510017D01*
G01X-358500Y510600D02*
X-359167Y510433D01*
X-359667Y510017D01*
X-360000Y509517D01*
X-360250Y508850D01*
X-360333Y508100D01*
X-360250Y507350D01*
X-360000Y506683D01*
X-359667Y506183D01*
X-359167Y505767D01*
X-358500Y505600D01*
X-357833Y505767D01*
X-357333Y506183D01*
X-357000Y506683D01*
X-356750Y507350D01*
X-356667Y508100D01*
X-356750Y508850D01*
X-357000Y509517D01*
X-357333Y510017D01*
X-357833Y510433D01*
X-358500Y510600D01*
G01X-352900Y505600D02*
Y510600D01*
X-353900Y509600D01*
G01Y505600D02*
X-351900D01*
G01X-347300D02*
Y510600D01*
X-348300Y509600D01*
G01Y505600D02*
X-346300D01*
G01X-335600Y508100D02*
X-333933D01*
Y506600D01*
X-334433Y506100D01*
X-335017Y505767D01*
X-335850Y505600D01*
X-336683Y505767D01*
X-337267Y506100D01*
X-337767Y506600D01*
X-338100Y507183D01*
X-338267Y507850D01*
Y508433D01*
X-338100Y508933D01*
X-337767Y509517D01*
X-337267Y510017D01*
X-336767Y510350D01*
X-336100Y510600D01*
X-335517D01*
X-334850Y510433D01*
X-334350Y510100D01*
G01X-331750Y507850D02*
X-329083D01*
X-329333Y508433D01*
X-329750Y508767D01*
X-330333Y508933D01*
X-330917Y508850D01*
X-331417Y508600D01*
X-331750Y508017D01*
X-331917Y507517D01*
Y507017D01*
X-331750Y506517D01*
X-331333Y506017D01*
X-330833Y505683D01*
X-330250Y505600D01*
X-329667Y505767D01*
X-329083Y506267D01*
G01X-326317Y505600D02*
Y508933D01*
G01Y508100D02*
X-325983Y508517D01*
X-325483Y508850D01*
X-324817Y508933D01*
X-324233Y508850D01*
X-323733Y508517D01*
X-323483Y507933D01*
Y505600D01*
G01X-320550Y507850D02*
X-317883D01*
X-318133Y508433D01*
X-318550Y508767D01*
X-319133Y508933D01*
X-319717Y508850D01*
X-320217Y508600D01*
X-320550Y508017D01*
X-320717Y507517D01*
Y507017D01*
X-320550Y506517D01*
X-320133Y506017D01*
X-319633Y505683D01*
X-319050Y505600D01*
X-318467Y505767D01*
X-317883Y506267D01*
G01X-314867Y505600D02*
Y508933D01*
G01Y508267D02*
X-314450Y508600D01*
X-314033Y508850D01*
X-313450Y508933D01*
X-313033Y508850D01*
X-312533Y508600D01*
G01X-308100Y508933D02*
Y505600D01*
G01Y510267D02*
X-308267Y510350D01*
Y510517D01*
X-308100Y510600D01*
X-307933Y510517D01*
Y510350D01*
X-308100Y510267D01*
G01X-301167Y508517D02*
X-301750Y508850D01*
X-302250Y508933D01*
X-302917Y508767D01*
X-303417Y508433D01*
X-303750Y507850D01*
X-303833Y507267D01*
X-303750Y506683D01*
X-303417Y506183D01*
X-302917Y505767D01*
X-302250Y505600D01*
X-301667Y505767D01*
X-301167Y506100D01*
G01X-292967Y505600D02*
Y510600D01*
X-290967D01*
X-290300Y510350D01*
X-289800Y509767D01*
X-289633Y509100D01*
X-289800Y508433D01*
X-290217Y507933D01*
X-290967Y507683D01*
X-292967D01*
G01X-286950Y507850D02*
X-284283D01*
X-284533Y508433D01*
X-284950Y508767D01*
X-285533Y508933D01*
X-286117Y508850D01*
X-286617Y508600D01*
X-286950Y508017D01*
X-287117Y507517D01*
Y507017D01*
X-286950Y506517D01*
X-286533Y506017D01*
X-286033Y505683D01*
X-285450Y505600D01*
X-284867Y505767D01*
X-284283Y506267D01*
G01X-281267Y505600D02*
Y508933D01*
G01Y508267D02*
X-280850Y508600D01*
X-280433Y508850D01*
X-279850Y508933D01*
X-279433Y508850D01*
X-278933Y508600D01*
G01X-275000Y505600D02*
Y509850D01*
X-274833Y510267D01*
X-274500Y510517D01*
X-274000Y510600D01*
X-273500Y510433D01*
X-273250Y510017D01*
G01X-274250Y508600D02*
X-275917D01*
G01X-268900Y505600D02*
X-269400Y505683D01*
X-269900Y506017D01*
X-270233Y506600D01*
X-270400Y507267D01*
X-270233Y507933D01*
X-269900Y508517D01*
X-269400Y508850D01*
X-268900Y508933D01*
X-268400Y508850D01*
X-267900Y508517D01*
X-267567Y507933D01*
X-267483Y507267D01*
X-267567Y506600D01*
X-267900Y506017D01*
X-268400Y505683D01*
X-268900Y505600D01*
G01X-264467D02*
Y508933D01*
G01Y508267D02*
X-264050Y508600D01*
X-263633Y508850D01*
X-263050Y508933D01*
X-262633Y508850D01*
X-262133Y508600D01*
G01X-260200Y505600D02*
Y508933D01*
G01Y508017D02*
X-259950Y508433D01*
X-259533Y508767D01*
X-258950Y508933D01*
X-258367Y508767D01*
X-257950Y508433D01*
X-257700Y508017D01*
Y505600D01*
G01Y508017D02*
X-257450Y508433D01*
X-257033Y508767D01*
X-256450Y508933D01*
X-255867Y508767D01*
X-255450Y508433D01*
X-255200Y507933D01*
Y505600D01*
G01X-250600D02*
Y508933D01*
G01Y508350D02*
X-250933Y508683D01*
X-251433Y508850D01*
X-252017Y508933D01*
X-252600Y508767D01*
X-253100Y508433D01*
X-253433Y507933D01*
X-253600Y507267D01*
X-253433Y506600D01*
X-253100Y506100D01*
X-252600Y505767D01*
X-252017Y505600D01*
X-251433Y505683D01*
X-250933Y505933D01*
X-250600Y506267D01*
G01X-247917Y505600D02*
Y508933D01*
G01Y508100D02*
X-247583Y508517D01*
X-247083Y508850D01*
X-246417Y508933D01*
X-245833Y508850D01*
X-245333Y508517D01*
X-245083Y507933D01*
Y505600D01*
G01X-239567Y508517D02*
X-240150Y508850D01*
X-240650Y508933D01*
X-241317Y508767D01*
X-241817Y508433D01*
X-242150Y507850D01*
X-242233Y507267D01*
X-242150Y506683D01*
X-241817Y506183D01*
X-241317Y505767D01*
X-240650Y505600D01*
X-240067Y505767D01*
X-239567Y506100D01*
G01X-236550Y507850D02*
X-233883D01*
X-234133Y508433D01*
X-234550Y508767D01*
X-235133Y508933D01*
X-235717Y508850D01*
X-236217Y508600D01*
X-236550Y508017D01*
X-236717Y507517D01*
Y507017D01*
X-236550Y506517D01*
X-236133Y506017D01*
X-235633Y505683D01*
X-235050Y505600D01*
X-234467Y505767D01*
X-233883Y506267D01*
G01X-225850D02*
X-225183Y505850D01*
X-224433Y505600D01*
X-223767D01*
X-223100Y505850D01*
X-222600Y506267D01*
X-222350Y506850D01*
X-222517Y507433D01*
X-222933Y507933D01*
X-223683Y508267D01*
X-224683Y508433D01*
X-225267Y508767D01*
X-225517Y509350D01*
X-225350Y509933D01*
X-224933Y510350D01*
X-224350Y510600D01*
X-223767D01*
X-223183Y510433D01*
X-222683Y510017D01*
G01X-220000Y503933D02*
Y508933D01*
G01Y508183D02*
X-219583Y508600D01*
X-219167Y508850D01*
X-218500Y508933D01*
X-217917Y508850D01*
X-217333Y508433D01*
X-217083Y507850D01*
X-217000Y507267D01*
X-217083Y506683D01*
X-217333Y506100D01*
X-217833Y505767D01*
X-218500Y505600D01*
X-219083Y505683D01*
X-219667Y505933D01*
X-220000Y506267D01*
G01X-214150Y507850D02*
X-211483D01*
X-211733Y508433D01*
X-212150Y508767D01*
X-212733Y508933D01*
X-213317Y508850D01*
X-213817Y508600D01*
X-214150Y508017D01*
X-214317Y507517D01*
Y507017D01*
X-214150Y506517D01*
X-213733Y506017D01*
X-213233Y505683D01*
X-212650Y505600D01*
X-212067Y505767D01*
X-211483Y506267D01*
G01X-205967Y508517D02*
X-206550Y508850D01*
X-207050Y508933D01*
X-207717Y508767D01*
X-208217Y508433D01*
X-208550Y507850D01*
X-208633Y507267D01*
X-208550Y506683D01*
X-208217Y506183D01*
X-207717Y505767D01*
X-207050Y505600D01*
X-206467Y505767D01*
X-205967Y506100D01*
G01X-201700Y508933D02*
Y505600D01*
G01Y510267D02*
X-201867Y510350D01*
Y510517D01*
X-201700Y510600D01*
X-201533Y510517D01*
Y510350D01*
X-201700Y510267D01*
G01X-196600Y505600D02*
Y509850D01*
X-196433Y510267D01*
X-196100Y510517D01*
X-195600Y510600D01*
X-195100Y510433D01*
X-194850Y510017D01*
G01X-195850Y508600D02*
X-197517D01*
G01X-190500Y508933D02*
Y505600D01*
G01Y510267D02*
X-190667Y510350D01*
Y510517D01*
X-190500Y510600D01*
X-190333Y510517D01*
Y510350D01*
X-190500Y510267D01*
G01X-183567Y508517D02*
X-184150Y508850D01*
X-184650Y508933D01*
X-185317Y508767D01*
X-185817Y508433D01*
X-186150Y507850D01*
X-186233Y507267D01*
X-186150Y506683D01*
X-185817Y506183D01*
X-185317Y505767D01*
X-184650Y505600D01*
X-184067Y505767D01*
X-183567Y506100D01*
G01X-177800Y505600D02*
Y508933D01*
G01Y508350D02*
X-178133Y508683D01*
X-178633Y508850D01*
X-179217Y508933D01*
X-179800Y508767D01*
X-180300Y508433D01*
X-180633Y507933D01*
X-180800Y507267D01*
X-180633Y506600D01*
X-180300Y506100D01*
X-179800Y505767D01*
X-179217Y505600D01*
X-178633Y505683D01*
X-178133Y505933D01*
X-177800Y506267D01*
G01X-173700Y510600D02*
Y505600D01*
G01X-174867Y508933D02*
X-172533D01*
G01X-168100D02*
Y505600D01*
G01Y510267D02*
X-168267Y510350D01*
Y510517D01*
X-168100Y510600D01*
X-167933Y510517D01*
Y510350D01*
X-168100Y510267D01*
G01X-162500Y505600D02*
X-163000Y505683D01*
X-163500Y506017D01*
X-163833Y506600D01*
X-164000Y507267D01*
X-163833Y507933D01*
X-163500Y508517D01*
X-163000Y508850D01*
X-162500Y508933D01*
X-162000Y508850D01*
X-161500Y508517D01*
X-161167Y507933D01*
X-161083Y507267D01*
X-161167Y506600D01*
X-161500Y506017D01*
X-162000Y505683D01*
X-162500Y505600D01*
G01X-158317D02*
Y508933D01*
G01Y508100D02*
X-157983Y508517D01*
X-157483Y508850D01*
X-156817Y508933D01*
X-156233Y508850D01*
X-155733Y508517D01*
X-155483Y507933D01*
Y505600D01*
G01X-146200D02*
Y509850D01*
X-146033Y510267D01*
X-145700Y510517D01*
X-145200Y510600D01*
X-144700Y510433D01*
X-144450Y510017D01*
G01X-145450Y508600D02*
X-147117D01*
G01X-140100Y505600D02*
X-140600Y505683D01*
X-141100Y506017D01*
X-141433Y506600D01*
X-141600Y507267D01*
X-141433Y507933D01*
X-141100Y508517D01*
X-140600Y508850D01*
X-140100Y508933D01*
X-139600Y508850D01*
X-139100Y508517D01*
X-138767Y507933D01*
X-138683Y507267D01*
X-138767Y506600D01*
X-139100Y506017D01*
X-139600Y505683D01*
X-140100Y505600D01*
G01X-135667D02*
Y508933D01*
G01Y508267D02*
X-135250Y508600D01*
X-134833Y508850D01*
X-134250Y508933D01*
X-133833Y508850D01*
X-133333Y508600D01*
G01X-124967Y505600D02*
Y510600D01*
X-122967D01*
X-122300Y510350D01*
X-121800Y509767D01*
X-121633Y509100D01*
X-121800Y508433D01*
X-122217Y507933D01*
X-122967Y507683D01*
X-124967D01*
G01X-118867Y505600D02*
Y508933D01*
G01Y508267D02*
X-118450Y508600D01*
X-118033Y508850D01*
X-117450Y508933D01*
X-117033Y508850D01*
X-116533Y508600D01*
G01X-112100Y508933D02*
Y505600D01*
G01Y510267D02*
X-112267Y510350D01*
Y510517D01*
X-112100Y510600D01*
X-111933Y510517D01*
Y510350D01*
X-112100Y510267D01*
G01X-107917Y505600D02*
Y508933D01*
G01Y508100D02*
X-107583Y508517D01*
X-107083Y508850D01*
X-106417Y508933D01*
X-105833Y508850D01*
X-105333Y508517D01*
X-105083Y507933D01*
Y505600D01*
G01X-100900Y510600D02*
Y505600D01*
G01X-102067Y508933D02*
X-99733D01*
G01X-96550Y507850D02*
X-93883D01*
X-94133Y508433D01*
X-94550Y508767D01*
X-95133Y508933D01*
X-95717Y508850D01*
X-96217Y508600D01*
X-96550Y508017D01*
X-96717Y507517D01*
Y507017D01*
X-96550Y506517D01*
X-96133Y506017D01*
X-95633Y505683D01*
X-95050Y505600D01*
X-94467Y505767D01*
X-93883Y506267D01*
G01X-88200Y510600D02*
Y505600D01*
G01Y506350D02*
X-88533Y505933D01*
X-89033Y505683D01*
X-89617Y505600D01*
X-90283Y505767D01*
X-90783Y506183D01*
X-91117Y506683D01*
X-91200Y507267D01*
X-91117Y507850D01*
X-90783Y508350D01*
X-90283Y508767D01*
X-89617Y508933D01*
X-89033Y508850D01*
X-88617Y508683D01*
X-88200Y508350D01*
G01X-77833Y508267D02*
X-77500Y508517D01*
X-77250Y508933D01*
X-77083Y509517D01*
X-77250Y510017D01*
X-77583Y510350D01*
X-78167Y510600D01*
X-80417D01*
Y505600D01*
X-77667D01*
X-77083Y505933D01*
X-76750Y506433D01*
X-76583Y507017D01*
X-76750Y507600D01*
X-77250Y508100D01*
X-77833Y508267D01*
X-80417D01*
G01X-72900Y505600D02*
X-73400Y505683D01*
X-73900Y506017D01*
X-74233Y506600D01*
X-74400Y507267D01*
X-74233Y507933D01*
X-73900Y508517D01*
X-73400Y508850D01*
X-72900Y508933D01*
X-72400Y508850D01*
X-71900Y508517D01*
X-71567Y507933D01*
X-71483Y507267D01*
X-71567Y506600D01*
X-71900Y506017D01*
X-72400Y505683D01*
X-72900Y505600D01*
G01X-65800D02*
Y508933D01*
G01Y508350D02*
X-66133Y508683D01*
X-66633Y508850D01*
X-67217Y508933D01*
X-67800Y508767D01*
X-68300Y508433D01*
X-68633Y507933D01*
X-68800Y507267D01*
X-68633Y506600D01*
X-68300Y506100D01*
X-67800Y505767D01*
X-67217Y505600D01*
X-66633Y505683D01*
X-66133Y505933D01*
X-65800Y506267D01*
G01X-62867Y505600D02*
Y508933D01*
G01Y508267D02*
X-62450Y508600D01*
X-62033Y508850D01*
X-61450Y508933D01*
X-61033Y508850D01*
X-60533Y508600D01*
G01X-54600Y510600D02*
Y505600D01*
G01Y506350D02*
X-54933Y505933D01*
X-55433Y505683D01*
X-56017Y505600D01*
X-56683Y505767D01*
X-57183Y506183D01*
X-57517Y506683D01*
X-57600Y507267D01*
X-57517Y507850D01*
X-57183Y508350D01*
X-56683Y508767D01*
X-56017Y508933D01*
X-55433Y508850D01*
X-55017Y508683D01*
X-54600Y508350D01*
G01X-51750Y506183D02*
X-51333Y505850D01*
X-50750Y505600D01*
X-50250D01*
X-49750Y505767D01*
X-49417Y506017D01*
X-49250Y506350D01*
X-49333Y506850D01*
X-49667Y507100D01*
X-51167Y507600D01*
X-51500Y508183D01*
X-51333Y508600D01*
X-51000Y508850D01*
X-50500Y508933D01*
X-50000Y508850D01*
X-49500Y508600D01*
G01X-387500Y518500D02*
X-385500D01*
G01X-386500D02*
Y513500D01*
G01X-387500D02*
X-385500D01*
G01X-382567D02*
Y518500D01*
X-380567D01*
X-379900Y518250D01*
X-379400Y517667D01*
X-379233Y517000D01*
X-379400Y516333D01*
X-379817Y515833D01*
X-380567Y515583D01*
X-382567D01*
G01X-373467Y518083D02*
X-373967Y518333D01*
X-374550Y518500D01*
X-375217D01*
X-375967Y518250D01*
X-376550Y517833D01*
X-376967Y517333D01*
X-377300Y516500D01*
X-377383Y515750D01*
X-377217Y515000D01*
X-376967Y514500D01*
X-376467Y514000D01*
X-375883Y513667D01*
X-375300Y513500D01*
X-374717D01*
X-374133Y513667D01*
X-373633Y513917D01*
X-373217Y514250D01*
G01X-370783Y515167D02*
X-368617D01*
G01X-366183Y513500D02*
X-364100Y518500D01*
X-362017Y513500D01*
G01X-362767Y515250D02*
X-365433D01*
G01X-359583Y515167D02*
X-357417D01*
G01X-354483Y515583D02*
X-353900Y516167D01*
X-353400Y516500D01*
X-352733Y516667D01*
X-352150Y516500D01*
X-351733Y516167D01*
X-351400Y515667D01*
X-351317Y515083D01*
X-351400Y514583D01*
X-351733Y514083D01*
X-352233Y513667D01*
X-352817Y513500D01*
X-353483Y513667D01*
X-354067Y514167D01*
X-354400Y514917D01*
X-354483Y515750D01*
X-354317Y516833D01*
X-354067Y517417D01*
X-353650Y518000D01*
X-353067Y518417D01*
X-352483Y518500D01*
X-351900Y518333D01*
X-351483Y517917D01*
G01X-347300Y518500D02*
X-347967Y518333D01*
X-348467Y517917D01*
X-348800Y517417D01*
X-349050Y516750D01*
X-349133Y516000D01*
X-349050Y515250D01*
X-348800Y514583D01*
X-348467Y514083D01*
X-347967Y513667D01*
X-347300Y513500D01*
X-346633Y513667D01*
X-346133Y514083D01*
X-345800Y514583D01*
X-345550Y515250D01*
X-345467Y516000D01*
X-345550Y516750D01*
X-345800Y517417D01*
X-346133Y517917D01*
X-346633Y518333D01*
X-347300Y518500D01*
G01X-341700D02*
X-342367Y518333D01*
X-342867Y517917D01*
X-343200Y517417D01*
X-343450Y516750D01*
X-343533Y516000D01*
X-343450Y515250D01*
X-343200Y514583D01*
X-342867Y514083D01*
X-342367Y513667D01*
X-341700Y513500D01*
X-341033Y513667D01*
X-340533Y514083D01*
X-340200Y514583D01*
X-339950Y515250D01*
X-339867Y516000D01*
X-339950Y516750D01*
X-340200Y517417D01*
X-340533Y517917D01*
X-341033Y518333D01*
X-341700Y518500D01*
G01X-332583Y513500D02*
X-330500Y518500D01*
X-328417Y513500D01*
G01X-329167Y515250D02*
X-331833D01*
G01X-323567Y516417D02*
X-324150Y516750D01*
X-324650Y516833D01*
X-325317Y516667D01*
X-325817Y516333D01*
X-326150Y515750D01*
X-326233Y515167D01*
X-326150Y514583D01*
X-325817Y514083D01*
X-325317Y513667D01*
X-324650Y513500D01*
X-324067Y513667D01*
X-323567Y514000D01*
G01X-317967Y516417D02*
X-318550Y516750D01*
X-319050Y516833D01*
X-319717Y516667D01*
X-320217Y516333D01*
X-320550Y515750D01*
X-320633Y515167D01*
X-320550Y514583D01*
X-320217Y514083D01*
X-319717Y513667D01*
X-319050Y513500D01*
X-318467Y513667D01*
X-317967Y514000D01*
G01X-314950Y515750D02*
X-312283D01*
X-312533Y516333D01*
X-312950Y516667D01*
X-313533Y516833D01*
X-314117Y516750D01*
X-314617Y516500D01*
X-314950Y515917D01*
X-315117Y515417D01*
Y514917D01*
X-314950Y514417D01*
X-314533Y513917D01*
X-314033Y513583D01*
X-313450Y513500D01*
X-312867Y513667D01*
X-312283Y514167D01*
G01X-309600Y511833D02*
Y516833D01*
G01Y516083D02*
X-309183Y516500D01*
X-308767Y516750D01*
X-308100Y516833D01*
X-307517Y516750D01*
X-306933Y516333D01*
X-306683Y515750D01*
X-306600Y515167D01*
X-306683Y514583D01*
X-306933Y514000D01*
X-307433Y513667D01*
X-308100Y513500D01*
X-308683Y513583D01*
X-309267Y513833D01*
X-309600Y514167D01*
G01X-302500Y518500D02*
Y513500D01*
G01X-303667Y516833D02*
X-301333D01*
G01X-295400Y513500D02*
Y516833D01*
G01Y516250D02*
X-295733Y516583D01*
X-296233Y516750D01*
X-296817Y516833D01*
X-297400Y516667D01*
X-297900Y516333D01*
X-298233Y515833D01*
X-298400Y515167D01*
X-298233Y514500D01*
X-297900Y514000D01*
X-297400Y513667D01*
X-296817Y513500D01*
X-296233Y513583D01*
X-295733Y513833D01*
X-295400Y514167D01*
G01X-292800Y513500D02*
Y518500D01*
G01Y516000D02*
X-292383Y516500D01*
X-291883Y516750D01*
X-291383Y516833D01*
X-290633Y516667D01*
X-290133Y516333D01*
X-289800Y515750D01*
Y515083D01*
X-289967Y514417D01*
X-290300Y513917D01*
X-290883Y513583D01*
X-291383Y513500D01*
X-291883Y513583D01*
X-292383Y513833D01*
X-292800Y514250D01*
G01X-285700Y516833D02*
Y513500D01*
G01Y518167D02*
X-285867Y518250D01*
Y518417D01*
X-285700Y518500D01*
X-285533Y518417D01*
Y518250D01*
X-285700Y518167D01*
G01X-280100Y513500D02*
Y518500D01*
G01X-274500Y516833D02*
Y513500D01*
G01Y518167D02*
X-274667Y518250D01*
Y518417D01*
X-274500Y518500D01*
X-274333Y518417D01*
Y518250D01*
X-274500Y518167D01*
G01X-268900Y518500D02*
Y513500D01*
G01X-270067Y516833D02*
X-267733D01*
G01X-265050Y512000D02*
X-264550Y511833D01*
X-263883Y512000D01*
X-263467Y512333D01*
X-263133Y512750D01*
X-262633Y514083D01*
X-261550Y516833D01*
G01X-264217D02*
X-262633Y514083D01*
G01X-252100Y513500D02*
X-252600Y513583D01*
X-253100Y513917D01*
X-253433Y514500D01*
X-253600Y515167D01*
X-253433Y515833D01*
X-253100Y516417D01*
X-252600Y516750D01*
X-252100Y516833D01*
X-251600Y516750D01*
X-251100Y516417D01*
X-250767Y515833D01*
X-250683Y515167D01*
X-250767Y514500D01*
X-251100Y513917D01*
X-251600Y513583D01*
X-252100Y513500D01*
G01X-247000D02*
Y517750D01*
X-246833Y518167D01*
X-246500Y518417D01*
X-246000Y518500D01*
X-245500Y518333D01*
X-245250Y517917D01*
G01X-246250Y516500D02*
X-247917D01*
G01X-236967Y513500D02*
Y518500D01*
X-234967D01*
X-234300Y518250D01*
X-233800Y517667D01*
X-233633Y517000D01*
X-233800Y516333D01*
X-234217Y515833D01*
X-234967Y515583D01*
X-236967D01*
G01X-230867Y513500D02*
Y516833D01*
G01Y516167D02*
X-230450Y516500D01*
X-230033Y516750D01*
X-229450Y516833D01*
X-229033Y516750D01*
X-228533Y516500D01*
G01X-224100Y516833D02*
Y513500D01*
G01Y518167D02*
X-224267Y518250D01*
Y518417D01*
X-224100Y518500D01*
X-223933Y518417D01*
Y518250D01*
X-224100Y518167D01*
G01X-219917Y513500D02*
Y516833D01*
G01Y516000D02*
X-219583Y516417D01*
X-219083Y516750D01*
X-218417Y516833D01*
X-217833Y516750D01*
X-217333Y516417D01*
X-217083Y515833D01*
Y513500D01*
G01X-212900Y518500D02*
Y513500D01*
G01X-214067Y516833D02*
X-211733D01*
G01X-208550Y515750D02*
X-205883D01*
X-206133Y516333D01*
X-206550Y516667D01*
X-207133Y516833D01*
X-207717Y516750D01*
X-208217Y516500D01*
X-208550Y515917D01*
X-208717Y515417D01*
Y514917D01*
X-208550Y514417D01*
X-208133Y513917D01*
X-207633Y513583D01*
X-207050Y513500D01*
X-206467Y513667D01*
X-205883Y514167D01*
G01X-200200Y518500D02*
Y513500D01*
G01Y514250D02*
X-200533Y513833D01*
X-201033Y513583D01*
X-201617Y513500D01*
X-202283Y513667D01*
X-202783Y514083D01*
X-203117Y514583D01*
X-203200Y515167D01*
X-203117Y515750D01*
X-202783Y516250D01*
X-202283Y516667D01*
X-201617Y516833D01*
X-201033Y516750D01*
X-200617Y516583D01*
X-200200Y516250D01*
G01X-189833Y516167D02*
X-189500Y516417D01*
X-189250Y516833D01*
X-189083Y517417D01*
X-189250Y517917D01*
X-189583Y518250D01*
X-190167Y518500D01*
X-192417D01*
Y513500D01*
X-189667D01*
X-189083Y513833D01*
X-188750Y514333D01*
X-188583Y514917D01*
X-188750Y515500D01*
X-189250Y516000D01*
X-189833Y516167D01*
X-192417D01*
G01X-184900Y513500D02*
X-185400Y513583D01*
X-185900Y513917D01*
X-186233Y514500D01*
X-186400Y515167D01*
X-186233Y515833D01*
X-185900Y516417D01*
X-185400Y516750D01*
X-184900Y516833D01*
X-184400Y516750D01*
X-183900Y516417D01*
X-183567Y515833D01*
X-183483Y515167D01*
X-183567Y514500D01*
X-183900Y513917D01*
X-184400Y513583D01*
X-184900Y513500D01*
G01X-177800D02*
Y516833D01*
G01Y516250D02*
X-178133Y516583D01*
X-178633Y516750D01*
X-179217Y516833D01*
X-179800Y516667D01*
X-180300Y516333D01*
X-180633Y515833D01*
X-180800Y515167D01*
X-180633Y514500D01*
X-180300Y514000D01*
X-179800Y513667D01*
X-179217Y513500D01*
X-178633Y513583D01*
X-178133Y513833D01*
X-177800Y514167D01*
G01X-174867Y513500D02*
Y516833D01*
G01Y516167D02*
X-174450Y516500D01*
X-174033Y516750D01*
X-173450Y516833D01*
X-173033Y516750D01*
X-172533Y516500D01*
G01X-166600Y518500D02*
Y513500D01*
G01Y514250D02*
X-166933Y513833D01*
X-167433Y513583D01*
X-168017Y513500D01*
X-168683Y513667D01*
X-169183Y514083D01*
X-169517Y514583D01*
X-169600Y515167D01*
X-169517Y515750D01*
X-169183Y516250D01*
X-168683Y516667D01*
X-168017Y516833D01*
X-167433Y516750D01*
X-167017Y516583D01*
X-166600Y516250D01*
G01X-163750Y514083D02*
X-163333Y513750D01*
X-162750Y513500D01*
X-162250D01*
X-161750Y513667D01*
X-161417Y513917D01*
X-161250Y514250D01*
X-161333Y514750D01*
X-161667Y515000D01*
X-163167Y515500D01*
X-163500Y516083D01*
X-163333Y516500D01*
X-163000Y516750D01*
X-162500Y516833D01*
X-162000Y516750D01*
X-161500Y516500D01*
G01X-346167Y-333000D02*
Y-338000D01*
X-342833D01*
G01X-338900D02*
X-339400Y-337917D01*
X-339900Y-337583D01*
X-340233Y-337000D01*
X-340400Y-336333D01*
X-340233Y-335667D01*
X-339900Y-335083D01*
X-339400Y-334750D01*
X-338900Y-334667D01*
X-338400Y-334750D01*
X-337900Y-335083D01*
X-337567Y-335667D01*
X-337483Y-336333D01*
X-337567Y-337000D01*
X-337900Y-337583D01*
X-338400Y-337917D01*
X-338900Y-338000D01*
G01X-334467Y-339250D02*
X-333883Y-339583D01*
X-333217Y-339667D01*
X-332633Y-339583D01*
X-332133Y-339167D01*
X-331800Y-338583D01*
Y-334667D01*
G01Y-335333D02*
X-332133Y-335000D01*
X-332633Y-334750D01*
X-333217Y-334667D01*
X-333883Y-334833D01*
X-334300Y-335167D01*
X-334633Y-335750D01*
X-334800Y-336333D01*
X-334717Y-336833D01*
X-334383Y-337417D01*
X-333883Y-337833D01*
X-333217Y-338000D01*
X-332717Y-337917D01*
X-332133Y-337583D01*
X-331800Y-337250D01*
G01X-327700Y-338000D02*
X-328200Y-337917D01*
X-328700Y-337583D01*
X-329033Y-337000D01*
X-329200Y-336333D01*
X-329033Y-335667D01*
X-328700Y-335083D01*
X-328200Y-334750D01*
X-327700Y-334667D01*
X-327200Y-334750D01*
X-326700Y-335083D01*
X-326367Y-335667D01*
X-326283Y-336333D01*
X-326367Y-337000D01*
X-326700Y-337583D01*
X-327200Y-337917D01*
X-327700Y-338000D01*
G01X-355000Y406000D02*
Y-342500D01*
G01Y-327500D02*
X236000D01*
G01X-344500Y-309000D02*
Y-314000D01*
G01X-345667Y-310667D02*
X-343333D01*
G01X-340317Y-314000D02*
Y-309000D01*
G01Y-311417D02*
X-339900Y-311000D01*
X-339483Y-310750D01*
X-338817Y-310667D01*
X-338317Y-310750D01*
X-337733Y-311083D01*
X-337483Y-311583D01*
Y-314000D01*
G01X-333300Y-310667D02*
Y-314000D01*
G01Y-309333D02*
X-333467Y-309250D01*
Y-309083D01*
X-333300Y-309000D01*
X-333133Y-309083D01*
Y-309250D01*
X-333300Y-309333D01*
G01X-326367Y-311083D02*
X-326950Y-310750D01*
X-327450Y-310667D01*
X-328117Y-310833D01*
X-328617Y-311167D01*
X-328950Y-311750D01*
X-329033Y-312333D01*
X-328950Y-312917D01*
X-328617Y-313417D01*
X-328117Y-313833D01*
X-327450Y-314000D01*
X-326867Y-313833D01*
X-326367Y-313500D01*
G01X-323517Y-314000D02*
Y-309000D01*
G01X-320850Y-310667D02*
X-323517Y-312583D01*
G01X-322433Y-311833D02*
X-320683Y-314000D01*
G01X-317917D02*
Y-310667D01*
G01Y-311500D02*
X-317583Y-311083D01*
X-317083Y-310750D01*
X-316417Y-310667D01*
X-315833Y-310750D01*
X-315333Y-311083D01*
X-315083Y-311667D01*
Y-314000D01*
G01X-312150Y-311750D02*
X-309483D01*
X-309733Y-311167D01*
X-310150Y-310833D01*
X-310733Y-310667D01*
X-311317Y-310750D01*
X-311817Y-311000D01*
X-312150Y-311583D01*
X-312317Y-312083D01*
Y-312583D01*
X-312150Y-313083D01*
X-311733Y-313583D01*
X-311233Y-313917D01*
X-310650Y-314000D01*
X-310067Y-313833D01*
X-309483Y-313333D01*
G01X-306550Y-313417D02*
X-306133Y-313750D01*
X-305550Y-314000D01*
X-305050D01*
X-304550Y-313833D01*
X-304217Y-313583D01*
X-304050Y-313250D01*
X-304133Y-312750D01*
X-304467Y-312500D01*
X-305967Y-312000D01*
X-306300Y-311417D01*
X-306133Y-311000D01*
X-305800Y-310750D01*
X-305300Y-310667D01*
X-304800Y-310750D01*
X-304300Y-311000D01*
G01X-300950Y-313417D02*
X-300533Y-313750D01*
X-299950Y-314000D01*
X-299450D01*
X-298950Y-313833D01*
X-298617Y-313583D01*
X-298450Y-313250D01*
X-298533Y-312750D01*
X-298867Y-312500D01*
X-300367Y-312000D01*
X-300700Y-311417D01*
X-300533Y-311000D01*
X-300200Y-310750D01*
X-299700Y-310667D01*
X-299200Y-310750D01*
X-298700Y-311000D01*
G01X-344500Y-288000D02*
Y-293000D01*
G01X-345667Y-289667D02*
X-343333D01*
G01X-340317Y-293000D02*
Y-288000D01*
G01Y-290417D02*
X-339900Y-290000D01*
X-339483Y-289750D01*
X-338817Y-289667D01*
X-338317Y-289750D01*
X-337733Y-290083D01*
X-337483Y-290583D01*
Y-293000D01*
G01X-333300Y-289667D02*
Y-293000D01*
G01Y-288333D02*
X-333467Y-288250D01*
Y-288083D01*
X-333300Y-288000D01*
X-333133Y-288083D01*
Y-288250D01*
X-333300Y-288333D01*
G01X-326367Y-290083D02*
X-326950Y-289750D01*
X-327450Y-289667D01*
X-328117Y-289833D01*
X-328617Y-290167D01*
X-328950Y-290750D01*
X-329033Y-291333D01*
X-328950Y-291917D01*
X-328617Y-292417D01*
X-328117Y-292833D01*
X-327450Y-293000D01*
X-326867Y-292833D01*
X-326367Y-292500D01*
G01X-323517Y-293000D02*
Y-288000D01*
G01X-320850Y-289667D02*
X-323517Y-291583D01*
G01X-322433Y-290833D02*
X-320683Y-293000D01*
G01X-317917D02*
Y-289667D01*
G01Y-290500D02*
X-317583Y-290083D01*
X-317083Y-289750D01*
X-316417Y-289667D01*
X-315833Y-289750D01*
X-315333Y-290083D01*
X-315083Y-290667D01*
Y-293000D01*
G01X-312150Y-290750D02*
X-309483D01*
X-309733Y-290167D01*
X-310150Y-289833D01*
X-310733Y-289667D01*
X-311317Y-289750D01*
X-311817Y-290000D01*
X-312150Y-290583D01*
X-312317Y-291083D01*
Y-291583D01*
X-312150Y-292083D01*
X-311733Y-292583D01*
X-311233Y-292917D01*
X-310650Y-293000D01*
X-310067Y-292833D01*
X-309483Y-292333D01*
G01X-306550Y-292417D02*
X-306133Y-292750D01*
X-305550Y-293000D01*
X-305050D01*
X-304550Y-292833D01*
X-304217Y-292583D01*
X-304050Y-292250D01*
X-304133Y-291750D01*
X-304467Y-291500D01*
X-305967Y-291000D01*
X-306300Y-290417D01*
X-306133Y-290000D01*
X-305800Y-289750D01*
X-305300Y-289667D01*
X-304800Y-289750D01*
X-304300Y-290000D01*
G01X-300950Y-292417D02*
X-300533Y-292750D01*
X-299950Y-293000D01*
X-299450D01*
X-298950Y-292833D01*
X-298617Y-292583D01*
X-298450Y-292250D01*
X-298533Y-291750D01*
X-298867Y-291500D01*
X-300367Y-291000D01*
X-300700Y-290417D01*
X-300533Y-290000D01*
X-300200Y-289750D01*
X-299700Y-289667D01*
X-299200Y-289750D01*
X-298700Y-290000D01*
G01X-339317Y-275167D02*
X-340150Y-274333D01*
X-340567Y-273500D01*
Y-270167D01*
X-340150Y-269333D01*
X-339317Y-268500D01*
G01X-335050Y-272833D02*
X-334383Y-273250D01*
X-333633Y-273500D01*
X-332967D01*
X-332300Y-273250D01*
X-331800Y-272833D01*
X-331550Y-272250D01*
X-331717Y-271667D01*
X-332133Y-271167D01*
X-332883Y-270833D01*
X-333883Y-270667D01*
X-334467Y-270333D01*
X-334717Y-269750D01*
X-334550Y-269167D01*
X-334133Y-268750D01*
X-333550Y-268500D01*
X-332967D01*
X-332383Y-268667D01*
X-331883Y-269083D01*
G01X-329867Y-273500D02*
Y-268500D01*
X-327700Y-272667D01*
X-325533Y-268500D01*
Y-273500D01*
G01X-323933D02*
Y-268500D01*
X-322267D01*
X-321600Y-268750D01*
X-321100Y-269083D01*
X-320683Y-269583D01*
X-320350Y-270167D01*
X-320267Y-271000D01*
X-320350Y-271833D01*
X-320683Y-272417D01*
X-321100Y-272917D01*
X-321600Y-273250D01*
X-322267Y-273500D01*
X-323933D01*
G01X-316083Y-275167D02*
X-315250Y-274333D01*
X-314833Y-273500D01*
Y-270167D01*
X-315250Y-269333D01*
X-316083Y-268500D01*
G01X-355000Y-282500D02*
X236000D01*
G01X-346250Y-260833D02*
X-345583Y-261250D01*
X-344833Y-261500D01*
X-344167D01*
X-343500Y-261250D01*
X-343000Y-260833D01*
X-342750Y-260250D01*
X-342917Y-259667D01*
X-343333Y-259167D01*
X-344083Y-258833D01*
X-345083Y-258667D01*
X-345667Y-258333D01*
X-345917Y-257750D01*
X-345750Y-257167D01*
X-345333Y-256750D01*
X-344750Y-256500D01*
X-344167D01*
X-343583Y-256667D01*
X-343083Y-257083D01*
G01X-338900Y-261500D02*
X-339400Y-261417D01*
X-339900Y-261083D01*
X-340233Y-260500D01*
X-340400Y-259833D01*
X-340233Y-259167D01*
X-339900Y-258583D01*
X-339400Y-258250D01*
X-338900Y-258167D01*
X-338400Y-258250D01*
X-337900Y-258583D01*
X-337567Y-259167D01*
X-337483Y-259833D01*
X-337567Y-260500D01*
X-337900Y-261083D01*
X-338400Y-261417D01*
X-338900Y-261500D01*
G01X-333300D02*
Y-256500D01*
G01X-326200D02*
Y-261500D01*
G01Y-260750D02*
X-326533Y-261167D01*
X-327033Y-261417D01*
X-327617Y-261500D01*
X-328283Y-261333D01*
X-328783Y-260917D01*
X-329117Y-260417D01*
X-329200Y-259833D01*
X-329117Y-259250D01*
X-328783Y-258750D01*
X-328283Y-258333D01*
X-327617Y-258167D01*
X-327033Y-258250D01*
X-326617Y-258417D01*
X-326200Y-258750D01*
G01X-323350Y-259250D02*
X-320683D01*
X-320933Y-258667D01*
X-321350Y-258333D01*
X-321933Y-258167D01*
X-322517Y-258250D01*
X-323017Y-258500D01*
X-323350Y-259083D01*
X-323517Y-259583D01*
Y-260083D01*
X-323350Y-260583D01*
X-322933Y-261083D01*
X-322433Y-261417D01*
X-321850Y-261500D01*
X-321267Y-261333D01*
X-320683Y-260833D01*
G01X-317667Y-261500D02*
Y-258167D01*
G01Y-258833D02*
X-317250Y-258500D01*
X-316833Y-258250D01*
X-316250Y-258167D01*
X-315833Y-258250D01*
X-315333Y-258500D01*
G01X-307800Y-261500D02*
Y-258167D01*
G01Y-259083D02*
X-307550Y-258667D01*
X-307133Y-258333D01*
X-306550Y-258167D01*
X-305967Y-258333D01*
X-305550Y-258667D01*
X-305300Y-259083D01*
Y-261500D01*
G01Y-259083D02*
X-305050Y-258667D01*
X-304633Y-258333D01*
X-304050Y-258167D01*
X-303467Y-258333D01*
X-303050Y-258667D01*
X-302800Y-259167D01*
Y-261500D01*
G01X-298200D02*
Y-258167D01*
G01Y-258750D02*
X-298533Y-258417D01*
X-299033Y-258250D01*
X-299617Y-258167D01*
X-300200Y-258333D01*
X-300700Y-258667D01*
X-301033Y-259167D01*
X-301200Y-259833D01*
X-301033Y-260500D01*
X-300700Y-261000D01*
X-300200Y-261333D01*
X-299617Y-261500D01*
X-299033Y-261417D01*
X-298533Y-261167D01*
X-298200Y-260833D01*
G01X-295350Y-260917D02*
X-294933Y-261250D01*
X-294350Y-261500D01*
X-293850D01*
X-293350Y-261333D01*
X-293017Y-261083D01*
X-292850Y-260750D01*
X-292933Y-260250D01*
X-293267Y-260000D01*
X-294767Y-259500D01*
X-295100Y-258917D01*
X-294933Y-258500D01*
X-294600Y-258250D01*
X-294100Y-258167D01*
X-293600Y-258250D01*
X-293100Y-258500D01*
G01X-289917Y-261500D02*
Y-256500D01*
G01X-287250Y-258167D02*
X-289917Y-260083D01*
G01X-288833Y-259333D02*
X-287083Y-261500D01*
G01X-275800Y-256500D02*
Y-261500D01*
G01Y-260750D02*
X-276133Y-261167D01*
X-276633Y-261417D01*
X-277217Y-261500D01*
X-277883Y-261333D01*
X-278383Y-260917D01*
X-278717Y-260417D01*
X-278800Y-259833D01*
X-278717Y-259250D01*
X-278383Y-258750D01*
X-277883Y-258333D01*
X-277217Y-258167D01*
X-276633Y-258250D01*
X-276217Y-258417D01*
X-275800Y-258750D01*
G01X-272950Y-259250D02*
X-270283D01*
X-270533Y-258667D01*
X-270950Y-258333D01*
X-271533Y-258167D01*
X-272117Y-258250D01*
X-272617Y-258500D01*
X-272950Y-259083D01*
X-273117Y-259583D01*
Y-260083D01*
X-272950Y-260583D01*
X-272533Y-261083D01*
X-272033Y-261417D01*
X-271450Y-261500D01*
X-270867Y-261333D01*
X-270283Y-260833D01*
G01X-266600Y-261500D02*
Y-257250D01*
X-266433Y-256833D01*
X-266100Y-256583D01*
X-265600Y-256500D01*
X-265100Y-256667D01*
X-264850Y-257083D01*
G01X-265850Y-258500D02*
X-267517D01*
G01X-260500Y-258167D02*
Y-261500D01*
G01Y-256833D02*
X-260667Y-256750D01*
Y-256583D01*
X-260500Y-256500D01*
X-260333Y-256583D01*
Y-256750D01*
X-260500Y-256833D01*
G01X-256317Y-261500D02*
Y-258167D01*
G01Y-259000D02*
X-255983Y-258583D01*
X-255483Y-258250D01*
X-254817Y-258167D01*
X-254233Y-258250D01*
X-253733Y-258583D01*
X-253483Y-259167D01*
Y-261500D01*
G01X-250550Y-259250D02*
X-247883D01*
X-248133Y-258667D01*
X-248550Y-258333D01*
X-249133Y-258167D01*
X-249717Y-258250D01*
X-250217Y-258500D01*
X-250550Y-259083D01*
X-250717Y-259583D01*
Y-260083D01*
X-250550Y-260583D01*
X-250133Y-261083D01*
X-249633Y-261417D01*
X-249050Y-261500D01*
X-248467Y-261333D01*
X-247883Y-260833D01*
G01X-239600Y-263167D02*
Y-258167D01*
G01Y-258917D02*
X-239183Y-258500D01*
X-238767Y-258250D01*
X-238100Y-258167D01*
X-237517Y-258250D01*
X-236933Y-258667D01*
X-236683Y-259250D01*
X-236600Y-259833D01*
X-236683Y-260417D01*
X-236933Y-261000D01*
X-237433Y-261333D01*
X-238100Y-261500D01*
X-238683Y-261417D01*
X-239267Y-261167D01*
X-239600Y-260833D01*
G01X-231000Y-261500D02*
Y-258167D01*
G01Y-258750D02*
X-231333Y-258417D01*
X-231833Y-258250D01*
X-232417Y-258167D01*
X-233000Y-258333D01*
X-233500Y-258667D01*
X-233833Y-259167D01*
X-234000Y-259833D01*
X-233833Y-260500D01*
X-233500Y-261000D01*
X-233000Y-261333D01*
X-232417Y-261500D01*
X-231833Y-261417D01*
X-231333Y-261167D01*
X-231000Y-260833D01*
G01X-225400Y-256500D02*
Y-261500D01*
G01Y-260750D02*
X-225733Y-261167D01*
X-226233Y-261417D01*
X-226817Y-261500D01*
X-227483Y-261333D01*
X-227983Y-260917D01*
X-228317Y-260417D01*
X-228400Y-259833D01*
X-228317Y-259250D01*
X-227983Y-258750D01*
X-227483Y-258333D01*
X-226817Y-258167D01*
X-226233Y-258250D01*
X-225817Y-258417D01*
X-225400Y-258750D01*
G01X-346017Y-248300D02*
Y-243300D01*
X-343850Y-247467D01*
X-341683Y-243300D01*
Y-248300D01*
G01X-336750D02*
Y-244967D01*
G01Y-245550D02*
X-337083Y-245217D01*
X-337583Y-245050D01*
X-338167Y-244967D01*
X-338750Y-245133D01*
X-339250Y-245467D01*
X-339583Y-245967D01*
X-339750Y-246633D01*
X-339583Y-247300D01*
X-339250Y-247800D01*
X-338750Y-248133D01*
X-338167Y-248300D01*
X-337583Y-248217D01*
X-337083Y-247967D01*
X-336750Y-247633D01*
G01X-333817Y-248300D02*
Y-244967D01*
G01Y-245633D02*
X-333400Y-245300D01*
X-332983Y-245050D01*
X-332400Y-244967D01*
X-331983Y-245050D01*
X-331483Y-245300D01*
G01X-328467Y-248300D02*
Y-243300D01*
G01X-325800Y-244967D02*
X-328467Y-246883D01*
G01X-327383Y-246133D02*
X-325633Y-248300D01*
G01X-321033Y-249967D02*
X-320200Y-249133D01*
X-319783Y-248300D01*
Y-244967D01*
X-320200Y-244133D01*
X-321033Y-243300D01*
G01X-345430Y-236870D02*
X-343763D01*
Y-238370D01*
X-344263Y-238870D01*
X-344847Y-239203D01*
X-345680Y-239370D01*
X-346513Y-239203D01*
X-347097Y-238870D01*
X-347597Y-238370D01*
X-347930Y-237787D01*
X-348097Y-237120D01*
Y-236537D01*
X-347930Y-236037D01*
X-347597Y-235453D01*
X-347097Y-234953D01*
X-346597Y-234620D01*
X-345930Y-234370D01*
X-345347D01*
X-344680Y-234537D01*
X-344180Y-234870D01*
G01X-340330Y-239370D02*
X-340830Y-239287D01*
X-341330Y-238953D01*
X-341663Y-238370D01*
X-341830Y-237703D01*
X-341663Y-237037D01*
X-341330Y-236453D01*
X-340830Y-236120D01*
X-340330Y-236037D01*
X-339830Y-236120D01*
X-339330Y-236453D01*
X-338997Y-237037D01*
X-338913Y-237703D01*
X-338997Y-238370D01*
X-339330Y-238953D01*
X-339830Y-239287D01*
X-340330Y-239370D01*
G01X-334730D02*
Y-234370D01*
G01X-327630D02*
Y-239370D01*
G01Y-238620D02*
X-327963Y-239037D01*
X-328463Y-239287D01*
X-329047Y-239370D01*
X-329713Y-239203D01*
X-330213Y-238787D01*
X-330547Y-238287D01*
X-330630Y-237703D01*
X-330547Y-237120D01*
X-330213Y-236620D01*
X-329713Y-236203D01*
X-329047Y-236037D01*
X-328463Y-236120D01*
X-328047Y-236287D01*
X-327630Y-236620D01*
G01X-324780Y-237120D02*
X-322113D01*
X-322363Y-236537D01*
X-322780Y-236203D01*
X-323363Y-236037D01*
X-323947Y-236120D01*
X-324447Y-236370D01*
X-324780Y-236953D01*
X-324947Y-237453D01*
Y-237953D01*
X-324780Y-238453D01*
X-324363Y-238953D01*
X-323863Y-239287D01*
X-323280Y-239370D01*
X-322697Y-239203D01*
X-322113Y-238703D01*
G01X-319347Y-239370D02*
Y-236037D01*
G01Y-236870D02*
X-319013Y-236453D01*
X-318513Y-236120D01*
X-317847Y-236037D01*
X-317263Y-236120D01*
X-316763Y-236453D01*
X-316513Y-237037D01*
Y-239370D01*
G01X-307230D02*
Y-235120D01*
X-307063Y-234703D01*
X-306730Y-234453D01*
X-306230Y-234370D01*
X-305730Y-234537D01*
X-305480Y-234953D01*
G01X-306480Y-236370D02*
X-308147D01*
G01X-301130Y-236037D02*
Y-239370D01*
G01Y-234703D02*
X-301297Y-234620D01*
Y-234453D01*
X-301130Y-234370D01*
X-300963Y-234453D01*
Y-234620D01*
X-301130Y-234703D01*
G01X-296947Y-239370D02*
Y-236037D01*
G01Y-236870D02*
X-296613Y-236453D01*
X-296113Y-236120D01*
X-295447Y-236037D01*
X-294863Y-236120D01*
X-294363Y-236453D01*
X-294113Y-237037D01*
Y-239370D01*
G01X-291097Y-240620D02*
X-290513Y-240953D01*
X-289847Y-241037D01*
X-289263Y-240953D01*
X-288763Y-240537D01*
X-288430Y-239953D01*
Y-236037D01*
G01Y-236703D02*
X-288763Y-236370D01*
X-289263Y-236120D01*
X-289847Y-236037D01*
X-290513Y-236203D01*
X-290930Y-236537D01*
X-291263Y-237120D01*
X-291430Y-237703D01*
X-291347Y-238203D01*
X-291013Y-238787D01*
X-290513Y-239203D01*
X-289847Y-239370D01*
X-289347Y-239287D01*
X-288763Y-238953D01*
X-288430Y-238620D01*
G01X-285580Y-237120D02*
X-282913D01*
X-283163Y-236537D01*
X-283580Y-236203D01*
X-284163Y-236037D01*
X-284747Y-236120D01*
X-285247Y-236370D01*
X-285580Y-236953D01*
X-285747Y-237453D01*
Y-237953D01*
X-285580Y-238453D01*
X-285163Y-238953D01*
X-284663Y-239287D01*
X-284080Y-239370D01*
X-283497Y-239203D01*
X-282913Y-238703D01*
G01X-279897Y-239370D02*
Y-236037D01*
G01Y-236703D02*
X-279480Y-236370D01*
X-279063Y-236120D01*
X-278480Y-236037D01*
X-278063Y-236120D01*
X-277563Y-236370D01*
G01X-269197Y-239370D02*
Y-234370D01*
X-267197D01*
X-266530Y-234620D01*
X-266030Y-235203D01*
X-265863Y-235870D01*
X-266030Y-236537D01*
X-266447Y-237037D01*
X-267197Y-237287D01*
X-269197D01*
G01X-264013Y-239370D02*
X-261930Y-234370D01*
X-259847Y-239370D01*
G01X-260597Y-237620D02*
X-263263D01*
G01X-258163Y-239370D02*
Y-234370D01*
X-256497D01*
X-255830Y-234620D01*
X-255330Y-234953D01*
X-254913Y-235453D01*
X-254580Y-236037D01*
X-254497Y-236870D01*
X-254580Y-237703D01*
X-254913Y-238287D01*
X-255330Y-238787D01*
X-255830Y-239120D01*
X-256497Y-239370D01*
X-258163D01*
G01X-246630Y-239537D02*
X-243630Y-234370D01*
G01X-241113Y-239370D02*
Y-234370D01*
X-237947D01*
G01X-239113Y-236787D02*
X-241113D01*
G01X-233930Y-236037D02*
Y-239370D01*
G01Y-234703D02*
X-234097Y-234620D01*
Y-234453D01*
X-233930Y-234370D01*
X-233763Y-234453D01*
Y-234620D01*
X-233930Y-234703D01*
G01X-226830Y-234370D02*
Y-239370D01*
G01Y-238620D02*
X-227163Y-239037D01*
X-227663Y-239287D01*
X-228247Y-239370D01*
X-228913Y-239203D01*
X-229413Y-238787D01*
X-229747Y-238287D01*
X-229830Y-237703D01*
X-229747Y-237120D01*
X-229413Y-236620D01*
X-228913Y-236203D01*
X-228247Y-236037D01*
X-227663Y-236120D01*
X-227247Y-236287D01*
X-226830Y-236620D01*
G01X-224147Y-236037D02*
Y-238370D01*
X-223813Y-238953D01*
X-223313Y-239287D01*
X-222730Y-239370D01*
X-222147Y-239287D01*
X-221647Y-238953D01*
X-221313Y-238370D01*
G01Y-239370D02*
Y-236037D01*
G01X-215797Y-236453D02*
X-216380Y-236120D01*
X-216880Y-236037D01*
X-217547Y-236203D01*
X-218047Y-236537D01*
X-218380Y-237120D01*
X-218463Y-237703D01*
X-218380Y-238287D01*
X-218047Y-238787D01*
X-217547Y-239203D01*
X-216880Y-239370D01*
X-216297Y-239203D01*
X-215797Y-238870D01*
G01X-211530Y-236037D02*
Y-239370D01*
G01Y-234703D02*
X-211697Y-234620D01*
Y-234453D01*
X-211530Y-234370D01*
X-211363Y-234453D01*
Y-234620D01*
X-211530Y-234703D01*
G01X-204430Y-239370D02*
Y-236037D01*
G01Y-236620D02*
X-204763Y-236287D01*
X-205263Y-236120D01*
X-205847Y-236037D01*
X-206430Y-236203D01*
X-206930Y-236537D01*
X-207263Y-237037D01*
X-207430Y-237703D01*
X-207263Y-238370D01*
X-206930Y-238870D01*
X-206430Y-239203D01*
X-205847Y-239370D01*
X-205263Y-239287D01*
X-204763Y-239037D01*
X-204430Y-238703D01*
G01X-200330Y-239370D02*
Y-234370D01*
G01X-345757Y-230327D02*
X-346590Y-229493D01*
X-347007Y-228660D01*
Y-225327D01*
X-346590Y-224493D01*
X-345757Y-223660D01*
G01X-342240Y-228660D02*
Y-225327D01*
G01Y-226243D02*
X-341990Y-225827D01*
X-341573Y-225493D01*
X-340990Y-225327D01*
X-340407Y-225493D01*
X-339990Y-225827D01*
X-339740Y-226243D01*
Y-228660D01*
G01Y-226243D02*
X-339490Y-225827D01*
X-339073Y-225493D01*
X-338490Y-225327D01*
X-337907Y-225493D01*
X-337490Y-225827D01*
X-337240Y-226327D01*
Y-228660D01*
G01X-335390Y-226410D02*
X-332723D01*
X-332973Y-225827D01*
X-333390Y-225493D01*
X-333973Y-225327D01*
X-334557Y-225410D01*
X-335057Y-225660D01*
X-335390Y-226243D01*
X-335557Y-226743D01*
Y-227243D01*
X-335390Y-227743D01*
X-334973Y-228243D01*
X-334473Y-228577D01*
X-333890Y-228660D01*
X-333307Y-228493D01*
X-332723Y-227993D01*
G01X-327040Y-228660D02*
Y-225327D01*
G01Y-225910D02*
X-327373Y-225577D01*
X-327873Y-225410D01*
X-328457Y-225327D01*
X-329040Y-225493D01*
X-329540Y-225827D01*
X-329873Y-226327D01*
X-330040Y-226993D01*
X-329873Y-227660D01*
X-329540Y-228160D01*
X-329040Y-228493D01*
X-328457Y-228660D01*
X-327873Y-228577D01*
X-327373Y-228327D01*
X-327040Y-227993D01*
G01X-324190Y-228077D02*
X-323773Y-228410D01*
X-323190Y-228660D01*
X-322690D01*
X-322190Y-228493D01*
X-321857Y-228243D01*
X-321690Y-227910D01*
X-321773Y-227410D01*
X-322107Y-227160D01*
X-323607Y-226660D01*
X-323940Y-226077D01*
X-323773Y-225660D01*
X-323440Y-225410D01*
X-322940Y-225327D01*
X-322440Y-225410D01*
X-321940Y-225660D01*
G01X-318757Y-225327D02*
Y-227660D01*
X-318423Y-228243D01*
X-317923Y-228577D01*
X-317340Y-228660D01*
X-316757Y-228577D01*
X-316257Y-228243D01*
X-315923Y-227660D01*
G01Y-228660D02*
Y-225327D01*
G01X-312907Y-228660D02*
Y-225327D01*
G01Y-225993D02*
X-312490Y-225660D01*
X-312073Y-225410D01*
X-311490Y-225327D01*
X-311073Y-225410D01*
X-310573Y-225660D01*
G01X-307390Y-226410D02*
X-304723D01*
X-304973Y-225827D01*
X-305390Y-225493D01*
X-305973Y-225327D01*
X-306557Y-225410D01*
X-307057Y-225660D01*
X-307390Y-226243D01*
X-307557Y-226743D01*
Y-227243D01*
X-307390Y-227743D01*
X-306973Y-228243D01*
X-306473Y-228577D01*
X-305890Y-228660D01*
X-305307Y-228493D01*
X-304723Y-227993D01*
G01X-294940Y-223660D02*
Y-228660D01*
G01X-296107Y-225327D02*
X-293773D01*
G01X-289340Y-228660D02*
X-289840Y-228577D01*
X-290340Y-228243D01*
X-290673Y-227660D01*
X-290840Y-226993D01*
X-290673Y-226327D01*
X-290340Y-225743D01*
X-289840Y-225410D01*
X-289340Y-225327D01*
X-288840Y-225410D01*
X-288340Y-225743D01*
X-288007Y-226327D01*
X-287923Y-226993D01*
X-288007Y-227660D01*
X-288340Y-228243D01*
X-288840Y-228577D01*
X-289340Y-228660D01*
G01X-285240Y-230327D02*
Y-225327D01*
G01Y-226077D02*
X-284823Y-225660D01*
X-284407Y-225410D01*
X-283740Y-225327D01*
X-283157Y-225410D01*
X-282573Y-225827D01*
X-282323Y-226410D01*
X-282240Y-226993D01*
X-282323Y-227577D01*
X-282573Y-228160D01*
X-283073Y-228493D01*
X-283740Y-228660D01*
X-284323Y-228577D01*
X-284907Y-228327D01*
X-285240Y-227993D01*
G01X-273790Y-228077D02*
X-273373Y-228410D01*
X-272790Y-228660D01*
X-272290D01*
X-271790Y-228493D01*
X-271457Y-228243D01*
X-271290Y-227910D01*
X-271373Y-227410D01*
X-271707Y-227160D01*
X-273207Y-226660D01*
X-273540Y-226077D01*
X-273373Y-225660D01*
X-273040Y-225410D01*
X-272540Y-225327D01*
X-272040Y-225410D01*
X-271540Y-225660D01*
G01X-266940Y-225327D02*
Y-228660D01*
G01Y-223993D02*
X-267107Y-223910D01*
Y-223743D01*
X-266940Y-223660D01*
X-266773Y-223743D01*
Y-223910D01*
X-266940Y-223993D01*
G01X-262590Y-225327D02*
X-260090D01*
X-262590Y-228660D01*
X-260090D01*
G01X-256990Y-226410D02*
X-254323D01*
X-254573Y-225827D01*
X-254990Y-225493D01*
X-255573Y-225327D01*
X-256157Y-225410D01*
X-256657Y-225660D01*
X-256990Y-226243D01*
X-257157Y-226743D01*
Y-227243D01*
X-256990Y-227743D01*
X-256573Y-228243D01*
X-256073Y-228577D01*
X-255490Y-228660D01*
X-254907Y-228493D01*
X-254323Y-227993D01*
G01X-244540Y-228660D02*
X-245040Y-228577D01*
X-245540Y-228243D01*
X-245873Y-227660D01*
X-246040Y-226993D01*
X-245873Y-226327D01*
X-245540Y-225743D01*
X-245040Y-225410D01*
X-244540Y-225327D01*
X-244040Y-225410D01*
X-243540Y-225743D01*
X-243207Y-226327D01*
X-243123Y-226993D01*
X-243207Y-227660D01*
X-243540Y-228243D01*
X-244040Y-228577D01*
X-244540Y-228660D01*
G01X-239440D02*
Y-224410D01*
X-239273Y-223993D01*
X-238940Y-223743D01*
X-238440Y-223660D01*
X-237940Y-223827D01*
X-237690Y-224243D01*
G01X-238690Y-225660D02*
X-240357D01*
G01X-229407Y-228660D02*
Y-223660D01*
X-227407D01*
X-226740Y-223910D01*
X-226240Y-224493D01*
X-226073Y-225160D01*
X-226240Y-225827D01*
X-226657Y-226327D01*
X-227407Y-226577D01*
X-229407D01*
G01X-224223Y-228660D02*
X-222140Y-223660D01*
X-220057Y-228660D01*
G01X-220807Y-226910D02*
X-223473D01*
G01X-218373Y-228660D02*
Y-223660D01*
X-216707D01*
X-216040Y-223910D01*
X-215540Y-224243D01*
X-215123Y-224743D01*
X-214790Y-225327D01*
X-214707Y-226160D01*
X-214790Y-226993D01*
X-215123Y-227577D01*
X-215540Y-228077D01*
X-216040Y-228410D01*
X-216707Y-228660D01*
X-218373D01*
G01X-206840Y-228827D02*
X-203840Y-223660D01*
G01X-346167Y-221500D02*
Y-216500D01*
X-344167D01*
X-343500Y-216750D01*
X-343000Y-217333D01*
X-342833Y-218000D01*
X-343000Y-218667D01*
X-343417Y-219167D01*
X-344167Y-219417D01*
X-346167D01*
G01X-340983Y-221500D02*
X-338900Y-216500D01*
X-336817Y-221500D01*
G01X-337567Y-219750D02*
X-340233D01*
G01X-335133Y-221500D02*
Y-216500D01*
X-333467D01*
X-332800Y-216750D01*
X-332300Y-217083D01*
X-331883Y-217583D01*
X-331550Y-218167D01*
X-331467Y-219000D01*
X-331550Y-219833D01*
X-331883Y-220417D01*
X-332300Y-220917D01*
X-332800Y-221250D01*
X-333467Y-221500D01*
X-335133D01*
G01X-323350Y-220917D02*
X-322933Y-221250D01*
X-322350Y-221500D01*
X-321850D01*
X-321350Y-221333D01*
X-321017Y-221083D01*
X-320850Y-220750D01*
X-320933Y-220250D01*
X-321267Y-220000D01*
X-322767Y-219500D01*
X-323100Y-218917D01*
X-322933Y-218500D01*
X-322600Y-218250D01*
X-322100Y-218167D01*
X-321600Y-218250D01*
X-321100Y-218500D01*
G01X-316500Y-218167D02*
Y-221500D01*
G01Y-216833D02*
X-316667Y-216750D01*
Y-216583D01*
X-316500Y-216500D01*
X-316333Y-216583D01*
Y-216750D01*
X-316500Y-216833D01*
G01X-312150Y-218167D02*
X-309650D01*
X-312150Y-221500D01*
X-309650D01*
G01X-306550Y-219250D02*
X-303883D01*
X-304133Y-218667D01*
X-304550Y-218333D01*
X-305133Y-218167D01*
X-305717Y-218250D01*
X-306217Y-218500D01*
X-306550Y-219083D01*
X-306717Y-219583D01*
Y-220083D01*
X-306550Y-220583D01*
X-306133Y-221083D01*
X-305633Y-221417D01*
X-305050Y-221500D01*
X-304467Y-221333D01*
X-303883Y-220833D01*
G01X-355000Y-212500D02*
X236000D01*
G01X-344500Y-188000D02*
Y-193000D01*
G01X-346417Y-188000D02*
X-342583D01*
G01X-340067Y-193000D02*
Y-189667D01*
G01Y-190333D02*
X-339650Y-190000D01*
X-339233Y-189750D01*
X-338650Y-189667D01*
X-338233Y-189750D01*
X-337733Y-190000D01*
G01X-331800Y-193000D02*
Y-189667D01*
G01Y-190250D02*
X-332133Y-189917D01*
X-332633Y-189750D01*
X-333217Y-189667D01*
X-333800Y-189833D01*
X-334300Y-190167D01*
X-334633Y-190667D01*
X-334800Y-191333D01*
X-334633Y-192000D01*
X-334300Y-192500D01*
X-333800Y-192833D01*
X-333217Y-193000D01*
X-332633Y-192917D01*
X-332133Y-192667D01*
X-331800Y-192333D01*
G01X-326367Y-190083D02*
X-326950Y-189750D01*
X-327450Y-189667D01*
X-328117Y-189833D01*
X-328617Y-190167D01*
X-328950Y-190750D01*
X-329033Y-191333D01*
X-328950Y-191917D01*
X-328617Y-192417D01*
X-328117Y-192833D01*
X-327450Y-193000D01*
X-326867Y-192833D01*
X-326367Y-192500D01*
G01X-323350Y-190750D02*
X-320683D01*
X-320933Y-190167D01*
X-321350Y-189833D01*
X-321933Y-189667D01*
X-322517Y-189750D01*
X-323017Y-190000D01*
X-323350Y-190583D01*
X-323517Y-191083D01*
Y-191583D01*
X-323350Y-192083D01*
X-322933Y-192583D01*
X-322433Y-192917D01*
X-321850Y-193000D01*
X-321267Y-192833D01*
X-320683Y-192333D01*
G01X-312983Y-189667D02*
X-311983Y-193000D01*
X-310900Y-189667D01*
X-309817Y-193000D01*
X-308817Y-189667D01*
G01X-305300D02*
Y-193000D01*
G01Y-188333D02*
X-305467Y-188250D01*
Y-188083D01*
X-305300Y-188000D01*
X-305133Y-188083D01*
Y-188250D01*
X-305300Y-188333D01*
G01X-298200Y-188000D02*
Y-193000D01*
G01Y-192250D02*
X-298533Y-192667D01*
X-299033Y-192917D01*
X-299617Y-193000D01*
X-300283Y-192833D01*
X-300783Y-192417D01*
X-301117Y-191917D01*
X-301200Y-191333D01*
X-301117Y-190750D01*
X-300783Y-190250D01*
X-300283Y-189833D01*
X-299617Y-189667D01*
X-299033Y-189750D01*
X-298617Y-189917D01*
X-298200Y-190250D01*
G01X-294100Y-188000D02*
Y-193000D01*
G01X-295267Y-189667D02*
X-292933D01*
G01X-289917Y-193000D02*
Y-188000D01*
G01Y-190417D02*
X-289500Y-190000D01*
X-289083Y-189750D01*
X-288417Y-189667D01*
X-287917Y-189750D01*
X-287333Y-190083D01*
X-287083Y-190583D01*
Y-193000D01*
G01X-346167Y-161500D02*
Y-156500D01*
X-344083D01*
X-343417Y-156750D01*
X-343000Y-157083D01*
X-342833Y-157750D01*
X-343000Y-158417D01*
X-343500Y-158833D01*
X-344083Y-159083D01*
X-346167D01*
G01X-344083D02*
X-342833Y-161500D01*
G01X-340150Y-159250D02*
X-337483D01*
X-337733Y-158667D01*
X-338150Y-158333D01*
X-338733Y-158167D01*
X-339317Y-158250D01*
X-339817Y-158500D01*
X-340150Y-159083D01*
X-340317Y-159583D01*
Y-160083D01*
X-340150Y-160583D01*
X-339733Y-161083D01*
X-339233Y-161417D01*
X-338650Y-161500D01*
X-338067Y-161333D01*
X-337483Y-160833D01*
G01X-333300Y-161500D02*
Y-156500D01*
G01X-326200Y-161500D02*
Y-158167D01*
G01Y-158750D02*
X-326533Y-158417D01*
X-327033Y-158250D01*
X-327617Y-158167D01*
X-328200Y-158333D01*
X-328700Y-158667D01*
X-329033Y-159167D01*
X-329200Y-159833D01*
X-329033Y-160500D01*
X-328700Y-161000D01*
X-328200Y-161333D01*
X-327617Y-161500D01*
X-327033Y-161417D01*
X-326533Y-161167D01*
X-326200Y-160833D01*
G01X-322100Y-156500D02*
Y-161500D01*
G01X-323267Y-158167D02*
X-320933D01*
G01X-316500D02*
Y-161500D01*
G01Y-156833D02*
X-316667Y-156750D01*
Y-156583D01*
X-316500Y-156500D01*
X-316333Y-156583D01*
Y-156750D01*
X-316500Y-156833D01*
G01X-312400Y-158167D02*
X-310900Y-161500D01*
X-309400Y-158167D01*
G01X-306550Y-159250D02*
X-303883D01*
X-304133Y-158667D01*
X-304550Y-158333D01*
X-305133Y-158167D01*
X-305717Y-158250D01*
X-306217Y-158500D01*
X-306550Y-159083D01*
X-306717Y-159583D01*
Y-160083D01*
X-306550Y-160583D01*
X-306133Y-161083D01*
X-305633Y-161417D01*
X-305050Y-161500D01*
X-304467Y-161333D01*
X-303883Y-160833D01*
G01X-295600Y-163167D02*
Y-158167D01*
G01Y-158917D02*
X-295183Y-158500D01*
X-294767Y-158250D01*
X-294100Y-158167D01*
X-293517Y-158250D01*
X-292933Y-158667D01*
X-292683Y-159250D01*
X-292600Y-159833D01*
X-292683Y-160417D01*
X-292933Y-161000D01*
X-293433Y-161333D01*
X-294100Y-161500D01*
X-294683Y-161417D01*
X-295267Y-161167D01*
X-295600Y-160833D01*
G01X-288500Y-161500D02*
X-289000Y-161417D01*
X-289500Y-161083D01*
X-289833Y-160500D01*
X-290000Y-159833D01*
X-289833Y-159167D01*
X-289500Y-158583D01*
X-289000Y-158250D01*
X-288500Y-158167D01*
X-288000Y-158250D01*
X-287500Y-158583D01*
X-287167Y-159167D01*
X-287083Y-159833D01*
X-287167Y-160500D01*
X-287500Y-161083D01*
X-288000Y-161417D01*
X-288500Y-161500D01*
G01X-284150Y-160917D02*
X-283733Y-161250D01*
X-283150Y-161500D01*
X-282650D01*
X-282150Y-161333D01*
X-281817Y-161083D01*
X-281650Y-160750D01*
X-281733Y-160250D01*
X-282067Y-160000D01*
X-283567Y-159500D01*
X-283900Y-158917D01*
X-283733Y-158500D01*
X-283400Y-158250D01*
X-282900Y-158167D01*
X-282400Y-158250D01*
X-281900Y-158500D01*
G01X-277300Y-158167D02*
Y-161500D01*
G01Y-156833D02*
X-277467Y-156750D01*
Y-156583D01*
X-277300Y-156500D01*
X-277133Y-156583D01*
Y-156750D01*
X-277300Y-156833D01*
G01X-271700Y-156500D02*
Y-161500D01*
G01X-272867Y-158167D02*
X-270533D01*
G01X-266100D02*
Y-161500D01*
G01Y-156833D02*
X-266267Y-156750D01*
Y-156583D01*
X-266100Y-156500D01*
X-265933Y-156583D01*
Y-156750D01*
X-266100Y-156833D01*
G01X-260500Y-161500D02*
X-261000Y-161417D01*
X-261500Y-161083D01*
X-261833Y-160500D01*
X-262000Y-159833D01*
X-261833Y-159167D01*
X-261500Y-158583D01*
X-261000Y-158250D01*
X-260500Y-158167D01*
X-260000Y-158250D01*
X-259500Y-158583D01*
X-259167Y-159167D01*
X-259083Y-159833D01*
X-259167Y-160500D01*
X-259500Y-161083D01*
X-260000Y-161417D01*
X-260500Y-161500D01*
G01X-256317D02*
Y-158167D01*
G01Y-159000D02*
X-255983Y-158583D01*
X-255483Y-158250D01*
X-254817Y-158167D01*
X-254233Y-158250D01*
X-253733Y-158583D01*
X-253483Y-159167D01*
Y-161500D01*
G01X-344500Y-129500D02*
Y-134500D01*
G01X-345667Y-131167D02*
X-343333D01*
G01X-340317Y-134500D02*
Y-129500D01*
G01Y-131917D02*
X-339900Y-131500D01*
X-339483Y-131250D01*
X-338817Y-131167D01*
X-338317Y-131250D01*
X-337733Y-131583D01*
X-337483Y-132083D01*
Y-134500D01*
G01X-333300Y-131167D02*
Y-134500D01*
G01Y-129833D02*
X-333467Y-129750D01*
Y-129583D01*
X-333300Y-129500D01*
X-333133Y-129583D01*
Y-129750D01*
X-333300Y-129833D01*
G01X-326367Y-131583D02*
X-326950Y-131250D01*
X-327450Y-131167D01*
X-328117Y-131333D01*
X-328617Y-131667D01*
X-328950Y-132250D01*
X-329033Y-132833D01*
X-328950Y-133417D01*
X-328617Y-133917D01*
X-328117Y-134333D01*
X-327450Y-134500D01*
X-326867Y-134333D01*
X-326367Y-134000D01*
G01X-323517Y-134500D02*
Y-129500D01*
G01X-320850Y-131167D02*
X-323517Y-133083D01*
G01X-322433Y-132333D02*
X-320683Y-134500D01*
G01X-317917D02*
Y-131167D01*
G01Y-132000D02*
X-317583Y-131583D01*
X-317083Y-131250D01*
X-316417Y-131167D01*
X-315833Y-131250D01*
X-315333Y-131583D01*
X-315083Y-132167D01*
Y-134500D01*
G01X-312150Y-132250D02*
X-309483D01*
X-309733Y-131667D01*
X-310150Y-131333D01*
X-310733Y-131167D01*
X-311317Y-131250D01*
X-311817Y-131500D01*
X-312150Y-132083D01*
X-312317Y-132583D01*
Y-133083D01*
X-312150Y-133583D01*
X-311733Y-134083D01*
X-311233Y-134417D01*
X-310650Y-134500D01*
X-310067Y-134333D01*
X-309483Y-133833D01*
G01X-306550Y-133917D02*
X-306133Y-134250D01*
X-305550Y-134500D01*
X-305050D01*
X-304550Y-134333D01*
X-304217Y-134083D01*
X-304050Y-133750D01*
X-304133Y-133250D01*
X-304467Y-133000D01*
X-305967Y-132500D01*
X-306300Y-131917D01*
X-306133Y-131500D01*
X-305800Y-131250D01*
X-305300Y-131167D01*
X-304800Y-131250D01*
X-304300Y-131500D01*
G01X-300950Y-133917D02*
X-300533Y-134250D01*
X-299950Y-134500D01*
X-299450D01*
X-298950Y-134333D01*
X-298617Y-134083D01*
X-298450Y-133750D01*
X-298533Y-133250D01*
X-298867Y-133000D01*
X-300367Y-132500D01*
X-300700Y-131917D01*
X-300533Y-131500D01*
X-300200Y-131250D01*
X-299700Y-131167D01*
X-299200Y-131250D01*
X-298700Y-131500D01*
G01X-287000Y-134500D02*
Y-131167D01*
G01Y-131750D02*
X-287333Y-131417D01*
X-287833Y-131250D01*
X-288417Y-131167D01*
X-289000Y-131333D01*
X-289500Y-131667D01*
X-289833Y-132167D01*
X-290000Y-132833D01*
X-289833Y-133500D01*
X-289500Y-134000D01*
X-289000Y-134333D01*
X-288417Y-134500D01*
X-287833Y-134417D01*
X-287333Y-134167D01*
X-287000Y-133833D01*
G01X-283400Y-134500D02*
Y-130250D01*
X-283233Y-129833D01*
X-282900Y-129583D01*
X-282400Y-129500D01*
X-281900Y-129667D01*
X-281650Y-130083D01*
G01X-282650Y-131500D02*
X-284317D01*
G01X-277300Y-129500D02*
Y-134500D01*
G01X-278467Y-131167D02*
X-276133D01*
G01X-272950Y-132250D02*
X-270283D01*
X-270533Y-131667D01*
X-270950Y-131333D01*
X-271533Y-131167D01*
X-272117Y-131250D01*
X-272617Y-131500D01*
X-272950Y-132083D01*
X-273117Y-132583D01*
Y-133083D01*
X-272950Y-133583D01*
X-272533Y-134083D01*
X-272033Y-134417D01*
X-271450Y-134500D01*
X-270867Y-134333D01*
X-270283Y-133833D01*
G01X-267267Y-134500D02*
Y-131167D01*
G01Y-131833D02*
X-266850Y-131500D01*
X-266433Y-131250D01*
X-265850Y-131167D01*
X-265433Y-131250D01*
X-264933Y-131500D01*
G01X-256400Y-136167D02*
Y-131167D01*
G01Y-131917D02*
X-255983Y-131500D01*
X-255567Y-131250D01*
X-254900Y-131167D01*
X-254317Y-131250D01*
X-253733Y-131667D01*
X-253483Y-132250D01*
X-253400Y-132833D01*
X-253483Y-133417D01*
X-253733Y-134000D01*
X-254233Y-134333D01*
X-254900Y-134500D01*
X-255483Y-134417D01*
X-256067Y-134167D01*
X-256400Y-133833D01*
G01X-249300Y-134500D02*
Y-129500D01*
G01X-242200Y-134500D02*
Y-131167D01*
G01Y-131750D02*
X-242533Y-131417D01*
X-243033Y-131250D01*
X-243617Y-131167D01*
X-244200Y-131333D01*
X-244700Y-131667D01*
X-245033Y-132167D01*
X-245200Y-132833D01*
X-245033Y-133500D01*
X-244700Y-134000D01*
X-244200Y-134333D01*
X-243617Y-134500D01*
X-243033Y-134417D01*
X-242533Y-134167D01*
X-242200Y-133833D01*
G01X-238100Y-129500D02*
Y-134500D01*
G01X-239267Y-131167D02*
X-236933D01*
G01X-232500D02*
Y-134500D01*
G01Y-129833D02*
X-232667Y-129750D01*
Y-129583D01*
X-232500Y-129500D01*
X-232333Y-129583D01*
Y-129750D01*
X-232500Y-129833D01*
G01X-228317Y-134500D02*
Y-131167D01*
G01Y-132000D02*
X-227983Y-131583D01*
X-227483Y-131250D01*
X-226817Y-131167D01*
X-226233Y-131250D01*
X-225733Y-131583D01*
X-225483Y-132167D01*
Y-134500D01*
G01X-222467Y-135750D02*
X-221883Y-136083D01*
X-221217Y-136167D01*
X-220633Y-136083D01*
X-220133Y-135667D01*
X-219800Y-135083D01*
Y-131167D01*
G01Y-131833D02*
X-220133Y-131500D01*
X-220633Y-131250D01*
X-221217Y-131167D01*
X-221883Y-131333D01*
X-222300Y-131667D01*
X-222633Y-132250D01*
X-222800Y-132833D01*
X-222717Y-133333D01*
X-222383Y-133917D01*
X-221883Y-134333D01*
X-221217Y-134500D01*
X-220717Y-134417D01*
X-220133Y-134083D01*
X-219800Y-133750D01*
G01X-342833Y-124500D02*
X-346167D01*
Y-119500D01*
X-342833D01*
G01X-344167Y-121917D02*
X-346167D01*
G01X-340150Y-121167D02*
X-337650Y-124500D01*
G01Y-121167D02*
X-340150Y-124500D01*
G01X-333300Y-119500D02*
Y-124500D01*
G01X-334467Y-121167D02*
X-332133D01*
G01X-328950Y-122250D02*
X-326283D01*
X-326533Y-121667D01*
X-326950Y-121333D01*
X-327533Y-121167D01*
X-328117Y-121250D01*
X-328617Y-121500D01*
X-328950Y-122083D01*
X-329117Y-122583D01*
Y-123083D01*
X-328950Y-123583D01*
X-328533Y-124083D01*
X-328033Y-124417D01*
X-327450Y-124500D01*
X-326867Y-124333D01*
X-326283Y-123833D01*
G01X-323267Y-124500D02*
Y-121167D01*
G01Y-121833D02*
X-322850Y-121500D01*
X-322433Y-121250D01*
X-321850Y-121167D01*
X-321433Y-121250D01*
X-320933Y-121500D01*
G01X-317917Y-124500D02*
Y-121167D01*
G01Y-122000D02*
X-317583Y-121583D01*
X-317083Y-121250D01*
X-316417Y-121167D01*
X-315833Y-121250D01*
X-315333Y-121583D01*
X-315083Y-122167D01*
Y-124500D01*
G01X-309400D02*
Y-121167D01*
G01Y-121750D02*
X-309733Y-121417D01*
X-310233Y-121250D01*
X-310817Y-121167D01*
X-311400Y-121333D01*
X-311900Y-121667D01*
X-312233Y-122167D01*
X-312400Y-122833D01*
X-312233Y-123500D01*
X-311900Y-124000D01*
X-311400Y-124333D01*
X-310817Y-124500D01*
X-310233Y-124417D01*
X-309733Y-124167D01*
X-309400Y-123833D01*
G01X-305300Y-124500D02*
Y-119500D01*
G01X-292767Y-121583D02*
X-293350Y-121250D01*
X-293850Y-121167D01*
X-294517Y-121333D01*
X-295017Y-121667D01*
X-295350Y-122250D01*
X-295433Y-122833D01*
X-295350Y-123417D01*
X-295017Y-123917D01*
X-294517Y-124333D01*
X-293850Y-124500D01*
X-293267Y-124333D01*
X-292767Y-124000D01*
G01X-288500Y-124500D02*
X-289000Y-124417D01*
X-289500Y-124083D01*
X-289833Y-123500D01*
X-290000Y-122833D01*
X-289833Y-122167D01*
X-289500Y-121583D01*
X-289000Y-121250D01*
X-288500Y-121167D01*
X-288000Y-121250D01*
X-287500Y-121583D01*
X-287167Y-122167D01*
X-287083Y-122833D01*
X-287167Y-123500D01*
X-287500Y-124083D01*
X-288000Y-124417D01*
X-288500Y-124500D01*
G01X-284317D02*
Y-121167D01*
G01Y-122000D02*
X-283983Y-121583D01*
X-283483Y-121250D01*
X-282817Y-121167D01*
X-282233Y-121250D01*
X-281733Y-121583D01*
X-281483Y-122167D01*
Y-124500D01*
G01X-275800Y-119500D02*
Y-124500D01*
G01Y-123750D02*
X-276133Y-124167D01*
X-276633Y-124417D01*
X-277217Y-124500D01*
X-277883Y-124333D01*
X-278383Y-123917D01*
X-278717Y-123417D01*
X-278800Y-122833D01*
X-278717Y-122250D01*
X-278383Y-121750D01*
X-277883Y-121333D01*
X-277217Y-121167D01*
X-276633Y-121250D01*
X-276217Y-121417D01*
X-275800Y-121750D01*
G01X-273117Y-121167D02*
Y-123500D01*
X-272783Y-124083D01*
X-272283Y-124417D01*
X-271700Y-124500D01*
X-271117Y-124417D01*
X-270617Y-124083D01*
X-270283Y-123500D01*
G01Y-124500D02*
Y-121167D01*
G01X-264767Y-121583D02*
X-265350Y-121250D01*
X-265850Y-121167D01*
X-266517Y-121333D01*
X-267017Y-121667D01*
X-267350Y-122250D01*
X-267433Y-122833D01*
X-267350Y-123417D01*
X-267017Y-123917D01*
X-266517Y-124333D01*
X-265850Y-124500D01*
X-265267Y-124333D01*
X-264767Y-124000D01*
G01X-260500Y-119500D02*
Y-124500D01*
G01X-261667Y-121167D02*
X-259333D01*
G01X-254900Y-124500D02*
X-255400Y-124417D01*
X-255900Y-124083D01*
X-256233Y-123500D01*
X-256400Y-122833D01*
X-256233Y-122167D01*
X-255900Y-121583D01*
X-255400Y-121250D01*
X-254900Y-121167D01*
X-254400Y-121250D01*
X-253900Y-121583D01*
X-253567Y-122167D01*
X-253483Y-122833D01*
X-253567Y-123500D01*
X-253900Y-124083D01*
X-254400Y-124417D01*
X-254900Y-124500D01*
G01X-250467D02*
Y-121167D01*
G01Y-121833D02*
X-250050Y-121500D01*
X-249633Y-121250D01*
X-249050Y-121167D01*
X-248633Y-121250D01*
X-248133Y-121500D01*
G01X-346167Y83500D02*
Y78500D01*
X-342833D01*
G01X-337400D02*
Y81833D01*
G01Y81250D02*
X-337733Y81583D01*
X-338233Y81750D01*
X-338817Y81833D01*
X-339400Y81667D01*
X-339900Y81333D01*
X-340233Y80833D01*
X-340400Y80167D01*
X-340233Y79500D01*
X-339900Y79000D01*
X-339400Y78667D01*
X-338817Y78500D01*
X-338233Y78583D01*
X-337733Y78833D01*
X-337400Y79167D01*
G01X-334550Y79083D02*
X-334133Y78750D01*
X-333550Y78500D01*
X-333050D01*
X-332550Y78667D01*
X-332217Y78917D01*
X-332050Y79250D01*
X-332133Y79750D01*
X-332467Y80000D01*
X-333967Y80500D01*
X-334300Y81083D01*
X-334133Y81500D01*
X-333800Y81750D01*
X-333300Y81833D01*
X-332800Y81750D01*
X-332300Y81500D01*
G01X-328950Y80750D02*
X-326283D01*
X-326533Y81333D01*
X-326950Y81667D01*
X-327533Y81833D01*
X-328117Y81750D01*
X-328617Y81500D01*
X-328950Y80917D01*
X-329117Y80417D01*
Y79917D01*
X-328950Y79417D01*
X-328533Y78917D01*
X-328033Y78583D01*
X-327450Y78500D01*
X-326867Y78667D01*
X-326283Y79167D01*
G01X-323267Y78500D02*
Y81833D01*
G01Y81167D02*
X-322850Y81500D01*
X-322433Y81750D01*
X-321850Y81833D01*
X-321433Y81750D01*
X-320933Y81500D01*
G01X-312400Y81833D02*
X-310900Y78500D01*
X-309400Y81833D01*
G01X-305300D02*
Y78500D01*
G01Y83167D02*
X-305467Y83250D01*
Y83417D01*
X-305300Y83500D01*
X-305133Y83417D01*
Y83250D01*
X-305300Y83167D01*
G01X-298200Y78500D02*
Y81833D01*
G01Y81250D02*
X-298533Y81583D01*
X-299033Y81750D01*
X-299617Y81833D01*
X-300200Y81667D01*
X-300700Y81333D01*
X-301033Y80833D01*
X-301200Y80167D01*
X-301033Y79500D01*
X-300700Y79000D01*
X-300200Y78667D01*
X-299617Y78500D01*
X-299033Y78583D01*
X-298533Y78833D01*
X-298200Y79167D01*
G01X-290333Y78333D02*
X-286667Y82000D01*
G01X-288500Y82667D02*
Y77667D01*
G01X-286667Y78333D02*
X-290333Y82000D01*
G01X-291000Y80167D02*
X-286000D01*
G01X-283317Y76833D02*
X-284150Y77667D01*
X-284567Y78500D01*
Y81833D01*
X-284150Y82667D01*
X-283317Y83500D01*
G01X-279133Y79250D02*
X-278633Y78833D01*
X-278050Y78583D01*
X-277300Y78500D01*
X-276550Y78667D01*
X-275967Y79000D01*
X-275550Y79583D01*
X-275467Y80250D01*
X-275633Y80917D01*
X-276050Y81333D01*
X-276633Y81667D01*
X-277217Y81750D01*
X-277800Y81667D01*
X-278550Y81333D01*
X-278300Y83500D01*
X-276050D01*
G01X-271700Y78333D02*
X-271867Y78417D01*
Y78583D01*
X-271700Y78667D01*
X-271533Y78583D01*
Y78417D01*
X-271700Y78333D01*
G01X-266100Y78500D02*
Y83500D01*
X-267100Y82500D01*
G01Y78500D02*
X-265100D01*
G01X-260083Y76833D02*
X-259250Y77667D01*
X-258833Y78500D01*
Y81833D01*
X-259250Y82667D01*
X-260083Y83500D01*
G01X-353500Y91500D02*
X236000D01*
G01X-346167Y133500D02*
Y138500D01*
X-344167D01*
X-343500Y138250D01*
X-343000Y137667D01*
X-342833Y137000D01*
X-343000Y136333D01*
X-343417Y135833D01*
X-344167Y135583D01*
X-346167D01*
G01X-338900Y138500D02*
Y133500D01*
G01X-340817Y138500D02*
X-336983D01*
G01X-335050Y133500D02*
Y138500D01*
G01X-331550D02*
Y133500D01*
G01Y136000D02*
X-335050D01*
G01X-323267Y133500D02*
Y136833D01*
G01Y136167D02*
X-322850Y136500D01*
X-322433Y136750D01*
X-321850Y136833D01*
X-321433Y136750D01*
X-320933Y136500D01*
G01X-317750Y135750D02*
X-315083D01*
X-315333Y136333D01*
X-315750Y136667D01*
X-316333Y136833D01*
X-316917Y136750D01*
X-317417Y136500D01*
X-317750Y135917D01*
X-317917Y135417D01*
Y134917D01*
X-317750Y134417D01*
X-317333Y133917D01*
X-316833Y133583D01*
X-316250Y133500D01*
X-315667Y133667D01*
X-315083Y134167D01*
G01X-312067Y132250D02*
X-311483Y131917D01*
X-310817Y131833D01*
X-310233Y131917D01*
X-309733Y132333D01*
X-309400Y132917D01*
Y136833D01*
G01Y136167D02*
X-309733Y136500D01*
X-310233Y136750D01*
X-310817Y136833D01*
X-311483Y136667D01*
X-311900Y136333D01*
X-312233Y135750D01*
X-312400Y135167D01*
X-312317Y134667D01*
X-311983Y134083D01*
X-311483Y133667D01*
X-310817Y133500D01*
X-310317Y133583D01*
X-309733Y133917D01*
X-309400Y134250D01*
G01X-305300Y136833D02*
Y133500D01*
G01Y138167D02*
X-305467Y138250D01*
Y138417D01*
X-305300Y138500D01*
X-305133Y138417D01*
Y138250D01*
X-305300Y138167D01*
G01X-300950Y134083D02*
X-300533Y133750D01*
X-299950Y133500D01*
X-299450D01*
X-298950Y133667D01*
X-298617Y133917D01*
X-298450Y134250D01*
X-298533Y134750D01*
X-298867Y135000D01*
X-300367Y135500D01*
X-300700Y136083D01*
X-300533Y136500D01*
X-300200Y136750D01*
X-299700Y136833D01*
X-299200Y136750D01*
X-298700Y136500D01*
G01X-294100Y138500D02*
Y133500D01*
G01X-295267Y136833D02*
X-292933D01*
G01X-289667Y133500D02*
Y136833D01*
G01Y136167D02*
X-289250Y136500D01*
X-288833Y136750D01*
X-288250Y136833D01*
X-287833Y136750D01*
X-287333Y136500D01*
G01X-281400Y133500D02*
Y136833D01*
G01Y136250D02*
X-281733Y136583D01*
X-282233Y136750D01*
X-282817Y136833D01*
X-283400Y136667D01*
X-283900Y136333D01*
X-284233Y135833D01*
X-284400Y135167D01*
X-284233Y134500D01*
X-283900Y134000D01*
X-283400Y133667D01*
X-282817Y133500D01*
X-282233Y133583D01*
X-281733Y133833D01*
X-281400Y134167D01*
G01X-277300Y138500D02*
Y133500D01*
G01X-278467Y136833D02*
X-276133D01*
G01X-271700D02*
Y133500D01*
G01Y138167D02*
X-271867Y138250D01*
Y138417D01*
X-271700Y138500D01*
X-271533Y138417D01*
Y138250D01*
X-271700Y138167D01*
G01X-266100Y133500D02*
X-266600Y133583D01*
X-267100Y133917D01*
X-267433Y134500D01*
X-267600Y135167D01*
X-267433Y135833D01*
X-267100Y136417D01*
X-266600Y136750D01*
X-266100Y136833D01*
X-265600Y136750D01*
X-265100Y136417D01*
X-264767Y135833D01*
X-264683Y135167D01*
X-264767Y134500D01*
X-265100Y133917D01*
X-265600Y133583D01*
X-266100Y133500D01*
G01X-261917D02*
Y136833D01*
G01Y136000D02*
X-261583Y136417D01*
X-261083Y136750D01*
X-260417Y136833D01*
X-259833Y136750D01*
X-259333Y136417D01*
X-259083Y135833D01*
Y133500D01*
G01X-346333Y160000D02*
Y165000D01*
X-344667D01*
X-344000Y164750D01*
X-343500Y164417D01*
X-343083Y163917D01*
X-342750Y163333D01*
X-342667Y162500D01*
X-342750Y161667D01*
X-343083Y161083D01*
X-343500Y160583D01*
X-344000Y160250D01*
X-344667Y160000D01*
X-346333D01*
G01X-340150Y162250D02*
X-337483D01*
X-337733Y162833D01*
X-338150Y163167D01*
X-338733Y163333D01*
X-339317Y163250D01*
X-339817Y163000D01*
X-340150Y162417D01*
X-340317Y161917D01*
Y161417D01*
X-340150Y160917D01*
X-339733Y160417D01*
X-339233Y160083D01*
X-338650Y160000D01*
X-338067Y160167D01*
X-337483Y160667D01*
G01X-334800Y158333D02*
Y163333D01*
G01Y162583D02*
X-334383Y163000D01*
X-333967Y163250D01*
X-333300Y163333D01*
X-332717Y163250D01*
X-332133Y162833D01*
X-331883Y162250D01*
X-331800Y161667D01*
X-331883Y161083D01*
X-332133Y160500D01*
X-332633Y160167D01*
X-333300Y160000D01*
X-333883Y160083D01*
X-334467Y160333D01*
X-334800Y160667D01*
G01X-327700Y165000D02*
Y160000D01*
G01X-328867Y163333D02*
X-326533D01*
G01X-323517Y160000D02*
Y165000D01*
G01Y162583D02*
X-323100Y163000D01*
X-322683Y163250D01*
X-322017Y163333D01*
X-321517Y163250D01*
X-320933Y162917D01*
X-320683Y162417D01*
Y160000D01*
G01X-309567Y162917D02*
X-310150Y163250D01*
X-310650Y163333D01*
X-311317Y163167D01*
X-311817Y162833D01*
X-312150Y162250D01*
X-312233Y161667D01*
X-312150Y161083D01*
X-311817Y160583D01*
X-311317Y160167D01*
X-310650Y160000D01*
X-310067Y160167D01*
X-309567Y160500D01*
G01X-305300Y160000D02*
X-305800Y160083D01*
X-306300Y160417D01*
X-306633Y161000D01*
X-306800Y161667D01*
X-306633Y162333D01*
X-306300Y162917D01*
X-305800Y163250D01*
X-305300Y163333D01*
X-304800Y163250D01*
X-304300Y162917D01*
X-303967Y162333D01*
X-303883Y161667D01*
X-303967Y161000D01*
X-304300Y160417D01*
X-304800Y160083D01*
X-305300Y160000D01*
G01X-301117D02*
Y163333D01*
G01Y162500D02*
X-300783Y162917D01*
X-300283Y163250D01*
X-299617Y163333D01*
X-299033Y163250D01*
X-298533Y162917D01*
X-298283Y162333D01*
Y160000D01*
G01X-294100Y165000D02*
Y160000D01*
G01X-295267Y163333D02*
X-292933D01*
G01X-289667Y160000D02*
Y163333D01*
G01Y162667D02*
X-289250Y163000D01*
X-288833Y163250D01*
X-288250Y163333D01*
X-287833Y163250D01*
X-287333Y163000D01*
G01X-282900Y160000D02*
X-283400Y160083D01*
X-283900Y160417D01*
X-284233Y161000D01*
X-284400Y161667D01*
X-284233Y162333D01*
X-283900Y162917D01*
X-283400Y163250D01*
X-282900Y163333D01*
X-282400Y163250D01*
X-281900Y162917D01*
X-281567Y162333D01*
X-281483Y161667D01*
X-281567Y161000D01*
X-281900Y160417D01*
X-282400Y160083D01*
X-282900Y160000D01*
G01X-277300D02*
Y165000D01*
G01X-267517Y160000D02*
Y165000D01*
G01Y162583D02*
X-267100Y163000D01*
X-266683Y163250D01*
X-266017Y163333D01*
X-265517Y163250D01*
X-264933Y162917D01*
X-264683Y162417D01*
Y160000D01*
G01X-260500D02*
X-261000Y160083D01*
X-261500Y160417D01*
X-261833Y161000D01*
X-262000Y161667D01*
X-261833Y162333D01*
X-261500Y162917D01*
X-261000Y163250D01*
X-260500Y163333D01*
X-260000Y163250D01*
X-259500Y162917D01*
X-259167Y162333D01*
X-259083Y161667D01*
X-259167Y161000D01*
X-259500Y160417D01*
X-260000Y160083D01*
X-260500Y160000D01*
G01X-254900D02*
Y165000D01*
G01X-250550Y162250D02*
X-247883D01*
X-248133Y162833D01*
X-248550Y163167D01*
X-249133Y163333D01*
X-249717Y163250D01*
X-250217Y163000D01*
X-250550Y162417D01*
X-250717Y161917D01*
Y161417D01*
X-250550Y160917D01*
X-250133Y160417D01*
X-249633Y160083D01*
X-249050Y160000D01*
X-248467Y160167D01*
X-247883Y160667D01*
G01X-355000Y151000D02*
X236000D01*
G01X-355000Y176000D02*
X236000D01*
G01X-346167Y182000D02*
Y187000D01*
X-344083D01*
X-343417Y186750D01*
X-343000Y186417D01*
X-342833Y185750D01*
X-343000Y185083D01*
X-343500Y184667D01*
X-344083Y184417D01*
X-346167D01*
G01X-344083D02*
X-342833Y182000D01*
G01X-338900D02*
X-339400Y182083D01*
X-339900Y182417D01*
X-340233Y183000D01*
X-340400Y183667D01*
X-340233Y184333D01*
X-339900Y184917D01*
X-339400Y185250D01*
X-338900Y185333D01*
X-338400Y185250D01*
X-337900Y184917D01*
X-337567Y184333D01*
X-337483Y183667D01*
X-337567Y183000D01*
X-337900Y182417D01*
X-338400Y182083D01*
X-338900Y182000D01*
G01X-334717Y185333D02*
Y183000D01*
X-334383Y182417D01*
X-333883Y182083D01*
X-333300Y182000D01*
X-332717Y182083D01*
X-332217Y182417D01*
X-331883Y183000D01*
G01Y182000D02*
Y185333D01*
G01X-328867Y180750D02*
X-328283Y180417D01*
X-327617Y180333D01*
X-327033Y180417D01*
X-326533Y180833D01*
X-326200Y181417D01*
Y185333D01*
G01Y184667D02*
X-326533Y185000D01*
X-327033Y185250D01*
X-327617Y185333D01*
X-328283Y185167D01*
X-328700Y184833D01*
X-329033Y184250D01*
X-329200Y183667D01*
X-329117Y183167D01*
X-328783Y182583D01*
X-328283Y182167D01*
X-327617Y182000D01*
X-327117Y182083D01*
X-326533Y182417D01*
X-326200Y182750D01*
G01X-323517Y182000D02*
Y187000D01*
G01Y184583D02*
X-323100Y185000D01*
X-322683Y185250D01*
X-322017Y185333D01*
X-321517Y185250D01*
X-320933Y184917D01*
X-320683Y184417D01*
Y182000D01*
G01X-317917D02*
Y185333D01*
G01Y184500D02*
X-317583Y184917D01*
X-317083Y185250D01*
X-316417Y185333D01*
X-315833Y185250D01*
X-315333Y184917D01*
X-315083Y184333D01*
Y182000D01*
G01X-312150Y184250D02*
X-309483D01*
X-309733Y184833D01*
X-310150Y185167D01*
X-310733Y185333D01*
X-311317Y185250D01*
X-311817Y185000D01*
X-312150Y184417D01*
X-312317Y183917D01*
Y183417D01*
X-312150Y182917D01*
X-311733Y182417D01*
X-311233Y182083D01*
X-310650Y182000D01*
X-310067Y182167D01*
X-309483Y182667D01*
G01X-306550Y182583D02*
X-306133Y182250D01*
X-305550Y182000D01*
X-305050D01*
X-304550Y182167D01*
X-304217Y182417D01*
X-304050Y182750D01*
X-304133Y183250D01*
X-304467Y183500D01*
X-305967Y184000D01*
X-306300Y184583D01*
X-306133Y185000D01*
X-305800Y185250D01*
X-305300Y185333D01*
X-304800Y185250D01*
X-304300Y185000D01*
G01X-300950Y182583D02*
X-300533Y182250D01*
X-299950Y182000D01*
X-299450D01*
X-298950Y182167D01*
X-298617Y182417D01*
X-298450Y182750D01*
X-298533Y183250D01*
X-298867Y183500D01*
X-300367Y184000D01*
X-300700Y184583D01*
X-300533Y185000D01*
X-300200Y185250D01*
X-299700Y185333D01*
X-299200Y185250D01*
X-298700Y185000D01*
G01X-354500Y191000D02*
X236000D01*
G01X-346250Y240500D02*
Y245500D01*
G01X-342750D02*
Y240500D01*
G01Y243000D02*
X-346250D01*
G01X-338900Y240500D02*
X-339400Y240583D01*
X-339900Y240917D01*
X-340233Y241500D01*
X-340400Y242167D01*
X-340233Y242833D01*
X-339900Y243417D01*
X-339400Y243750D01*
X-338900Y243833D01*
X-338400Y243750D01*
X-337900Y243417D01*
X-337567Y242833D01*
X-337483Y242167D01*
X-337567Y241500D01*
X-337900Y240917D01*
X-338400Y240583D01*
X-338900Y240500D01*
G01X-333300D02*
Y245500D01*
G01X-328950Y242750D02*
X-326283D01*
X-326533Y243333D01*
X-326950Y243667D01*
X-327533Y243833D01*
X-328117Y243750D01*
X-328617Y243500D01*
X-328950Y242917D01*
X-329117Y242417D01*
Y241917D01*
X-328950Y241417D01*
X-328533Y240917D01*
X-328033Y240583D01*
X-327450Y240500D01*
X-326867Y240667D01*
X-326283Y241167D01*
G01X-317750Y241083D02*
X-317333Y240750D01*
X-316750Y240500D01*
X-316250D01*
X-315750Y240667D01*
X-315417Y240917D01*
X-315250Y241250D01*
X-315333Y241750D01*
X-315667Y242000D01*
X-317167Y242500D01*
X-317500Y243083D01*
X-317333Y243500D01*
X-317000Y243750D01*
X-316500Y243833D01*
X-316000Y243750D01*
X-315500Y243500D01*
G01X-310900Y243833D02*
Y240500D01*
G01Y245167D02*
X-311067Y245250D01*
Y245417D01*
X-310900Y245500D01*
X-310733Y245417D01*
Y245250D01*
X-310900Y245167D01*
G01X-306550Y243833D02*
X-304050D01*
X-306550Y240500D01*
X-304050D01*
G01X-300950Y242750D02*
X-298283D01*
X-298533Y243333D01*
X-298950Y243667D01*
X-299533Y243833D01*
X-300117Y243750D01*
X-300617Y243500D01*
X-300950Y242917D01*
X-301117Y242417D01*
Y241917D01*
X-300950Y241417D01*
X-300533Y240917D01*
X-300033Y240583D01*
X-299450Y240500D01*
X-298867Y240667D01*
X-298283Y241167D01*
G01X-346250Y315500D02*
Y320500D01*
G01X-342750D02*
Y315500D01*
G01Y318000D02*
X-346250D01*
G01X-338900Y315500D02*
X-339400Y315583D01*
X-339900Y315917D01*
X-340233Y316500D01*
X-340400Y317167D01*
X-340233Y317833D01*
X-339900Y318417D01*
X-339400Y318750D01*
X-338900Y318833D01*
X-338400Y318750D01*
X-337900Y318417D01*
X-337567Y317833D01*
X-337483Y317167D01*
X-337567Y316500D01*
X-337900Y315917D01*
X-338400Y315583D01*
X-338900Y315500D01*
G01X-333300D02*
Y320500D01*
G01X-328950Y317750D02*
X-326283D01*
X-326533Y318333D01*
X-326950Y318667D01*
X-327533Y318833D01*
X-328117Y318750D01*
X-328617Y318500D01*
X-328950Y317917D01*
X-329117Y317417D01*
Y316917D01*
X-328950Y316417D01*
X-328533Y315917D01*
X-328033Y315583D01*
X-327450Y315500D01*
X-326867Y315667D01*
X-326283Y316167D01*
G01X-318000Y313833D02*
Y318833D01*
G01Y318083D02*
X-317583Y318500D01*
X-317167Y318750D01*
X-316500Y318833D01*
X-315917Y318750D01*
X-315333Y318333D01*
X-315083Y317750D01*
X-315000Y317167D01*
X-315083Y316583D01*
X-315333Y316000D01*
X-315833Y315667D01*
X-316500Y315500D01*
X-317083Y315583D01*
X-317667Y315833D01*
X-318000Y316167D01*
G01X-310900Y315500D02*
X-311400Y315583D01*
X-311900Y315917D01*
X-312233Y316500D01*
X-312400Y317167D01*
X-312233Y317833D01*
X-311900Y318417D01*
X-311400Y318750D01*
X-310900Y318833D01*
X-310400Y318750D01*
X-309900Y318417D01*
X-309567Y317833D01*
X-309483Y317167D01*
X-309567Y316500D01*
X-309900Y315917D01*
X-310400Y315583D01*
X-310900Y315500D01*
G01X-306550Y316083D02*
X-306133Y315750D01*
X-305550Y315500D01*
X-305050D01*
X-304550Y315667D01*
X-304217Y315917D01*
X-304050Y316250D01*
X-304133Y316750D01*
X-304467Y317000D01*
X-305967Y317500D01*
X-306300Y318083D01*
X-306133Y318500D01*
X-305800Y318750D01*
X-305300Y318833D01*
X-304800Y318750D01*
X-304300Y318500D01*
G01X-299700Y318833D02*
Y315500D01*
G01Y320167D02*
X-299867Y320250D01*
Y320417D01*
X-299700Y320500D01*
X-299533Y320417D01*
Y320250D01*
X-299700Y320167D01*
G01X-294100Y320500D02*
Y315500D01*
G01X-295267Y318833D02*
X-292933D01*
G01X-288500D02*
Y315500D01*
G01Y320167D02*
X-288667Y320250D01*
Y320417D01*
X-288500Y320500D01*
X-288333Y320417D01*
Y320250D01*
X-288500Y320167D01*
G01X-282900Y315500D02*
X-283400Y315583D01*
X-283900Y315917D01*
X-284233Y316500D01*
X-284400Y317167D01*
X-284233Y317833D01*
X-283900Y318417D01*
X-283400Y318750D01*
X-282900Y318833D01*
X-282400Y318750D01*
X-281900Y318417D01*
X-281567Y317833D01*
X-281483Y317167D01*
X-281567Y316500D01*
X-281900Y315917D01*
X-282400Y315583D01*
X-282900Y315500D01*
G01X-278717D02*
Y318833D01*
G01Y318000D02*
X-278383Y318417D01*
X-277883Y318750D01*
X-277217Y318833D01*
X-276633Y318750D01*
X-276133Y318417D01*
X-275883Y317833D01*
Y315500D01*
G01X-266100Y320500D02*
Y315500D01*
G01X-267267Y318833D02*
X-264933D01*
G01X-260500Y315500D02*
X-261000Y315583D01*
X-261500Y315917D01*
X-261833Y316500D01*
X-262000Y317167D01*
X-261833Y317833D01*
X-261500Y318417D01*
X-261000Y318750D01*
X-260500Y318833D01*
X-260000Y318750D01*
X-259500Y318417D01*
X-259167Y317833D01*
X-259083Y317167D01*
X-259167Y316500D01*
X-259500Y315917D01*
X-260000Y315583D01*
X-260500Y315500D01*
G01X-254900D02*
Y320500D01*
G01X-250550Y317750D02*
X-247883D01*
X-248133Y318333D01*
X-248550Y318667D01*
X-249133Y318833D01*
X-249717Y318750D01*
X-250217Y318500D01*
X-250550Y317917D01*
X-250717Y317417D01*
Y316917D01*
X-250550Y316417D01*
X-250133Y315917D01*
X-249633Y315583D01*
X-249050Y315500D01*
X-248467Y315667D01*
X-247883Y316167D01*
G01X-244867Y315500D02*
Y318833D01*
G01Y318167D02*
X-244450Y318500D01*
X-244033Y318750D01*
X-243450Y318833D01*
X-243033Y318750D01*
X-242533Y318500D01*
G01X-236600Y315500D02*
Y318833D01*
G01Y318250D02*
X-236933Y318583D01*
X-237433Y318750D01*
X-238017Y318833D01*
X-238600Y318667D01*
X-239100Y318333D01*
X-239433Y317833D01*
X-239600Y317167D01*
X-239433Y316500D01*
X-239100Y316000D01*
X-238600Y315667D01*
X-238017Y315500D01*
X-237433Y315583D01*
X-236933Y315833D01*
X-236600Y316167D01*
G01X-233917Y315500D02*
Y318833D01*
G01Y318000D02*
X-233583Y318417D01*
X-233083Y318750D01*
X-232417Y318833D01*
X-231833Y318750D01*
X-231333Y318417D01*
X-231083Y317833D01*
Y315500D01*
G01X-225567Y318417D02*
X-226150Y318750D01*
X-226650Y318833D01*
X-227317Y318667D01*
X-227817Y318333D01*
X-228150Y317750D01*
X-228233Y317167D01*
X-228150Y316583D01*
X-227817Y316083D01*
X-227317Y315667D01*
X-226650Y315500D01*
X-226067Y315667D01*
X-225567Y316000D01*
G01X-222550Y317750D02*
X-219883D01*
X-220133Y318333D01*
X-220550Y318667D01*
X-221133Y318833D01*
X-221717Y318750D01*
X-222217Y318500D01*
X-222550Y317917D01*
X-222717Y317417D01*
Y316917D01*
X-222550Y316417D01*
X-222133Y315917D01*
X-221633Y315583D01*
X-221050Y315500D01*
X-220467Y315667D01*
X-219883Y316167D01*
G01X-355000Y311000D02*
X236000D01*
G01X-346583Y337000D02*
X-344500Y332000D01*
X-342417Y337000D01*
G01X-338900Y335333D02*
Y332000D01*
G01Y336667D02*
X-339067Y336750D01*
Y336917D01*
X-338900Y337000D01*
X-338733Y336917D01*
Y336750D01*
X-338900Y336667D01*
G01X-331800Y332000D02*
Y335333D01*
G01Y334750D02*
X-332133Y335083D01*
X-332633Y335250D01*
X-333217Y335333D01*
X-333800Y335167D01*
X-334300Y334833D01*
X-334633Y334333D01*
X-334800Y333667D01*
X-334633Y333000D01*
X-334300Y332500D01*
X-333800Y332167D01*
X-333217Y332000D01*
X-332633Y332083D01*
X-332133Y332333D01*
X-331800Y332667D01*
G01X-323517Y332000D02*
Y337000D01*
G01Y334583D02*
X-323100Y335000D01*
X-322683Y335250D01*
X-322017Y335333D01*
X-321517Y335250D01*
X-320933Y334917D01*
X-320683Y334417D01*
Y332000D01*
G01X-316500D02*
X-317000Y332083D01*
X-317500Y332417D01*
X-317833Y333000D01*
X-318000Y333667D01*
X-317833Y334333D01*
X-317500Y334917D01*
X-317000Y335250D01*
X-316500Y335333D01*
X-316000Y335250D01*
X-315500Y334917D01*
X-315167Y334333D01*
X-315083Y333667D01*
X-315167Y333000D01*
X-315500Y332417D01*
X-316000Y332083D01*
X-316500Y332000D01*
G01X-310900D02*
Y337000D01*
G01X-306550Y334250D02*
X-303883D01*
X-304133Y334833D01*
X-304550Y335167D01*
X-305133Y335333D01*
X-305717Y335250D01*
X-306217Y335000D01*
X-306550Y334417D01*
X-306717Y333917D01*
Y333417D01*
X-306550Y332917D01*
X-306133Y332417D01*
X-305633Y332083D01*
X-305050Y332000D01*
X-304467Y332167D01*
X-303883Y332667D01*
G01X-294100Y337000D02*
Y332000D01*
G01X-295267Y335333D02*
X-292933D01*
G01X-289917Y332000D02*
Y337000D01*
G01Y334583D02*
X-289500Y335000D01*
X-289083Y335250D01*
X-288417Y335333D01*
X-287917Y335250D01*
X-287333Y334917D01*
X-287083Y334417D01*
Y332000D01*
G01X-284150Y334250D02*
X-281483D01*
X-281733Y334833D01*
X-282150Y335167D01*
X-282733Y335333D01*
X-283317Y335250D01*
X-283817Y335000D01*
X-284150Y334417D01*
X-284317Y333917D01*
Y333417D01*
X-284150Y332917D01*
X-283733Y332417D01*
X-283233Y332083D01*
X-282650Y332000D01*
X-282067Y332167D01*
X-281483Y332667D01*
G01X-278467Y332000D02*
Y335333D01*
G01Y334667D02*
X-278050Y335000D01*
X-277633Y335250D01*
X-277050Y335333D01*
X-276633Y335250D01*
X-276133Y335000D01*
G01X-274200Y332000D02*
Y335333D01*
G01Y334417D02*
X-273950Y334833D01*
X-273533Y335167D01*
X-272950Y335333D01*
X-272367Y335167D01*
X-271950Y334833D01*
X-271700Y334417D01*
Y332000D01*
G01Y334417D02*
X-271450Y334833D01*
X-271033Y335167D01*
X-270450Y335333D01*
X-269867Y335167D01*
X-269450Y334833D01*
X-269200Y334333D01*
Y332000D01*
G01X-264600D02*
Y335333D01*
G01Y334750D02*
X-264933Y335083D01*
X-265433Y335250D01*
X-266017Y335333D01*
X-266600Y335167D01*
X-267100Y334833D01*
X-267433Y334333D01*
X-267600Y333667D01*
X-267433Y333000D01*
X-267100Y332500D01*
X-266600Y332167D01*
X-266017Y332000D01*
X-265433Y332083D01*
X-264933Y332333D01*
X-264600Y332667D01*
G01X-260500Y332000D02*
Y337000D01*
G01X-250800Y330333D02*
Y335333D01*
G01Y334583D02*
X-250383Y335000D01*
X-249967Y335250D01*
X-249300Y335333D01*
X-248717Y335250D01*
X-248133Y334833D01*
X-247883Y334250D01*
X-247800Y333667D01*
X-247883Y333083D01*
X-248133Y332500D01*
X-248633Y332167D01*
X-249300Y332000D01*
X-249883Y332083D01*
X-250467Y332333D01*
X-250800Y332667D01*
G01X-242200Y332000D02*
Y335333D01*
G01Y334750D02*
X-242533Y335083D01*
X-243033Y335250D01*
X-243617Y335333D01*
X-244200Y335167D01*
X-244700Y334833D01*
X-245033Y334333D01*
X-245200Y333667D01*
X-245033Y333000D01*
X-244700Y332500D01*
X-244200Y332167D01*
X-243617Y332000D01*
X-243033Y332083D01*
X-242533Y332333D01*
X-242200Y332667D01*
G01X-236600Y337000D02*
Y332000D01*
G01Y332750D02*
X-236933Y332333D01*
X-237433Y332083D01*
X-238017Y332000D01*
X-238683Y332167D01*
X-239183Y332583D01*
X-239517Y333083D01*
X-239600Y333667D01*
X-239517Y334250D01*
X-239183Y334750D01*
X-238683Y335167D01*
X-238017Y335333D01*
X-237433Y335250D01*
X-237017Y335083D01*
X-236600Y334750D01*
G01X-355000Y341000D02*
X236000D01*
G01X-346583Y347000D02*
X-344500Y352000D01*
X-342417Y347000D01*
G01X-343167Y348750D02*
X-345833D01*
G01X-340317Y347000D02*
Y350333D01*
G01Y349500D02*
X-339983Y349917D01*
X-339483Y350250D01*
X-338817Y350333D01*
X-338233Y350250D01*
X-337733Y349917D01*
X-337483Y349333D01*
Y347000D01*
G01X-333300Y352000D02*
Y347000D01*
G01X-334467Y350333D02*
X-332133D01*
G01X-327700D02*
Y347000D01*
G01Y351667D02*
X-327867Y351750D01*
Y351917D01*
X-327700Y352000D01*
X-327533Y351917D01*
Y351750D01*
X-327700Y351667D01*
G01X-323183Y348667D02*
X-321017D01*
G01X-312400Y345333D02*
Y350333D01*
G01Y349583D02*
X-311983Y350000D01*
X-311567Y350250D01*
X-310900Y350333D01*
X-310317Y350250D01*
X-309733Y349833D01*
X-309483Y349250D01*
X-309400Y348667D01*
X-309483Y348083D01*
X-309733Y347500D01*
X-310233Y347167D01*
X-310900Y347000D01*
X-311483Y347083D01*
X-312067Y347333D01*
X-312400Y347667D01*
G01X-303800Y347000D02*
Y350333D01*
G01Y349750D02*
X-304133Y350083D01*
X-304633Y350250D01*
X-305217Y350333D01*
X-305800Y350167D01*
X-306300Y349833D01*
X-306633Y349333D01*
X-306800Y348667D01*
X-306633Y348000D01*
X-306300Y347500D01*
X-305800Y347167D01*
X-305217Y347000D01*
X-304633Y347083D01*
X-304133Y347333D01*
X-303800Y347667D01*
G01X-298200Y352000D02*
Y347000D01*
G01Y347750D02*
X-298533Y347333D01*
X-299033Y347083D01*
X-299617Y347000D01*
X-300283Y347167D01*
X-300783Y347583D01*
X-301117Y348083D01*
X-301200Y348667D01*
X-301117Y349250D01*
X-300783Y349750D01*
X-300283Y350167D01*
X-299617Y350333D01*
X-299033Y350250D01*
X-298617Y350083D01*
X-298200Y349750D01*
G01X-355000Y356000D02*
X236000D01*
G01X-346657Y366590D02*
Y371590D01*
X-342823Y366590D01*
Y371590D01*
G01X-339140Y366590D02*
X-339640Y366673D01*
X-340140Y367007D01*
X-340473Y367590D01*
X-340640Y368257D01*
X-340473Y368923D01*
X-340140Y369507D01*
X-339640Y369840D01*
X-339140Y369923D01*
X-338640Y369840D01*
X-338140Y369507D01*
X-337807Y368923D01*
X-337723Y368257D01*
X-337807Y367590D01*
X-338140Y367007D01*
X-338640Y366673D01*
X-339140Y366590D01*
G01X-334957D02*
Y369923D01*
G01Y369090D02*
X-334623Y369507D01*
X-334123Y369840D01*
X-333457Y369923D01*
X-332873Y369840D01*
X-332373Y369507D01*
X-332123Y368923D01*
Y366590D01*
G01X-329023Y368257D02*
X-326857D01*
G01X-322840Y366590D02*
Y370840D01*
X-322673Y371257D01*
X-322340Y371507D01*
X-321840Y371590D01*
X-321340Y371423D01*
X-321090Y371007D01*
G01X-322090Y369590D02*
X-323757D01*
G01X-318157Y369923D02*
Y367590D01*
X-317823Y367007D01*
X-317323Y366673D01*
X-316740Y366590D01*
X-316157Y366673D01*
X-315657Y367007D01*
X-315323Y367590D01*
G01Y366590D02*
Y369923D01*
G01X-312557Y366590D02*
Y369923D01*
G01Y369090D02*
X-312223Y369507D01*
X-311723Y369840D01*
X-311057Y369923D01*
X-310473Y369840D01*
X-309973Y369507D01*
X-309723Y368923D01*
Y366590D01*
G01X-304207Y369507D02*
X-304790Y369840D01*
X-305290Y369923D01*
X-305957Y369757D01*
X-306457Y369423D01*
X-306790Y368840D01*
X-306873Y368257D01*
X-306790Y367673D01*
X-306457Y367173D01*
X-305957Y366757D01*
X-305290Y366590D01*
X-304707Y366757D01*
X-304207Y367090D01*
G01X-299940Y371590D02*
Y366590D01*
G01X-301107Y369923D02*
X-298773D01*
G01X-294340D02*
Y366590D01*
G01Y371257D02*
X-294507Y371340D01*
Y371507D01*
X-294340Y371590D01*
X-294173Y371507D01*
Y371340D01*
X-294340Y371257D01*
G01X-288740Y366590D02*
X-289240Y366673D01*
X-289740Y367007D01*
X-290073Y367590D01*
X-290240Y368257D01*
X-290073Y368923D01*
X-289740Y369507D01*
X-289240Y369840D01*
X-288740Y369923D01*
X-288240Y369840D01*
X-287740Y369507D01*
X-287407Y368923D01*
X-287323Y368257D01*
X-287407Y367590D01*
X-287740Y367007D01*
X-288240Y366673D01*
X-288740Y366590D01*
G01X-284557D02*
Y369923D01*
G01Y369090D02*
X-284223Y369507D01*
X-283723Y369840D01*
X-283057Y369923D01*
X-282473Y369840D01*
X-281973Y369507D01*
X-281723Y368923D01*
Y366590D01*
G01X-276040D02*
Y369923D01*
G01Y369340D02*
X-276373Y369673D01*
X-276873Y369840D01*
X-277457Y369923D01*
X-278040Y369757D01*
X-278540Y369423D01*
X-278873Y368923D01*
X-279040Y368257D01*
X-278873Y367590D01*
X-278540Y367090D01*
X-278040Y366757D01*
X-277457Y366590D01*
X-276873Y366673D01*
X-276373Y366923D01*
X-276040Y367257D01*
G01X-271940Y366590D02*
Y371590D01*
G01X-262240Y364923D02*
Y369923D01*
G01Y369173D02*
X-261823Y369590D01*
X-261407Y369840D01*
X-260740Y369923D01*
X-260157Y369840D01*
X-259573Y369423D01*
X-259323Y368840D01*
X-259240Y368257D01*
X-259323Y367673D01*
X-259573Y367090D01*
X-260073Y366757D01*
X-260740Y366590D01*
X-261323Y366673D01*
X-261907Y366923D01*
X-262240Y367257D01*
G01X-253640Y366590D02*
Y369923D01*
G01Y369340D02*
X-253973Y369673D01*
X-254473Y369840D01*
X-255057Y369923D01*
X-255640Y369757D01*
X-256140Y369423D01*
X-256473Y368923D01*
X-256640Y368257D01*
X-256473Y367590D01*
X-256140Y367090D01*
X-255640Y366757D01*
X-255057Y366590D01*
X-254473Y366673D01*
X-253973Y366923D01*
X-253640Y367257D01*
G01X-248040Y371590D02*
Y366590D01*
G01Y367340D02*
X-248373Y366923D01*
X-248873Y366673D01*
X-249457Y366590D01*
X-250123Y366757D01*
X-250623Y367173D01*
X-250957Y367673D01*
X-251040Y368257D01*
X-250957Y368840D01*
X-250623Y369340D01*
X-250123Y369757D01*
X-249457Y369923D01*
X-248873Y369840D01*
X-248457Y369673D01*
X-248040Y369340D01*
G01X-298167Y395083D02*
X-298667Y395333D01*
X-299250Y395500D01*
X-299917D01*
X-300667Y395250D01*
X-301250Y394833D01*
X-301667Y394333D01*
X-302000Y393500D01*
X-302083Y392750D01*
X-301917Y392000D01*
X-301667Y391500D01*
X-301167Y391000D01*
X-300583Y390667D01*
X-300000Y390500D01*
X-299417D01*
X-298833Y390667D01*
X-298333Y390917D01*
X-297917Y391250D01*
G01X-294400Y390500D02*
Y395500D01*
G01X-287300Y390500D02*
Y393833D01*
G01Y393250D02*
X-287633Y393583D01*
X-288133Y393750D01*
X-288717Y393833D01*
X-289300Y393667D01*
X-289800Y393333D01*
X-290133Y392833D01*
X-290300Y392167D01*
X-290133Y391500D01*
X-289800Y391000D01*
X-289300Y390667D01*
X-288717Y390500D01*
X-288133Y390583D01*
X-287633Y390833D01*
X-287300Y391167D01*
G01X-284450Y391083D02*
X-284033Y390750D01*
X-283450Y390500D01*
X-282950D01*
X-282450Y390667D01*
X-282117Y390917D01*
X-281950Y391250D01*
X-282033Y391750D01*
X-282367Y392000D01*
X-283867Y392500D01*
X-284200Y393083D01*
X-284033Y393500D01*
X-283700Y393750D01*
X-283200Y393833D01*
X-282700Y393750D01*
X-282200Y393500D01*
G01X-278850Y391083D02*
X-278433Y390750D01*
X-277850Y390500D01*
X-277350D01*
X-276850Y390667D01*
X-276517Y390917D01*
X-276350Y391250D01*
X-276433Y391750D01*
X-276767Y392000D01*
X-278267Y392500D01*
X-278600Y393083D01*
X-278433Y393500D01*
X-278100Y393750D01*
X-277600Y393833D01*
X-277100Y393750D01*
X-276600Y393500D01*
G01X-272000Y393833D02*
Y390500D01*
G01Y395167D02*
X-272167Y395250D01*
Y395417D01*
X-272000Y395500D01*
X-271833Y395417D01*
Y395250D01*
X-272000Y395167D01*
G01X-266900Y390500D02*
Y394750D01*
X-266733Y395167D01*
X-266400Y395417D01*
X-265900Y395500D01*
X-265400Y395333D01*
X-265150Y394917D01*
G01X-266150Y393500D02*
X-267817D01*
G01X-262550Y389000D02*
X-262050Y388833D01*
X-261383Y389000D01*
X-260967Y389333D01*
X-260633Y389750D01*
X-260133Y391083D01*
X-259050Y393833D01*
G01X-261717D02*
X-260133Y391083D01*
G01X-196000Y-342500D02*
Y166000D01*
G01X-194500Y-312500D02*
X236000D01*
G01X-194500Y-267500D02*
X236000D01*
G01X-194500Y-232500D02*
X236000D01*
G01X-194500Y-197500D02*
X236000D01*
G01X-194500Y-182500D02*
X236000D01*
G01X-194500Y-137500D02*
X236000D01*
G01X-194500Y-112500D02*
X236000D01*
G01X-196000Y-35500D02*
X236000D01*
G01X-196000Y17500D02*
X236000D01*
G01X-196000Y124000D02*
Y406000D01*
G01Y206000D02*
X236000D01*
G01X-196000Y221000D02*
X236000D01*
G01X-196000Y236000D02*
X236000D01*
G01X-196000Y251000D02*
X236000D01*
G01X-196000Y266000D02*
X236000D01*
G01X-196000Y281000D02*
X236000D01*
G01X-196000Y296000D02*
X236000D01*
G01X-184500Y-336500D02*
Y-333167D01*
G01Y-333750D02*
X-184833Y-333417D01*
X-185333Y-333250D01*
X-185917Y-333167D01*
X-186500Y-333333D01*
X-187000Y-333667D01*
X-187333Y-334167D01*
X-187500Y-334833D01*
X-187333Y-335500D01*
X-187000Y-336000D01*
X-186500Y-336333D01*
X-185917Y-336500D01*
X-185333Y-336417D01*
X-184833Y-336167D01*
X-184500Y-335833D01*
G01X-178900Y-331500D02*
Y-336500D01*
G01Y-335750D02*
X-179233Y-336167D01*
X-179733Y-336417D01*
X-180317Y-336500D01*
X-180983Y-336333D01*
X-181483Y-335917D01*
X-181817Y-335417D01*
X-181900Y-334833D01*
X-181817Y-334250D01*
X-181483Y-333750D01*
X-180983Y-333333D01*
X-180317Y-333167D01*
X-179733Y-333250D01*
X-179317Y-333417D01*
X-178900Y-333750D01*
G01X-173300Y-331500D02*
Y-336500D01*
G01Y-335750D02*
X-173633Y-336167D01*
X-174133Y-336417D01*
X-174717Y-336500D01*
X-175383Y-336333D01*
X-175883Y-335917D01*
X-176217Y-335417D01*
X-176300Y-334833D01*
X-176217Y-334250D01*
X-175883Y-333750D01*
X-175383Y-333333D01*
X-174717Y-333167D01*
X-174133Y-333250D01*
X-173717Y-333417D01*
X-173300Y-333750D01*
G01X-164850Y-335917D02*
X-164433Y-336250D01*
X-163850Y-336500D01*
X-163350D01*
X-162850Y-336333D01*
X-162517Y-336083D01*
X-162350Y-335750D01*
X-162433Y-335250D01*
X-162767Y-335000D01*
X-164267Y-334500D01*
X-164600Y-333917D01*
X-164433Y-333500D01*
X-164100Y-333250D01*
X-163600Y-333167D01*
X-163100Y-333250D01*
X-162600Y-333500D01*
G01X-159417Y-333167D02*
Y-335500D01*
X-159083Y-336083D01*
X-158583Y-336417D01*
X-158000Y-336500D01*
X-157417Y-336417D01*
X-156917Y-336083D01*
X-156583Y-335500D01*
G01Y-336500D02*
Y-333167D01*
G01X-153900Y-338167D02*
Y-333167D01*
G01Y-333917D02*
X-153483Y-333500D01*
X-153067Y-333250D01*
X-152400Y-333167D01*
X-151817Y-333250D01*
X-151233Y-333667D01*
X-150983Y-334250D01*
X-150900Y-334833D01*
X-150983Y-335417D01*
X-151233Y-336000D01*
X-151733Y-336333D01*
X-152400Y-336500D01*
X-152983Y-336417D01*
X-153567Y-336167D01*
X-153900Y-335833D01*
G01X-148300Y-338167D02*
Y-333167D01*
G01Y-333917D02*
X-147883Y-333500D01*
X-147467Y-333250D01*
X-146800Y-333167D01*
X-146217Y-333250D01*
X-145633Y-333667D01*
X-145383Y-334250D01*
X-145300Y-334833D01*
X-145383Y-335417D01*
X-145633Y-336000D01*
X-146133Y-336333D01*
X-146800Y-336500D01*
X-147383Y-336417D01*
X-147967Y-336167D01*
X-148300Y-335833D01*
G01X-141200Y-336500D02*
Y-331500D01*
G01X-135600Y-333167D02*
Y-336500D01*
G01Y-331833D02*
X-135767Y-331750D01*
Y-331583D01*
X-135600Y-331500D01*
X-135433Y-331583D01*
Y-331750D01*
X-135600Y-331833D01*
G01X-131250Y-334250D02*
X-128583D01*
X-128833Y-333667D01*
X-129250Y-333333D01*
X-129833Y-333167D01*
X-130417Y-333250D01*
X-130917Y-333500D01*
X-131250Y-334083D01*
X-131417Y-334583D01*
Y-335083D01*
X-131250Y-335583D01*
X-130833Y-336083D01*
X-130333Y-336417D01*
X-129750Y-336500D01*
X-129167Y-336333D01*
X-128583Y-335833D01*
G01X-125567Y-336500D02*
Y-333167D01*
G01Y-333833D02*
X-125150Y-333500D01*
X-124733Y-333250D01*
X-124150Y-333167D01*
X-123733Y-333250D01*
X-123233Y-333500D01*
G01X-118800Y-333167D02*
X-117967Y-332125D01*
Y-331500D01*
X-118592D01*
Y-332125D01*
X-117967D01*
G01X-114450Y-335917D02*
X-114033Y-336250D01*
X-113450Y-336500D01*
X-112950D01*
X-112450Y-336333D01*
X-112117Y-336083D01*
X-111950Y-335750D01*
X-112033Y-335250D01*
X-112367Y-335000D01*
X-113867Y-334500D01*
X-114200Y-333917D01*
X-114033Y-333500D01*
X-113700Y-333250D01*
X-113200Y-333167D01*
X-112700Y-333250D01*
X-112200Y-333500D01*
G01X-103667Y-331500D02*
Y-336500D01*
X-100333D01*
G01X-96400D02*
X-96900Y-336417D01*
X-97400Y-336083D01*
X-97733Y-335500D01*
X-97900Y-334833D01*
X-97733Y-334167D01*
X-97400Y-333583D01*
X-96900Y-333250D01*
X-96400Y-333167D01*
X-95900Y-333250D01*
X-95400Y-333583D01*
X-95067Y-334167D01*
X-94983Y-334833D01*
X-95067Y-335500D01*
X-95400Y-336083D01*
X-95900Y-336417D01*
X-96400Y-336500D01*
G01X-91967Y-337750D02*
X-91383Y-338083D01*
X-90717Y-338167D01*
X-90133Y-338083D01*
X-89633Y-337667D01*
X-89300Y-337083D01*
Y-333167D01*
G01Y-333833D02*
X-89633Y-333500D01*
X-90133Y-333250D01*
X-90717Y-333167D01*
X-91383Y-333333D01*
X-91800Y-333667D01*
X-92133Y-334250D01*
X-92300Y-334833D01*
X-92217Y-335333D01*
X-91883Y-335917D01*
X-91383Y-336333D01*
X-90717Y-336500D01*
X-90217Y-336417D01*
X-89633Y-336083D01*
X-89300Y-335750D01*
G01X-85200Y-336500D02*
X-85700Y-336417D01*
X-86200Y-336083D01*
X-86533Y-335500D01*
X-86700Y-334833D01*
X-86533Y-334167D01*
X-86200Y-333583D01*
X-85700Y-333250D01*
X-85200Y-333167D01*
X-84700Y-333250D01*
X-84200Y-333583D01*
X-83867Y-334167D01*
X-83783Y-334833D01*
X-83867Y-335500D01*
X-84200Y-336083D01*
X-84700Y-336417D01*
X-85200Y-336500D01*
G01X-72500D02*
Y-333167D01*
G01Y-333750D02*
X-72833Y-333417D01*
X-73333Y-333250D01*
X-73917Y-333167D01*
X-74500Y-333333D01*
X-75000Y-333667D01*
X-75333Y-334167D01*
X-75500Y-334833D01*
X-75333Y-335500D01*
X-75000Y-336000D01*
X-74500Y-336333D01*
X-73917Y-336500D01*
X-73333Y-336417D01*
X-72833Y-336167D01*
X-72500Y-335833D01*
G01X-69817Y-336500D02*
Y-333167D01*
G01Y-334000D02*
X-69483Y-333583D01*
X-68983Y-333250D01*
X-68317Y-333167D01*
X-67733Y-333250D01*
X-67233Y-333583D01*
X-66983Y-334167D01*
Y-336500D01*
G01X-61300Y-331500D02*
Y-336500D01*
G01Y-335750D02*
X-61633Y-336167D01*
X-62133Y-336417D01*
X-62717Y-336500D01*
X-63383Y-336333D01*
X-63883Y-335917D01*
X-64217Y-335417D01*
X-64300Y-334833D01*
X-64217Y-334250D01*
X-63883Y-333750D01*
X-63383Y-333333D01*
X-62717Y-333167D01*
X-62133Y-333250D01*
X-61717Y-333417D01*
X-61300Y-333750D01*
G01X-53433Y-331500D02*
Y-335083D01*
X-53100Y-335833D01*
X-52433Y-336333D01*
X-51600Y-336500D01*
X-50767Y-336333D01*
X-50100Y-335833D01*
X-49767Y-335083D01*
Y-331500D01*
G01X-47667D02*
Y-336500D01*
X-44333D01*
G01X-35300D02*
Y-332250D01*
X-35133Y-331833D01*
X-34800Y-331583D01*
X-34300Y-331500D01*
X-33800Y-331667D01*
X-33550Y-332083D01*
G01X-34550Y-333500D02*
X-36217D01*
G01X-29200Y-333167D02*
Y-336500D01*
G01Y-331833D02*
X-29367Y-331750D01*
Y-331583D01*
X-29200Y-331500D01*
X-29033Y-331583D01*
Y-331750D01*
X-29200Y-331833D01*
G01X-23600Y-336500D02*
Y-331500D01*
G01X-19250Y-334250D02*
X-16583D01*
X-16833Y-333667D01*
X-17250Y-333333D01*
X-17833Y-333167D01*
X-18417Y-333250D01*
X-18917Y-333500D01*
X-19250Y-334083D01*
X-19417Y-334583D01*
Y-335083D01*
X-19250Y-335583D01*
X-18833Y-336083D01*
X-18333Y-336417D01*
X-17750Y-336500D01*
X-17167Y-336333D01*
X-16583Y-335833D01*
G01X-8717Y-336500D02*
Y-331500D01*
X-4883Y-336500D01*
Y-331500D01*
G01X-2617Y-333167D02*
Y-335500D01*
X-2283Y-336083D01*
X-1783Y-336417D01*
X-1200Y-336500D01*
X-617Y-336417D01*
X-117Y-336083D01*
X217Y-335500D01*
G01Y-336500D02*
Y-333167D01*
G01X1900Y-336500D02*
Y-333167D01*
G01Y-334083D02*
X2150Y-333667D01*
X2567Y-333333D01*
X3150Y-333167D01*
X3733Y-333333D01*
X4150Y-333667D01*
X4400Y-334083D01*
Y-336500D01*
G01Y-334083D02*
X4650Y-333667D01*
X5067Y-333333D01*
X5650Y-333167D01*
X6233Y-333333D01*
X6650Y-333667D01*
X6900Y-334167D01*
Y-336500D01*
G01X8500D02*
Y-331500D01*
G01Y-334000D02*
X8917Y-333500D01*
X9417Y-333250D01*
X9917Y-333167D01*
X10667Y-333333D01*
X11167Y-333667D01*
X11500Y-334250D01*
Y-334917D01*
X11333Y-335583D01*
X11000Y-336083D01*
X10417Y-336417D01*
X9917Y-336500D01*
X9417Y-336417D01*
X8917Y-336167D01*
X8500Y-335750D01*
G01X14350Y-334250D02*
X17017D01*
X16767Y-333667D01*
X16350Y-333333D01*
X15767Y-333167D01*
X15183Y-333250D01*
X14683Y-333500D01*
X14350Y-334083D01*
X14183Y-334583D01*
Y-335083D01*
X14350Y-335583D01*
X14767Y-336083D01*
X15267Y-336417D01*
X15850Y-336500D01*
X16433Y-336333D01*
X17017Y-335833D01*
G01X20033Y-336500D02*
Y-333167D01*
G01Y-333833D02*
X20450Y-333500D01*
X20867Y-333250D01*
X21450Y-333167D01*
X21867Y-333250D01*
X22367Y-333500D01*
G01X32400Y-333167D02*
Y-336500D01*
G01Y-331833D02*
X32233Y-331750D01*
Y-331583D01*
X32400Y-331500D01*
X32567Y-331583D01*
Y-331750D01*
X32400Y-331833D01*
G01X36583Y-336500D02*
Y-333167D01*
G01Y-334000D02*
X36917Y-333583D01*
X37417Y-333250D01*
X38083Y-333167D01*
X38667Y-333250D01*
X39167Y-333583D01*
X39417Y-334167D01*
Y-336500D01*
G01X47950Y-335917D02*
X48367Y-336250D01*
X48950Y-336500D01*
X49450D01*
X49950Y-336333D01*
X50283Y-336083D01*
X50450Y-335750D01*
X50367Y-335250D01*
X50033Y-335000D01*
X48533Y-334500D01*
X48200Y-333917D01*
X48367Y-333500D01*
X48700Y-333250D01*
X49200Y-333167D01*
X49700Y-333250D01*
X50200Y-333500D01*
G01X54800Y-333167D02*
Y-336500D01*
G01Y-331833D02*
X54633Y-331750D01*
Y-331583D01*
X54800Y-331500D01*
X54967Y-331583D01*
Y-331750D01*
X54800Y-331833D01*
G01X60400Y-336500D02*
Y-331500D01*
G01X64583Y-336500D02*
Y-331500D01*
G01X67250Y-333167D02*
X64583Y-335083D01*
G01X65667Y-334333D02*
X67417Y-336500D01*
G01X70350Y-335917D02*
X70767Y-336250D01*
X71350Y-336500D01*
X71850D01*
X72350Y-336333D01*
X72683Y-336083D01*
X72850Y-335750D01*
X72767Y-335250D01*
X72433Y-335000D01*
X70933Y-334500D01*
X70600Y-333917D01*
X70767Y-333500D01*
X71100Y-333250D01*
X71600Y-333167D01*
X72100Y-333250D01*
X72600Y-333500D01*
G01X78533Y-333583D02*
X77950Y-333250D01*
X77450Y-333167D01*
X76783Y-333333D01*
X76283Y-333667D01*
X75950Y-334250D01*
X75867Y-334833D01*
X75950Y-335417D01*
X76283Y-335917D01*
X76783Y-336333D01*
X77450Y-336500D01*
X78033Y-336333D01*
X78533Y-336000D01*
G01X81633Y-336500D02*
Y-333167D01*
G01Y-333833D02*
X82050Y-333500D01*
X82467Y-333250D01*
X83050Y-333167D01*
X83467Y-333250D01*
X83967Y-333500D01*
G01X87150Y-334250D02*
X89817D01*
X89567Y-333667D01*
X89150Y-333333D01*
X88567Y-333167D01*
X87983Y-333250D01*
X87483Y-333500D01*
X87150Y-334083D01*
X86983Y-334583D01*
Y-335083D01*
X87150Y-335583D01*
X87567Y-336083D01*
X88067Y-336417D01*
X88650Y-336500D01*
X89233Y-336333D01*
X89817Y-335833D01*
G01X92750Y-334250D02*
X95417D01*
X95167Y-333667D01*
X94750Y-333333D01*
X94167Y-333167D01*
X93583Y-333250D01*
X93083Y-333500D01*
X92750Y-334083D01*
X92583Y-334583D01*
Y-335083D01*
X92750Y-335583D01*
X93167Y-336083D01*
X93667Y-336417D01*
X94250Y-336500D01*
X94833Y-336333D01*
X95417Y-335833D01*
G01X98183Y-336500D02*
Y-333167D01*
G01Y-334000D02*
X98517Y-333583D01*
X99017Y-333250D01*
X99683Y-333167D01*
X100267Y-333250D01*
X100767Y-333583D01*
X101017Y-334167D01*
Y-336500D01*
G01X-187750Y-320833D02*
X-187083Y-321250D01*
X-186333Y-321500D01*
X-185667D01*
X-185000Y-321250D01*
X-184500Y-320833D01*
X-184250Y-320250D01*
X-184417Y-319667D01*
X-184833Y-319167D01*
X-185583Y-318833D01*
X-186583Y-318667D01*
X-187167Y-318333D01*
X-187417Y-317750D01*
X-187250Y-317167D01*
X-186833Y-316750D01*
X-186250Y-316500D01*
X-185667D01*
X-185083Y-316667D01*
X-184583Y-317083D01*
G01X-180400Y-321500D02*
X-180900Y-321417D01*
X-181400Y-321083D01*
X-181733Y-320500D01*
X-181900Y-319833D01*
X-181733Y-319167D01*
X-181400Y-318583D01*
X-180900Y-318250D01*
X-180400Y-318167D01*
X-179900Y-318250D01*
X-179400Y-318583D01*
X-179067Y-319167D01*
X-178983Y-319833D01*
X-179067Y-320500D01*
X-179400Y-321083D01*
X-179900Y-321417D01*
X-180400Y-321500D01*
G01X-174800D02*
Y-316500D01*
G01X-167700D02*
Y-321500D01*
G01Y-320750D02*
X-168033Y-321167D01*
X-168533Y-321417D01*
X-169117Y-321500D01*
X-169783Y-321333D01*
X-170283Y-320917D01*
X-170617Y-320417D01*
X-170700Y-319833D01*
X-170617Y-319250D01*
X-170283Y-318750D01*
X-169783Y-318333D01*
X-169117Y-318167D01*
X-168533Y-318250D01*
X-168117Y-318417D01*
X-167700Y-318750D01*
G01X-164850Y-319250D02*
X-162183D01*
X-162433Y-318667D01*
X-162850Y-318333D01*
X-163433Y-318167D01*
X-164017Y-318250D01*
X-164517Y-318500D01*
X-164850Y-319083D01*
X-165017Y-319583D01*
Y-320083D01*
X-164850Y-320583D01*
X-164433Y-321083D01*
X-163933Y-321417D01*
X-163350Y-321500D01*
X-162767Y-321333D01*
X-162183Y-320833D01*
G01X-159167Y-321500D02*
Y-318167D01*
G01Y-318833D02*
X-158750Y-318500D01*
X-158333Y-318250D01*
X-157750Y-318167D01*
X-157333Y-318250D01*
X-156833Y-318500D01*
G01X-149300Y-321500D02*
Y-318167D01*
G01Y-319083D02*
X-149050Y-318667D01*
X-148633Y-318333D01*
X-148050Y-318167D01*
X-147467Y-318333D01*
X-147050Y-318667D01*
X-146800Y-319083D01*
Y-321500D01*
G01Y-319083D02*
X-146550Y-318667D01*
X-146133Y-318333D01*
X-145550Y-318167D01*
X-144967Y-318333D01*
X-144550Y-318667D01*
X-144300Y-319167D01*
Y-321500D01*
G01X-139700D02*
Y-318167D01*
G01Y-318750D02*
X-140033Y-318417D01*
X-140533Y-318250D01*
X-141117Y-318167D01*
X-141700Y-318333D01*
X-142200Y-318667D01*
X-142533Y-319167D01*
X-142700Y-319833D01*
X-142533Y-320500D01*
X-142200Y-321000D01*
X-141700Y-321333D01*
X-141117Y-321500D01*
X-140533Y-321417D01*
X-140033Y-321167D01*
X-139700Y-320833D01*
G01X-136850Y-320917D02*
X-136433Y-321250D01*
X-135850Y-321500D01*
X-135350D01*
X-134850Y-321333D01*
X-134517Y-321083D01*
X-134350Y-320750D01*
X-134433Y-320250D01*
X-134767Y-320000D01*
X-136267Y-319500D01*
X-136600Y-318917D01*
X-136433Y-318500D01*
X-136100Y-318250D01*
X-135600Y-318167D01*
X-135100Y-318250D01*
X-134600Y-318500D01*
G01X-131417Y-321500D02*
Y-316500D01*
G01X-128750Y-318167D02*
X-131417Y-320083D01*
G01X-130333Y-319333D02*
X-128583Y-321500D01*
G01X-118800Y-316500D02*
Y-321500D01*
G01X-119967Y-318167D02*
X-117633D01*
G01X-114617Y-321500D02*
Y-316500D01*
G01Y-318917D02*
X-114200Y-318500D01*
X-113783Y-318250D01*
X-113117Y-318167D01*
X-112617Y-318250D01*
X-112033Y-318583D01*
X-111783Y-319083D01*
Y-321500D01*
G01X-107600Y-318167D02*
Y-321500D01*
G01Y-316833D02*
X-107767Y-316750D01*
Y-316583D01*
X-107600Y-316500D01*
X-107433Y-316583D01*
Y-316750D01*
X-107600Y-316833D01*
G01X-100667Y-318583D02*
X-101250Y-318250D01*
X-101750Y-318167D01*
X-102417Y-318333D01*
X-102917Y-318667D01*
X-103250Y-319250D01*
X-103333Y-319833D01*
X-103250Y-320417D01*
X-102917Y-320917D01*
X-102417Y-321333D01*
X-101750Y-321500D01*
X-101167Y-321333D01*
X-100667Y-321000D01*
G01X-97817Y-321500D02*
Y-316500D01*
G01X-95150Y-318167D02*
X-97817Y-320083D01*
G01X-96733Y-319333D02*
X-94983Y-321500D01*
G01X-92217D02*
Y-318167D01*
G01Y-319000D02*
X-91883Y-318583D01*
X-91383Y-318250D01*
X-90717Y-318167D01*
X-90133Y-318250D01*
X-89633Y-318583D01*
X-89383Y-319167D01*
Y-321500D01*
G01X-86450Y-319250D02*
X-83783D01*
X-84033Y-318667D01*
X-84450Y-318333D01*
X-85033Y-318167D01*
X-85617Y-318250D01*
X-86117Y-318500D01*
X-86450Y-319083D01*
X-86617Y-319583D01*
Y-320083D01*
X-86450Y-320583D01*
X-86033Y-321083D01*
X-85533Y-321417D01*
X-84950Y-321500D01*
X-84367Y-321333D01*
X-83783Y-320833D01*
G01X-80850Y-320917D02*
X-80433Y-321250D01*
X-79850Y-321500D01*
X-79350D01*
X-78850Y-321333D01*
X-78517Y-321083D01*
X-78350Y-320750D01*
X-78433Y-320250D01*
X-78767Y-320000D01*
X-80267Y-319500D01*
X-80600Y-318917D01*
X-80433Y-318500D01*
X-80100Y-318250D01*
X-79600Y-318167D01*
X-79100Y-318250D01*
X-78600Y-318500D01*
G01X-75250Y-320917D02*
X-74833Y-321250D01*
X-74250Y-321500D01*
X-73750D01*
X-73250Y-321333D01*
X-72917Y-321083D01*
X-72750Y-320750D01*
X-72833Y-320250D01*
X-73167Y-320000D01*
X-74667Y-319500D01*
X-75000Y-318917D01*
X-74833Y-318500D01*
X-74500Y-318250D01*
X-74000Y-318167D01*
X-73500Y-318250D01*
X-73000Y-318500D01*
G01X-64300Y-323167D02*
Y-318167D01*
G01Y-318917D02*
X-63883Y-318500D01*
X-63467Y-318250D01*
X-62800Y-318167D01*
X-62217Y-318250D01*
X-61633Y-318667D01*
X-61383Y-319250D01*
X-61300Y-319833D01*
X-61383Y-320417D01*
X-61633Y-321000D01*
X-62133Y-321333D01*
X-62800Y-321500D01*
X-63383Y-321417D01*
X-63967Y-321167D01*
X-64300Y-320833D01*
G01X-57200Y-321500D02*
Y-316500D01*
G01X-53017Y-318167D02*
Y-320500D01*
X-52683Y-321083D01*
X-52183Y-321417D01*
X-51600Y-321500D01*
X-51017Y-321417D01*
X-50517Y-321083D01*
X-50183Y-320500D01*
G01Y-321500D02*
Y-318167D01*
G01X-47250Y-320917D02*
X-46833Y-321250D01*
X-46250Y-321500D01*
X-45750D01*
X-45250Y-321333D01*
X-44917Y-321083D01*
X-44750Y-320750D01*
X-44833Y-320250D01*
X-45167Y-320000D01*
X-46667Y-319500D01*
X-47000Y-318917D01*
X-46833Y-318500D01*
X-46500Y-318250D01*
X-46000Y-318167D01*
X-45500Y-318250D01*
X-45000Y-318500D01*
G01X-34800Y-321500D02*
Y-316500D01*
G01X-30450Y-319250D02*
X-27783D01*
X-28033Y-318667D01*
X-28450Y-318333D01*
X-29033Y-318167D01*
X-29617Y-318250D01*
X-30117Y-318500D01*
X-30450Y-319083D01*
X-30617Y-319583D01*
Y-320083D01*
X-30450Y-320583D01*
X-30033Y-321083D01*
X-29533Y-321417D01*
X-28950Y-321500D01*
X-28367Y-321333D01*
X-27783Y-320833D01*
G01X-24767Y-322750D02*
X-24183Y-323083D01*
X-23517Y-323167D01*
X-22933Y-323083D01*
X-22433Y-322667D01*
X-22100Y-322083D01*
Y-318167D01*
G01Y-318833D02*
X-22433Y-318500D01*
X-22933Y-318250D01*
X-23517Y-318167D01*
X-24183Y-318333D01*
X-24600Y-318667D01*
X-24933Y-319250D01*
X-25100Y-319833D01*
X-25017Y-320333D01*
X-24683Y-320917D01*
X-24183Y-321333D01*
X-23517Y-321500D01*
X-23017Y-321417D01*
X-22433Y-321083D01*
X-22100Y-320750D01*
G01X-19250Y-319250D02*
X-16583D01*
X-16833Y-318667D01*
X-17250Y-318333D01*
X-17833Y-318167D01*
X-18417Y-318250D01*
X-18917Y-318500D01*
X-19250Y-319083D01*
X-19417Y-319583D01*
Y-320083D01*
X-19250Y-320583D01*
X-18833Y-321083D01*
X-18333Y-321417D01*
X-17750Y-321500D01*
X-17167Y-321333D01*
X-16583Y-320833D01*
G01X-13817Y-321500D02*
Y-318167D01*
G01Y-319000D02*
X-13483Y-318583D01*
X-12983Y-318250D01*
X-12317Y-318167D01*
X-11733Y-318250D01*
X-11233Y-318583D01*
X-10983Y-319167D01*
Y-321500D01*
G01X-5300Y-316500D02*
Y-321500D01*
G01Y-320750D02*
X-5633Y-321167D01*
X-6133Y-321417D01*
X-6717Y-321500D01*
X-7383Y-321333D01*
X-7883Y-320917D01*
X-8217Y-320417D01*
X-8300Y-319833D01*
X-8217Y-319250D01*
X-7883Y-318750D01*
X-7383Y-318333D01*
X-6717Y-318167D01*
X-6133Y-318250D01*
X-5717Y-318417D01*
X-5300Y-318750D01*
G01X4400Y-316500D02*
Y-321500D01*
G01X3233Y-318167D02*
X5567D01*
G01X8583Y-321500D02*
Y-316500D01*
G01Y-318917D02*
X9000Y-318500D01*
X9417Y-318250D01*
X10083Y-318167D01*
X10583Y-318250D01*
X11167Y-318583D01*
X11417Y-319083D01*
Y-321500D01*
G01X15600Y-318167D02*
Y-321500D01*
G01Y-316833D02*
X15433Y-316750D01*
Y-316583D01*
X15600Y-316500D01*
X15767Y-316583D01*
Y-316750D01*
X15600Y-316833D01*
G01X22533Y-318583D02*
X21950Y-318250D01*
X21450Y-318167D01*
X20783Y-318333D01*
X20283Y-318667D01*
X19950Y-319250D01*
X19867Y-319833D01*
X19950Y-320417D01*
X20283Y-320917D01*
X20783Y-321333D01*
X21450Y-321500D01*
X22033Y-321333D01*
X22533Y-321000D01*
G01X25383Y-321500D02*
Y-316500D01*
G01X28050Y-318167D02*
X25383Y-320083D01*
G01X26467Y-319333D02*
X28217Y-321500D01*
G01X30983D02*
Y-318167D01*
G01Y-319000D02*
X31317Y-318583D01*
X31817Y-318250D01*
X32483Y-318167D01*
X33067Y-318250D01*
X33567Y-318583D01*
X33817Y-319167D01*
Y-321500D01*
G01X36750Y-319250D02*
X39417D01*
X39167Y-318667D01*
X38750Y-318333D01*
X38167Y-318167D01*
X37583Y-318250D01*
X37083Y-318500D01*
X36750Y-319083D01*
X36583Y-319583D01*
Y-320083D01*
X36750Y-320583D01*
X37167Y-321083D01*
X37667Y-321417D01*
X38250Y-321500D01*
X38833Y-321333D01*
X39417Y-320833D01*
G01X42350Y-320917D02*
X42767Y-321250D01*
X43350Y-321500D01*
X43850D01*
X44350Y-321333D01*
X44683Y-321083D01*
X44850Y-320750D01*
X44767Y-320250D01*
X44433Y-320000D01*
X42933Y-319500D01*
X42600Y-318917D01*
X42767Y-318500D01*
X43100Y-318250D01*
X43600Y-318167D01*
X44100Y-318250D01*
X44600Y-318500D01*
G01X47950Y-320917D02*
X48367Y-321250D01*
X48950Y-321500D01*
X49450D01*
X49950Y-321333D01*
X50283Y-321083D01*
X50450Y-320750D01*
X50367Y-320250D01*
X50033Y-320000D01*
X48533Y-319500D01*
X48200Y-318917D01*
X48367Y-318500D01*
X48700Y-318250D01*
X49200Y-318167D01*
X49700Y-318250D01*
X50200Y-318500D01*
G01X60400Y-321500D02*
X59900Y-321417D01*
X59400Y-321083D01*
X59067Y-320500D01*
X58900Y-319833D01*
X59067Y-319167D01*
X59400Y-318583D01*
X59900Y-318250D01*
X60400Y-318167D01*
X60900Y-318250D01*
X61400Y-318583D01*
X61733Y-319167D01*
X61817Y-319833D01*
X61733Y-320500D01*
X61400Y-321083D01*
X60900Y-321417D01*
X60400Y-321500D01*
G01X64583D02*
Y-318167D01*
G01Y-319000D02*
X64917Y-318583D01*
X65417Y-318250D01*
X66083Y-318167D01*
X66667Y-318250D01*
X67167Y-318583D01*
X67417Y-319167D01*
Y-321500D01*
G01X77200Y-316500D02*
Y-321500D01*
G01X76033Y-318167D02*
X78367D01*
G01X81633Y-321500D02*
Y-318167D01*
G01Y-318833D02*
X82050Y-318500D01*
X82467Y-318250D01*
X83050Y-318167D01*
X83467Y-318250D01*
X83967Y-318500D01*
G01X89900Y-321500D02*
Y-318167D01*
G01Y-318750D02*
X89567Y-318417D01*
X89067Y-318250D01*
X88483Y-318167D01*
X87900Y-318333D01*
X87400Y-318667D01*
X87067Y-319167D01*
X86900Y-319833D01*
X87067Y-320500D01*
X87400Y-321000D01*
X87900Y-321333D01*
X88483Y-321500D01*
X89067Y-321417D01*
X89567Y-321167D01*
X89900Y-320833D01*
G01X95333Y-318583D02*
X94750Y-318250D01*
X94250Y-318167D01*
X93583Y-318333D01*
X93083Y-318667D01*
X92750Y-319250D01*
X92667Y-319833D01*
X92750Y-320417D01*
X93083Y-320917D01*
X93583Y-321333D01*
X94250Y-321500D01*
X94833Y-321333D01*
X95333Y-321000D01*
G01X98350Y-319250D02*
X101017D01*
X100767Y-318667D01*
X100350Y-318333D01*
X99767Y-318167D01*
X99183Y-318250D01*
X98683Y-318500D01*
X98350Y-319083D01*
X98183Y-319583D01*
Y-320083D01*
X98350Y-320583D01*
X98767Y-321083D01*
X99267Y-321417D01*
X99850Y-321500D01*
X100433Y-321333D01*
X101017Y-320833D01*
G01X105200Y-321667D02*
X105033Y-321583D01*
Y-321417D01*
X105200Y-321333D01*
X105367Y-321417D01*
Y-321583D01*
X105200Y-321667D01*
G01X-186000Y-306500D02*
Y-301500D01*
G01X-181650Y-304250D02*
X-178983D01*
X-179233Y-303667D01*
X-179650Y-303333D01*
X-180233Y-303167D01*
X-180817Y-303250D01*
X-181317Y-303500D01*
X-181650Y-304083D01*
X-181817Y-304583D01*
Y-305083D01*
X-181650Y-305583D01*
X-181233Y-306083D01*
X-180733Y-306417D01*
X-180150Y-306500D01*
X-179567Y-306333D01*
X-178983Y-305833D01*
G01X-175967Y-307750D02*
X-175383Y-308083D01*
X-174717Y-308167D01*
X-174133Y-308083D01*
X-173633Y-307667D01*
X-173300Y-307083D01*
Y-303167D01*
G01Y-303833D02*
X-173633Y-303500D01*
X-174133Y-303250D01*
X-174717Y-303167D01*
X-175383Y-303333D01*
X-175800Y-303667D01*
X-176133Y-304250D01*
X-176300Y-304833D01*
X-176217Y-305333D01*
X-175883Y-305917D01*
X-175383Y-306333D01*
X-174717Y-306500D01*
X-174217Y-306417D01*
X-173633Y-306083D01*
X-173300Y-305750D01*
G01X-170450Y-304250D02*
X-167783D01*
X-168033Y-303667D01*
X-168450Y-303333D01*
X-169033Y-303167D01*
X-169617Y-303250D01*
X-170117Y-303500D01*
X-170450Y-304083D01*
X-170617Y-304583D01*
Y-305083D01*
X-170450Y-305583D01*
X-170033Y-306083D01*
X-169533Y-306417D01*
X-168950Y-306500D01*
X-168367Y-306333D01*
X-167783Y-305833D01*
G01X-165017Y-306500D02*
Y-303167D01*
G01Y-304000D02*
X-164683Y-303583D01*
X-164183Y-303250D01*
X-163517Y-303167D01*
X-162933Y-303250D01*
X-162433Y-303583D01*
X-162183Y-304167D01*
Y-306500D01*
G01X-156500Y-301500D02*
Y-306500D01*
G01Y-305750D02*
X-156833Y-306167D01*
X-157333Y-306417D01*
X-157917Y-306500D01*
X-158583Y-306333D01*
X-159083Y-305917D01*
X-159417Y-305417D01*
X-159500Y-304833D01*
X-159417Y-304250D01*
X-159083Y-303750D01*
X-158583Y-303333D01*
X-157917Y-303167D01*
X-157333Y-303250D01*
X-156917Y-303417D01*
X-156500Y-303750D01*
G01X-146800Y-301500D02*
Y-306500D01*
G01X-147967Y-303167D02*
X-145633D01*
G01X-142617Y-306500D02*
Y-301500D01*
G01Y-303917D02*
X-142200Y-303500D01*
X-141783Y-303250D01*
X-141117Y-303167D01*
X-140617Y-303250D01*
X-140033Y-303583D01*
X-139783Y-304083D01*
Y-306500D01*
G01X-135600Y-303167D02*
Y-306500D01*
G01Y-301833D02*
X-135767Y-301750D01*
Y-301583D01*
X-135600Y-301500D01*
X-135433Y-301583D01*
Y-301750D01*
X-135600Y-301833D01*
G01X-128667Y-303583D02*
X-129250Y-303250D01*
X-129750Y-303167D01*
X-130417Y-303333D01*
X-130917Y-303667D01*
X-131250Y-304250D01*
X-131333Y-304833D01*
X-131250Y-305417D01*
X-130917Y-305917D01*
X-130417Y-306333D01*
X-129750Y-306500D01*
X-129167Y-306333D01*
X-128667Y-306000D01*
G01X-125817Y-306500D02*
Y-301500D01*
G01X-123150Y-303167D02*
X-125817Y-305083D01*
G01X-124733Y-304333D02*
X-122983Y-306500D01*
G01X-120217D02*
Y-303167D01*
G01Y-304000D02*
X-119883Y-303583D01*
X-119383Y-303250D01*
X-118717Y-303167D01*
X-118133Y-303250D01*
X-117633Y-303583D01*
X-117383Y-304167D01*
Y-306500D01*
G01X-114450Y-304250D02*
X-111783D01*
X-112033Y-303667D01*
X-112450Y-303333D01*
X-113033Y-303167D01*
X-113617Y-303250D01*
X-114117Y-303500D01*
X-114450Y-304083D01*
X-114617Y-304583D01*
Y-305083D01*
X-114450Y-305583D01*
X-114033Y-306083D01*
X-113533Y-306417D01*
X-112950Y-306500D01*
X-112367Y-306333D01*
X-111783Y-305833D01*
G01X-108850Y-305917D02*
X-108433Y-306250D01*
X-107850Y-306500D01*
X-107350D01*
X-106850Y-306333D01*
X-106517Y-306083D01*
X-106350Y-305750D01*
X-106433Y-305250D01*
X-106767Y-305000D01*
X-108267Y-304500D01*
X-108600Y-303917D01*
X-108433Y-303500D01*
X-108100Y-303250D01*
X-107600Y-303167D01*
X-107100Y-303250D01*
X-106600Y-303500D01*
G01X-103250Y-305917D02*
X-102833Y-306250D01*
X-102250Y-306500D01*
X-101750D01*
X-101250Y-306333D01*
X-100917Y-306083D01*
X-100750Y-305750D01*
X-100833Y-305250D01*
X-101167Y-305000D01*
X-102667Y-304500D01*
X-103000Y-303917D01*
X-102833Y-303500D01*
X-102500Y-303250D01*
X-102000Y-303167D01*
X-101500Y-303250D01*
X-101000Y-303500D01*
G01X-90800Y-306500D02*
X-91300Y-306417D01*
X-91800Y-306083D01*
X-92133Y-305500D01*
X-92300Y-304833D01*
X-92133Y-304167D01*
X-91800Y-303583D01*
X-91300Y-303250D01*
X-90800Y-303167D01*
X-90300Y-303250D01*
X-89800Y-303583D01*
X-89467Y-304167D01*
X-89383Y-304833D01*
X-89467Y-305500D01*
X-89800Y-306083D01*
X-90300Y-306417D01*
X-90800Y-306500D01*
G01X-86617D02*
Y-303167D01*
G01Y-304000D02*
X-86283Y-303583D01*
X-85783Y-303250D01*
X-85117Y-303167D01*
X-84533Y-303250D01*
X-84033Y-303583D01*
X-83783Y-304167D01*
Y-306500D01*
G01X-72667Y-303583D02*
X-73250Y-303250D01*
X-73750Y-303167D01*
X-74417Y-303333D01*
X-74917Y-303667D01*
X-75250Y-304250D01*
X-75333Y-304833D01*
X-75250Y-305417D01*
X-74917Y-305917D01*
X-74417Y-306333D01*
X-73750Y-306500D01*
X-73167Y-306333D01*
X-72667Y-306000D01*
G01X-68400Y-306500D02*
X-68900Y-306417D01*
X-69400Y-306083D01*
X-69733Y-305500D01*
X-69900Y-304833D01*
X-69733Y-304167D01*
X-69400Y-303583D01*
X-68900Y-303250D01*
X-68400Y-303167D01*
X-67900Y-303250D01*
X-67400Y-303583D01*
X-67067Y-304167D01*
X-66983Y-304833D01*
X-67067Y-305500D01*
X-67400Y-306083D01*
X-67900Y-306417D01*
X-68400Y-306500D01*
G01X-64300Y-308167D02*
Y-303167D01*
G01Y-303917D02*
X-63883Y-303500D01*
X-63467Y-303250D01*
X-62800Y-303167D01*
X-62217Y-303250D01*
X-61633Y-303667D01*
X-61383Y-304250D01*
X-61300Y-304833D01*
X-61383Y-305417D01*
X-61633Y-306000D01*
X-62133Y-306333D01*
X-62800Y-306500D01*
X-63383Y-306417D01*
X-63967Y-306167D01*
X-64300Y-305833D01*
G01X-58700Y-308167D02*
Y-303167D01*
G01Y-303917D02*
X-58283Y-303500D01*
X-57867Y-303250D01*
X-57200Y-303167D01*
X-56617Y-303250D01*
X-56033Y-303667D01*
X-55783Y-304250D01*
X-55700Y-304833D01*
X-55783Y-305417D01*
X-56033Y-306000D01*
X-56533Y-306333D01*
X-57200Y-306500D01*
X-57783Y-306417D01*
X-58367Y-306167D01*
X-58700Y-305833D01*
G01X-52850Y-304250D02*
X-50183D01*
X-50433Y-303667D01*
X-50850Y-303333D01*
X-51433Y-303167D01*
X-52017Y-303250D01*
X-52517Y-303500D01*
X-52850Y-304083D01*
X-53017Y-304583D01*
Y-305083D01*
X-52850Y-305583D01*
X-52433Y-306083D01*
X-51933Y-306417D01*
X-51350Y-306500D01*
X-50767Y-306333D01*
X-50183Y-305833D01*
G01X-47167Y-306500D02*
Y-303167D01*
G01Y-303833D02*
X-46750Y-303500D01*
X-46333Y-303250D01*
X-45750Y-303167D01*
X-45333Y-303250D01*
X-44833Y-303500D01*
G01X-35217Y-308167D02*
X-36050Y-307333D01*
X-36467Y-306500D01*
Y-303167D01*
X-36050Y-302333D01*
X-35217Y-301500D01*
G01X-31283Y-303167D02*
X-30283Y-306500D01*
X-29200Y-303167D01*
X-28117Y-306500D01*
X-27117Y-303167D01*
G01X-25017Y-306500D02*
Y-301500D01*
G01Y-303917D02*
X-24600Y-303500D01*
X-24183Y-303250D01*
X-23517Y-303167D01*
X-23017Y-303250D01*
X-22433Y-303583D01*
X-22183Y-304083D01*
Y-306500D01*
G01X-18000Y-303167D02*
Y-306500D01*
G01Y-301833D02*
X-18167Y-301750D01*
Y-301583D01*
X-18000Y-301500D01*
X-17833Y-301583D01*
Y-301750D01*
X-18000Y-301833D01*
G01X-11067Y-303583D02*
X-11650Y-303250D01*
X-12150Y-303167D01*
X-12817Y-303333D01*
X-13317Y-303667D01*
X-13650Y-304250D01*
X-13733Y-304833D01*
X-13650Y-305417D01*
X-13317Y-305917D01*
X-12817Y-306333D01*
X-12150Y-306500D01*
X-11567Y-306333D01*
X-11067Y-306000D01*
G01X-8217Y-306500D02*
Y-301500D01*
G01Y-303917D02*
X-7800Y-303500D01*
X-7383Y-303250D01*
X-6717Y-303167D01*
X-6217Y-303250D01*
X-5633Y-303583D01*
X-5383Y-304083D01*
Y-306500D01*
G01X4400Y-303167D02*
Y-306500D01*
G01Y-301833D02*
X4233Y-301750D01*
Y-301583D01*
X4400Y-301500D01*
X4567Y-301583D01*
Y-301750D01*
X4400Y-301833D01*
G01X8750Y-305917D02*
X9167Y-306250D01*
X9750Y-306500D01*
X10250D01*
X10750Y-306333D01*
X11083Y-306083D01*
X11250Y-305750D01*
X11167Y-305250D01*
X10833Y-305000D01*
X9333Y-304500D01*
X9000Y-303917D01*
X9167Y-303500D01*
X9500Y-303250D01*
X10000Y-303167D01*
X10500Y-303250D01*
X11000Y-303500D01*
G01X19700Y-306500D02*
Y-301500D01*
G01Y-304000D02*
X20117Y-303500D01*
X20617Y-303250D01*
X21117Y-303167D01*
X21867Y-303333D01*
X22367Y-303667D01*
X22700Y-304250D01*
Y-304917D01*
X22533Y-305583D01*
X22200Y-306083D01*
X21617Y-306417D01*
X21117Y-306500D01*
X20617Y-306417D01*
X20117Y-306167D01*
X19700Y-305750D01*
G01X25550Y-304250D02*
X28217D01*
X27967Y-303667D01*
X27550Y-303333D01*
X26967Y-303167D01*
X26383Y-303250D01*
X25883Y-303500D01*
X25550Y-304083D01*
X25383Y-304583D01*
Y-305083D01*
X25550Y-305583D01*
X25967Y-306083D01*
X26467Y-306417D01*
X27050Y-306500D01*
X27633Y-306333D01*
X28217Y-305833D01*
G01X32400Y-301500D02*
Y-306500D01*
G01X31233Y-303167D02*
X33567D01*
G01X38000Y-301500D02*
Y-306500D01*
G01X36833Y-303167D02*
X39167D01*
G01X42350Y-304250D02*
X45017D01*
X44767Y-303667D01*
X44350Y-303333D01*
X43767Y-303167D01*
X43183Y-303250D01*
X42683Y-303500D01*
X42350Y-304083D01*
X42183Y-304583D01*
Y-305083D01*
X42350Y-305583D01*
X42767Y-306083D01*
X43267Y-306417D01*
X43850Y-306500D01*
X44433Y-306333D01*
X45017Y-305833D01*
G01X48033Y-306500D02*
Y-303167D01*
G01Y-303833D02*
X48450Y-303500D01*
X48867Y-303250D01*
X49450Y-303167D01*
X49867Y-303250D01*
X50367Y-303500D01*
G01X55217Y-308167D02*
X56050Y-307333D01*
X56467Y-306500D01*
Y-303167D01*
X56050Y-302333D01*
X55217Y-301500D01*
G01X-187250Y-292417D02*
X-186833Y-292750D01*
X-186250Y-293000D01*
X-185750D01*
X-185250Y-292833D01*
X-184917Y-292583D01*
X-184750Y-292250D01*
X-184833Y-291750D01*
X-185167Y-291500D01*
X-186667Y-291000D01*
X-187000Y-290417D01*
X-186833Y-290000D01*
X-186500Y-289750D01*
X-186000Y-289667D01*
X-185500Y-289750D01*
X-185000Y-290000D01*
G01X-180400Y-293000D02*
X-180900Y-292917D01*
X-181400Y-292583D01*
X-181733Y-292000D01*
X-181900Y-291333D01*
X-181733Y-290667D01*
X-181400Y-290083D01*
X-180900Y-289750D01*
X-180400Y-289667D01*
X-179900Y-289750D01*
X-179400Y-290083D01*
X-179067Y-290667D01*
X-178983Y-291333D01*
X-179067Y-292000D01*
X-179400Y-292583D01*
X-179900Y-292917D01*
X-180400Y-293000D01*
G01X-174800D02*
Y-288000D01*
G01X-167700D02*
Y-293000D01*
G01Y-292250D02*
X-168033Y-292667D01*
X-168533Y-292917D01*
X-169117Y-293000D01*
X-169783Y-292833D01*
X-170283Y-292417D01*
X-170617Y-291917D01*
X-170700Y-291333D01*
X-170617Y-290750D01*
X-170283Y-290250D01*
X-169783Y-289833D01*
X-169117Y-289667D01*
X-168533Y-289750D01*
X-168117Y-289917D01*
X-167700Y-290250D01*
G01X-164850Y-290750D02*
X-162183D01*
X-162433Y-290167D01*
X-162850Y-289833D01*
X-163433Y-289667D01*
X-164017Y-289750D01*
X-164517Y-290000D01*
X-164850Y-290583D01*
X-165017Y-291083D01*
Y-291583D01*
X-164850Y-292083D01*
X-164433Y-292583D01*
X-163933Y-292917D01*
X-163350Y-293000D01*
X-162767Y-292833D01*
X-162183Y-292333D01*
G01X-159167Y-293000D02*
Y-289667D01*
G01Y-290333D02*
X-158750Y-290000D01*
X-158333Y-289750D01*
X-157750Y-289667D01*
X-157333Y-289750D01*
X-156833Y-290000D01*
G01X-149300Y-293000D02*
Y-289667D01*
G01Y-290583D02*
X-149050Y-290167D01*
X-148633Y-289833D01*
X-148050Y-289667D01*
X-147467Y-289833D01*
X-147050Y-290167D01*
X-146800Y-290583D01*
Y-293000D01*
G01Y-290583D02*
X-146550Y-290167D01*
X-146133Y-289833D01*
X-145550Y-289667D01*
X-144967Y-289833D01*
X-144550Y-290167D01*
X-144300Y-290667D01*
Y-293000D01*
G01X-139700D02*
Y-289667D01*
G01Y-290250D02*
X-140033Y-289917D01*
X-140533Y-289750D01*
X-141117Y-289667D01*
X-141700Y-289833D01*
X-142200Y-290167D01*
X-142533Y-290667D01*
X-142700Y-291333D01*
X-142533Y-292000D01*
X-142200Y-292500D01*
X-141700Y-292833D01*
X-141117Y-293000D01*
X-140533Y-292917D01*
X-140033Y-292667D01*
X-139700Y-292333D01*
G01X-136850Y-292417D02*
X-136433Y-292750D01*
X-135850Y-293000D01*
X-135350D01*
X-134850Y-292833D01*
X-134517Y-292583D01*
X-134350Y-292250D01*
X-134433Y-291750D01*
X-134767Y-291500D01*
X-136267Y-291000D01*
X-136600Y-290417D01*
X-136433Y-290000D01*
X-136100Y-289750D01*
X-135600Y-289667D01*
X-135100Y-289750D01*
X-134600Y-290000D01*
G01X-131417Y-293000D02*
Y-288000D01*
G01X-128750Y-289667D02*
X-131417Y-291583D01*
G01X-130333Y-290833D02*
X-128583Y-293000D01*
G01X-118800Y-288000D02*
Y-293000D01*
G01X-119967Y-289667D02*
X-117633D01*
G01X-114617Y-293000D02*
Y-288000D01*
G01Y-290417D02*
X-114200Y-290000D01*
X-113783Y-289750D01*
X-113117Y-289667D01*
X-112617Y-289750D01*
X-112033Y-290083D01*
X-111783Y-290583D01*
Y-293000D01*
G01X-107600Y-289667D02*
Y-293000D01*
G01Y-288333D02*
X-107767Y-288250D01*
Y-288083D01*
X-107600Y-288000D01*
X-107433Y-288083D01*
Y-288250D01*
X-107600Y-288333D01*
G01X-100667Y-290083D02*
X-101250Y-289750D01*
X-101750Y-289667D01*
X-102417Y-289833D01*
X-102917Y-290167D01*
X-103250Y-290750D01*
X-103333Y-291333D01*
X-103250Y-291917D01*
X-102917Y-292417D01*
X-102417Y-292833D01*
X-101750Y-293000D01*
X-101167Y-292833D01*
X-100667Y-292500D01*
G01X-97817Y-293000D02*
Y-288000D01*
G01X-95150Y-289667D02*
X-97817Y-291583D01*
G01X-96733Y-290833D02*
X-94983Y-293000D01*
G01X-92217D02*
Y-289667D01*
G01Y-290500D02*
X-91883Y-290083D01*
X-91383Y-289750D01*
X-90717Y-289667D01*
X-90133Y-289750D01*
X-89633Y-290083D01*
X-89383Y-290667D01*
Y-293000D01*
G01X-86450Y-290750D02*
X-83783D01*
X-84033Y-290167D01*
X-84450Y-289833D01*
X-85033Y-289667D01*
X-85617Y-289750D01*
X-86117Y-290000D01*
X-86450Y-290583D01*
X-86617Y-291083D01*
Y-291583D01*
X-86450Y-292083D01*
X-86033Y-292583D01*
X-85533Y-292917D01*
X-84950Y-293000D01*
X-84367Y-292833D01*
X-83783Y-292333D01*
G01X-80850Y-292417D02*
X-80433Y-292750D01*
X-79850Y-293000D01*
X-79350D01*
X-78850Y-292833D01*
X-78517Y-292583D01*
X-78350Y-292250D01*
X-78433Y-291750D01*
X-78767Y-291500D01*
X-80267Y-291000D01*
X-80600Y-290417D01*
X-80433Y-290000D01*
X-80100Y-289750D01*
X-79600Y-289667D01*
X-79100Y-289750D01*
X-78600Y-290000D01*
G01X-75250Y-292417D02*
X-74833Y-292750D01*
X-74250Y-293000D01*
X-73750D01*
X-73250Y-292833D01*
X-72917Y-292583D01*
X-72750Y-292250D01*
X-72833Y-291750D01*
X-73167Y-291500D01*
X-74667Y-291000D01*
X-75000Y-290417D01*
X-74833Y-290000D01*
X-74500Y-289750D01*
X-74000Y-289667D01*
X-73500Y-289750D01*
X-73000Y-290000D01*
G01X-186000Y-273000D02*
Y-278000D01*
G01X-187917Y-273000D02*
X-184083D01*
G01X-181817Y-278000D02*
Y-273000D01*
G01Y-275417D02*
X-181400Y-275000D01*
X-180983Y-274750D01*
X-180317Y-274667D01*
X-179817Y-274750D01*
X-179233Y-275083D01*
X-178983Y-275583D01*
Y-278000D01*
G01X-176050Y-275750D02*
X-173383D01*
X-173633Y-275167D01*
X-174050Y-274833D01*
X-174633Y-274667D01*
X-175217Y-274750D01*
X-175717Y-275000D01*
X-176050Y-275583D01*
X-176217Y-276083D01*
Y-276583D01*
X-176050Y-277083D01*
X-175633Y-277583D01*
X-175133Y-277917D01*
X-174550Y-278000D01*
X-173967Y-277833D01*
X-173383Y-277333D01*
G01X-163600Y-278000D02*
Y-273000D01*
G01X-156500Y-278000D02*
Y-274667D01*
G01Y-275250D02*
X-156833Y-274917D01*
X-157333Y-274750D01*
X-157917Y-274667D01*
X-158500Y-274833D01*
X-159000Y-275167D01*
X-159333Y-275667D01*
X-159500Y-276333D01*
X-159333Y-277000D01*
X-159000Y-277500D01*
X-158500Y-277833D01*
X-157917Y-278000D01*
X-157333Y-277917D01*
X-156833Y-277667D01*
X-156500Y-277333D01*
G01X-153567Y-278000D02*
Y-274667D01*
G01Y-275333D02*
X-153150Y-275000D01*
X-152733Y-274750D01*
X-152150Y-274667D01*
X-151733Y-274750D01*
X-151233Y-275000D01*
G01X-147967Y-279250D02*
X-147383Y-279583D01*
X-146717Y-279667D01*
X-146133Y-279583D01*
X-145633Y-279167D01*
X-145300Y-278583D01*
Y-274667D01*
G01Y-275333D02*
X-145633Y-275000D01*
X-146133Y-274750D01*
X-146717Y-274667D01*
X-147383Y-274833D01*
X-147800Y-275167D01*
X-148133Y-275750D01*
X-148300Y-276333D01*
X-148217Y-276833D01*
X-147883Y-277417D01*
X-147383Y-277833D01*
X-146717Y-278000D01*
X-146217Y-277917D01*
X-145633Y-277583D01*
X-145300Y-277250D01*
G01X-142450Y-275750D02*
X-139783D01*
X-140033Y-275167D01*
X-140450Y-274833D01*
X-141033Y-274667D01*
X-141617Y-274750D01*
X-142117Y-275000D01*
X-142450Y-275583D01*
X-142617Y-276083D01*
Y-276583D01*
X-142450Y-277083D01*
X-142033Y-277583D01*
X-141533Y-277917D01*
X-140950Y-278000D01*
X-140367Y-277833D01*
X-139783Y-277333D01*
G01X-136850Y-277417D02*
X-136433Y-277750D01*
X-135850Y-278000D01*
X-135350D01*
X-134850Y-277833D01*
X-134517Y-277583D01*
X-134350Y-277250D01*
X-134433Y-276750D01*
X-134767Y-276500D01*
X-136267Y-276000D01*
X-136600Y-275417D01*
X-136433Y-275000D01*
X-136100Y-274750D01*
X-135600Y-274667D01*
X-135100Y-274750D01*
X-134600Y-275000D01*
G01X-130000Y-273000D02*
Y-278000D01*
G01X-131167Y-274667D02*
X-128833D01*
G01X-117300Y-273000D02*
Y-278000D01*
G01Y-277250D02*
X-117633Y-277667D01*
X-118133Y-277917D01*
X-118717Y-278000D01*
X-119383Y-277833D01*
X-119883Y-277417D01*
X-120217Y-276917D01*
X-120300Y-276333D01*
X-120217Y-275750D01*
X-119883Y-275250D01*
X-119383Y-274833D01*
X-118717Y-274667D01*
X-118133Y-274750D01*
X-117717Y-274917D01*
X-117300Y-275250D01*
G01X-113200Y-274667D02*
Y-278000D01*
G01Y-273333D02*
X-113367Y-273250D01*
Y-273083D01*
X-113200Y-273000D01*
X-113033Y-273083D01*
Y-273250D01*
X-113200Y-273333D01*
G01X-110100Y-278000D02*
Y-274667D01*
G01Y-275583D02*
X-109850Y-275167D01*
X-109433Y-274833D01*
X-108850Y-274667D01*
X-108267Y-274833D01*
X-107850Y-275167D01*
X-107600Y-275583D01*
Y-278000D01*
G01Y-275583D02*
X-107350Y-275167D01*
X-106933Y-274833D01*
X-106350Y-274667D01*
X-105767Y-274833D01*
X-105350Y-275167D01*
X-105100Y-275667D01*
Y-278000D01*
G01X-103250Y-275750D02*
X-100583D01*
X-100833Y-275167D01*
X-101250Y-274833D01*
X-101833Y-274667D01*
X-102417Y-274750D01*
X-102917Y-275000D01*
X-103250Y-275583D01*
X-103417Y-276083D01*
Y-276583D01*
X-103250Y-277083D01*
X-102833Y-277583D01*
X-102333Y-277917D01*
X-101750Y-278000D01*
X-101167Y-277833D01*
X-100583Y-277333D01*
G01X-97817Y-278000D02*
Y-274667D01*
G01Y-275500D02*
X-97483Y-275083D01*
X-96983Y-274750D01*
X-96317Y-274667D01*
X-95733Y-274750D01*
X-95233Y-275083D01*
X-94983Y-275667D01*
Y-278000D01*
G01X-92050Y-277417D02*
X-91633Y-277750D01*
X-91050Y-278000D01*
X-90550D01*
X-90050Y-277833D01*
X-89717Y-277583D01*
X-89550Y-277250D01*
X-89633Y-276750D01*
X-89967Y-276500D01*
X-91467Y-276000D01*
X-91800Y-275417D01*
X-91633Y-275000D01*
X-91300Y-274750D01*
X-90800Y-274667D01*
X-90300Y-274750D01*
X-89800Y-275000D01*
G01X-85200Y-274667D02*
Y-278000D01*
G01Y-273333D02*
X-85367Y-273250D01*
Y-273083D01*
X-85200Y-273000D01*
X-85033Y-273083D01*
Y-273250D01*
X-85200Y-273333D01*
G01X-79600Y-278000D02*
X-80100Y-277917D01*
X-80600Y-277583D01*
X-80933Y-277000D01*
X-81100Y-276333D01*
X-80933Y-275667D01*
X-80600Y-275083D01*
X-80100Y-274750D01*
X-79600Y-274667D01*
X-79100Y-274750D01*
X-78600Y-275083D01*
X-78267Y-275667D01*
X-78183Y-276333D01*
X-78267Y-277000D01*
X-78600Y-277583D01*
X-79100Y-277917D01*
X-79600Y-278000D01*
G01X-75417D02*
Y-274667D01*
G01Y-275500D02*
X-75083Y-275083D01*
X-74583Y-274750D01*
X-73917Y-274667D01*
X-73333Y-274750D01*
X-72833Y-275083D01*
X-72583Y-275667D01*
Y-278000D01*
G01X-62800D02*
X-63300Y-277917D01*
X-63800Y-277583D01*
X-64133Y-277000D01*
X-64300Y-276333D01*
X-64133Y-275667D01*
X-63800Y-275083D01*
X-63300Y-274750D01*
X-62800Y-274667D01*
X-62300Y-274750D01*
X-61800Y-275083D01*
X-61467Y-275667D01*
X-61383Y-276333D01*
X-61467Y-277000D01*
X-61800Y-277583D01*
X-62300Y-277917D01*
X-62800Y-278000D01*
G01X-57700D02*
Y-273750D01*
X-57533Y-273333D01*
X-57200Y-273083D01*
X-56700Y-273000D01*
X-56200Y-273167D01*
X-55950Y-273583D01*
G01X-56950Y-275000D02*
X-58617D01*
G01X-47500Y-279667D02*
Y-274667D01*
G01Y-275417D02*
X-47083Y-275000D01*
X-46667Y-274750D01*
X-46000Y-274667D01*
X-45417Y-274750D01*
X-44833Y-275167D01*
X-44583Y-275750D01*
X-44500Y-276333D01*
X-44583Y-276917D01*
X-44833Y-277500D01*
X-45333Y-277833D01*
X-46000Y-278000D01*
X-46583Y-277917D01*
X-47167Y-277667D01*
X-47500Y-277333D01*
G01X-38900Y-278000D02*
Y-274667D01*
G01Y-275250D02*
X-39233Y-274917D01*
X-39733Y-274750D01*
X-40317Y-274667D01*
X-40900Y-274833D01*
X-41400Y-275167D01*
X-41733Y-275667D01*
X-41900Y-276333D01*
X-41733Y-277000D01*
X-41400Y-277500D01*
X-40900Y-277833D01*
X-40317Y-278000D01*
X-39733Y-277917D01*
X-39233Y-277667D01*
X-38900Y-277333D01*
G01X-33300Y-273000D02*
Y-278000D01*
G01Y-277250D02*
X-33633Y-277667D01*
X-34133Y-277917D01*
X-34717Y-278000D01*
X-35383Y-277833D01*
X-35883Y-277417D01*
X-36217Y-276917D01*
X-36300Y-276333D01*
X-36217Y-275750D01*
X-35883Y-275250D01*
X-35383Y-274833D01*
X-34717Y-274667D01*
X-34133Y-274750D01*
X-33717Y-274917D01*
X-33300Y-275250D01*
G01X-23600Y-278000D02*
X-24100Y-277917D01*
X-24600Y-277583D01*
X-24933Y-277000D01*
X-25100Y-276333D01*
X-24933Y-275667D01*
X-24600Y-275083D01*
X-24100Y-274750D01*
X-23600Y-274667D01*
X-23100Y-274750D01*
X-22600Y-275083D01*
X-22267Y-275667D01*
X-22183Y-276333D01*
X-22267Y-277000D01*
X-22600Y-277583D01*
X-23100Y-277917D01*
X-23600Y-278000D01*
G01X-19167D02*
Y-274667D01*
G01Y-275333D02*
X-18750Y-275000D01*
X-18333Y-274750D01*
X-17750Y-274667D01*
X-17333Y-274750D01*
X-16833Y-275000D01*
G01X-5300Y-273000D02*
Y-278000D01*
G01Y-277250D02*
X-5633Y-277667D01*
X-6133Y-277917D01*
X-6717Y-278000D01*
X-7383Y-277833D01*
X-7883Y-277417D01*
X-8217Y-276917D01*
X-8300Y-276333D01*
X-8217Y-275750D01*
X-7883Y-275250D01*
X-7383Y-274833D01*
X-6717Y-274667D01*
X-6133Y-274750D01*
X-5717Y-274917D01*
X-5300Y-275250D01*
G01X-1200Y-274667D02*
Y-278000D01*
G01Y-273333D02*
X-1367Y-273250D01*
Y-273083D01*
X-1200Y-273000D01*
X-1033Y-273083D01*
Y-273250D01*
X-1200Y-273333D01*
G01X5900Y-278000D02*
Y-274667D01*
G01Y-275250D02*
X5567Y-274917D01*
X5067Y-274750D01*
X4483Y-274667D01*
X3900Y-274833D01*
X3400Y-275167D01*
X3067Y-275667D01*
X2900Y-276333D01*
X3067Y-277000D01*
X3400Y-277500D01*
X3900Y-277833D01*
X4483Y-278000D01*
X5067Y-277917D01*
X5567Y-277667D01*
X5900Y-277333D01*
G01X7500Y-278000D02*
Y-274667D01*
G01Y-275583D02*
X7750Y-275167D01*
X8167Y-274833D01*
X8750Y-274667D01*
X9333Y-274833D01*
X9750Y-275167D01*
X10000Y-275583D01*
Y-278000D01*
G01Y-275583D02*
X10250Y-275167D01*
X10667Y-274833D01*
X11250Y-274667D01*
X11833Y-274833D01*
X12250Y-275167D01*
X12500Y-275667D01*
Y-278000D01*
G01X14350Y-275750D02*
X17017D01*
X16767Y-275167D01*
X16350Y-274833D01*
X15767Y-274667D01*
X15183Y-274750D01*
X14683Y-275000D01*
X14350Y-275583D01*
X14183Y-276083D01*
Y-276583D01*
X14350Y-277083D01*
X14767Y-277583D01*
X15267Y-277917D01*
X15850Y-278000D01*
X16433Y-277833D01*
X17017Y-277333D01*
G01X21200Y-273000D02*
Y-278000D01*
G01X20033Y-274667D02*
X22367D01*
G01X25550Y-275750D02*
X28217D01*
X27967Y-275167D01*
X27550Y-274833D01*
X26967Y-274667D01*
X26383Y-274750D01*
X25883Y-275000D01*
X25550Y-275583D01*
X25383Y-276083D01*
Y-276583D01*
X25550Y-277083D01*
X25967Y-277583D01*
X26467Y-277917D01*
X27050Y-278000D01*
X27633Y-277833D01*
X28217Y-277333D01*
G01X31233Y-278000D02*
Y-274667D01*
G01Y-275333D02*
X31650Y-275000D01*
X32067Y-274750D01*
X32650Y-274667D01*
X33067Y-274750D01*
X33567Y-275000D01*
G01X45267Y-278000D02*
X41933Y-276333D01*
X45267Y-274667D01*
G01X48117Y-277083D02*
X50283D01*
G01Y-275583D02*
X48117D01*
G01X60400Y-278000D02*
Y-273000D01*
X59400Y-274000D01*
G01Y-278000D02*
X61400D01*
G01X67000D02*
Y-273000D01*
X63917Y-276583D01*
X68083D01*
G01X74700Y-278000D02*
Y-274667D01*
G01Y-275583D02*
X74950Y-275167D01*
X75367Y-274833D01*
X75950Y-274667D01*
X76533Y-274833D01*
X76950Y-275167D01*
X77200Y-275583D01*
Y-278000D01*
G01Y-275583D02*
X77450Y-275167D01*
X77867Y-274833D01*
X78450Y-274667D01*
X79033Y-274833D01*
X79450Y-275167D01*
X79700Y-275667D01*
Y-278000D01*
G01X82800Y-274667D02*
Y-278000D01*
G01Y-273333D02*
X82633Y-273250D01*
Y-273083D01*
X82800Y-273000D01*
X82967Y-273083D01*
Y-273250D01*
X82800Y-273333D01*
G01X88400Y-278000D02*
Y-273000D01*
G01X-186000Y-258000D02*
Y-263000D01*
G01X-187917Y-258000D02*
X-184083D01*
G01X-181817Y-263000D02*
Y-258000D01*
G01Y-260417D02*
X-181400Y-260000D01*
X-180983Y-259750D01*
X-180317Y-259667D01*
X-179817Y-259750D01*
X-179233Y-260083D01*
X-178983Y-260583D01*
Y-263000D01*
G01X-176050Y-260750D02*
X-173383D01*
X-173633Y-260167D01*
X-174050Y-259833D01*
X-174633Y-259667D01*
X-175217Y-259750D01*
X-175717Y-260000D01*
X-176050Y-260583D01*
X-176217Y-261083D01*
Y-261583D01*
X-176050Y-262083D01*
X-175633Y-262583D01*
X-175133Y-262917D01*
X-174550Y-263000D01*
X-173967Y-262833D01*
X-173383Y-262333D01*
G01X-163600Y-263000D02*
Y-258000D01*
G01X-156500Y-263000D02*
Y-259667D01*
G01Y-260250D02*
X-156833Y-259917D01*
X-157333Y-259750D01*
X-157917Y-259667D01*
X-158500Y-259833D01*
X-159000Y-260167D01*
X-159333Y-260667D01*
X-159500Y-261333D01*
X-159333Y-262000D01*
X-159000Y-262500D01*
X-158500Y-262833D01*
X-157917Y-263000D01*
X-157333Y-262917D01*
X-156833Y-262667D01*
X-156500Y-262333D01*
G01X-153567Y-263000D02*
Y-259667D01*
G01Y-260333D02*
X-153150Y-260000D01*
X-152733Y-259750D01*
X-152150Y-259667D01*
X-151733Y-259750D01*
X-151233Y-260000D01*
G01X-147967Y-264250D02*
X-147383Y-264583D01*
X-146717Y-264667D01*
X-146133Y-264583D01*
X-145633Y-264167D01*
X-145300Y-263583D01*
Y-259667D01*
G01Y-260333D02*
X-145633Y-260000D01*
X-146133Y-259750D01*
X-146717Y-259667D01*
X-147383Y-259833D01*
X-147800Y-260167D01*
X-148133Y-260750D01*
X-148300Y-261333D01*
X-148217Y-261833D01*
X-147883Y-262417D01*
X-147383Y-262833D01*
X-146717Y-263000D01*
X-146217Y-262917D01*
X-145633Y-262583D01*
X-145300Y-262250D01*
G01X-142450Y-260750D02*
X-139783D01*
X-140033Y-260167D01*
X-140450Y-259833D01*
X-141033Y-259667D01*
X-141617Y-259750D01*
X-142117Y-260000D01*
X-142450Y-260583D01*
X-142617Y-261083D01*
Y-261583D01*
X-142450Y-262083D01*
X-142033Y-262583D01*
X-141533Y-262917D01*
X-140950Y-263000D01*
X-140367Y-262833D01*
X-139783Y-262333D01*
G01X-136850Y-262417D02*
X-136433Y-262750D01*
X-135850Y-263000D01*
X-135350D01*
X-134850Y-262833D01*
X-134517Y-262583D01*
X-134350Y-262250D01*
X-134433Y-261750D01*
X-134767Y-261500D01*
X-136267Y-261000D01*
X-136600Y-260417D01*
X-136433Y-260000D01*
X-136100Y-259750D01*
X-135600Y-259667D01*
X-135100Y-259750D01*
X-134600Y-260000D01*
G01X-130000Y-258000D02*
Y-263000D01*
G01X-131167Y-259667D02*
X-128833D01*
G01X-117300Y-258000D02*
Y-263000D01*
G01Y-262250D02*
X-117633Y-262667D01*
X-118133Y-262917D01*
X-118717Y-263000D01*
X-119383Y-262833D01*
X-119883Y-262417D01*
X-120217Y-261917D01*
X-120300Y-261333D01*
X-120217Y-260750D01*
X-119883Y-260250D01*
X-119383Y-259833D01*
X-118717Y-259667D01*
X-118133Y-259750D01*
X-117717Y-259917D01*
X-117300Y-260250D01*
G01X-113200Y-259667D02*
Y-263000D01*
G01Y-258333D02*
X-113367Y-258250D01*
Y-258083D01*
X-113200Y-258000D01*
X-113033Y-258083D01*
Y-258250D01*
X-113200Y-258333D01*
G01X-110100Y-263000D02*
Y-259667D01*
G01Y-260583D02*
X-109850Y-260167D01*
X-109433Y-259833D01*
X-108850Y-259667D01*
X-108267Y-259833D01*
X-107850Y-260167D01*
X-107600Y-260583D01*
Y-263000D01*
G01Y-260583D02*
X-107350Y-260167D01*
X-106933Y-259833D01*
X-106350Y-259667D01*
X-105767Y-259833D01*
X-105350Y-260167D01*
X-105100Y-260667D01*
Y-263000D01*
G01X-103250Y-260750D02*
X-100583D01*
X-100833Y-260167D01*
X-101250Y-259833D01*
X-101833Y-259667D01*
X-102417Y-259750D01*
X-102917Y-260000D01*
X-103250Y-260583D01*
X-103417Y-261083D01*
Y-261583D01*
X-103250Y-262083D01*
X-102833Y-262583D01*
X-102333Y-262917D01*
X-101750Y-263000D01*
X-101167Y-262833D01*
X-100583Y-262333D01*
G01X-97817Y-263000D02*
Y-259667D01*
G01Y-260500D02*
X-97483Y-260083D01*
X-96983Y-259750D01*
X-96317Y-259667D01*
X-95733Y-259750D01*
X-95233Y-260083D01*
X-94983Y-260667D01*
Y-263000D01*
G01X-92050Y-262417D02*
X-91633Y-262750D01*
X-91050Y-263000D01*
X-90550D01*
X-90050Y-262833D01*
X-89717Y-262583D01*
X-89550Y-262250D01*
X-89633Y-261750D01*
X-89967Y-261500D01*
X-91467Y-261000D01*
X-91800Y-260417D01*
X-91633Y-260000D01*
X-91300Y-259750D01*
X-90800Y-259667D01*
X-90300Y-259750D01*
X-89800Y-260000D01*
G01X-85200Y-259667D02*
Y-263000D01*
G01Y-258333D02*
X-85367Y-258250D01*
Y-258083D01*
X-85200Y-258000D01*
X-85033Y-258083D01*
Y-258250D01*
X-85200Y-258333D01*
G01X-79600Y-263000D02*
X-80100Y-262917D01*
X-80600Y-262583D01*
X-80933Y-262000D01*
X-81100Y-261333D01*
X-80933Y-260667D01*
X-80600Y-260083D01*
X-80100Y-259750D01*
X-79600Y-259667D01*
X-79100Y-259750D01*
X-78600Y-260083D01*
X-78267Y-260667D01*
X-78183Y-261333D01*
X-78267Y-262000D01*
X-78600Y-262583D01*
X-79100Y-262917D01*
X-79600Y-263000D01*
G01X-75417D02*
Y-259667D01*
G01Y-260500D02*
X-75083Y-260083D01*
X-74583Y-259750D01*
X-73917Y-259667D01*
X-73333Y-259750D01*
X-72833Y-260083D01*
X-72583Y-260667D01*
Y-263000D01*
G01X-62800D02*
X-63300Y-262917D01*
X-63800Y-262583D01*
X-64133Y-262000D01*
X-64300Y-261333D01*
X-64133Y-260667D01*
X-63800Y-260083D01*
X-63300Y-259750D01*
X-62800Y-259667D01*
X-62300Y-259750D01*
X-61800Y-260083D01*
X-61467Y-260667D01*
X-61383Y-261333D01*
X-61467Y-262000D01*
X-61800Y-262583D01*
X-62300Y-262917D01*
X-62800Y-263000D01*
G01X-57700D02*
Y-258750D01*
X-57533Y-258333D01*
X-57200Y-258083D01*
X-56700Y-258000D01*
X-56200Y-258167D01*
X-55950Y-258583D01*
G01X-56950Y-260000D02*
X-58617D01*
G01X-47500Y-264667D02*
Y-259667D01*
G01Y-260417D02*
X-47083Y-260000D01*
X-46667Y-259750D01*
X-46000Y-259667D01*
X-45417Y-259750D01*
X-44833Y-260167D01*
X-44583Y-260750D01*
X-44500Y-261333D01*
X-44583Y-261917D01*
X-44833Y-262500D01*
X-45333Y-262833D01*
X-46000Y-263000D01*
X-46583Y-262917D01*
X-47167Y-262667D01*
X-47500Y-262333D01*
G01X-38900Y-263000D02*
Y-259667D01*
G01Y-260250D02*
X-39233Y-259917D01*
X-39733Y-259750D01*
X-40317Y-259667D01*
X-40900Y-259833D01*
X-41400Y-260167D01*
X-41733Y-260667D01*
X-41900Y-261333D01*
X-41733Y-262000D01*
X-41400Y-262500D01*
X-40900Y-262833D01*
X-40317Y-263000D01*
X-39733Y-262917D01*
X-39233Y-262667D01*
X-38900Y-262333D01*
G01X-33300Y-258000D02*
Y-263000D01*
G01Y-262250D02*
X-33633Y-262667D01*
X-34133Y-262917D01*
X-34717Y-263000D01*
X-35383Y-262833D01*
X-35883Y-262417D01*
X-36217Y-261917D01*
X-36300Y-261333D01*
X-36217Y-260750D01*
X-35883Y-260250D01*
X-35383Y-259833D01*
X-34717Y-259667D01*
X-34133Y-259750D01*
X-33717Y-259917D01*
X-33300Y-260250D01*
G01X-23600Y-263000D02*
X-24100Y-262917D01*
X-24600Y-262583D01*
X-24933Y-262000D01*
X-25100Y-261333D01*
X-24933Y-260667D01*
X-24600Y-260083D01*
X-24100Y-259750D01*
X-23600Y-259667D01*
X-23100Y-259750D01*
X-22600Y-260083D01*
X-22267Y-260667D01*
X-22183Y-261333D01*
X-22267Y-262000D01*
X-22600Y-262583D01*
X-23100Y-262917D01*
X-23600Y-263000D01*
G01X-19167D02*
Y-259667D01*
G01Y-260333D02*
X-18750Y-260000D01*
X-18333Y-259750D01*
X-17750Y-259667D01*
X-17333Y-259750D01*
X-16833Y-260000D01*
G01X-5300Y-258000D02*
Y-263000D01*
G01Y-262250D02*
X-5633Y-262667D01*
X-6133Y-262917D01*
X-6717Y-263000D01*
X-7383Y-262833D01*
X-7883Y-262417D01*
X-8217Y-261917D01*
X-8300Y-261333D01*
X-8217Y-260750D01*
X-7883Y-260250D01*
X-7383Y-259833D01*
X-6717Y-259667D01*
X-6133Y-259750D01*
X-5717Y-259917D01*
X-5300Y-260250D01*
G01X-1200Y-259667D02*
Y-263000D01*
G01Y-258333D02*
X-1367Y-258250D01*
Y-258083D01*
X-1200Y-258000D01*
X-1033Y-258083D01*
Y-258250D01*
X-1200Y-258333D01*
G01X5900Y-263000D02*
Y-259667D01*
G01Y-260250D02*
X5567Y-259917D01*
X5067Y-259750D01*
X4483Y-259667D01*
X3900Y-259833D01*
X3400Y-260167D01*
X3067Y-260667D01*
X2900Y-261333D01*
X3067Y-262000D01*
X3400Y-262500D01*
X3900Y-262833D01*
X4483Y-263000D01*
X5067Y-262917D01*
X5567Y-262667D01*
X5900Y-262333D01*
G01X7500Y-263000D02*
Y-259667D01*
G01Y-260583D02*
X7750Y-260167D01*
X8167Y-259833D01*
X8750Y-259667D01*
X9333Y-259833D01*
X9750Y-260167D01*
X10000Y-260583D01*
Y-263000D01*
G01Y-260583D02*
X10250Y-260167D01*
X10667Y-259833D01*
X11250Y-259667D01*
X11833Y-259833D01*
X12250Y-260167D01*
X12500Y-260667D01*
Y-263000D01*
G01X14350Y-260750D02*
X17017D01*
X16767Y-260167D01*
X16350Y-259833D01*
X15767Y-259667D01*
X15183Y-259750D01*
X14683Y-260000D01*
X14350Y-260583D01*
X14183Y-261083D01*
Y-261583D01*
X14350Y-262083D01*
X14767Y-262583D01*
X15267Y-262917D01*
X15850Y-263000D01*
X16433Y-262833D01*
X17017Y-262333D01*
G01X21200Y-258000D02*
Y-263000D01*
G01X20033Y-259667D02*
X22367D01*
G01X25550Y-260750D02*
X28217D01*
X27967Y-260167D01*
X27550Y-259833D01*
X26967Y-259667D01*
X26383Y-259750D01*
X25883Y-260000D01*
X25550Y-260583D01*
X25383Y-261083D01*
Y-261583D01*
X25550Y-262083D01*
X25967Y-262583D01*
X26467Y-262917D01*
X27050Y-263000D01*
X27633Y-262833D01*
X28217Y-262333D01*
G01X31233Y-263000D02*
Y-259667D01*
G01Y-260333D02*
X31650Y-260000D01*
X32067Y-259750D01*
X32650Y-259667D01*
X33067Y-259750D01*
X33567Y-260000D01*
G01X41933Y-263000D02*
X45267Y-261333D01*
X41933Y-259667D01*
G01X49200Y-263000D02*
Y-258000D01*
X48200Y-259000D01*
G01Y-263000D02*
X50200D01*
G01X55800D02*
Y-258000D01*
X52717Y-261583D01*
X56883D01*
G01X63500Y-263000D02*
Y-259667D01*
G01Y-260583D02*
X63750Y-260167D01*
X64167Y-259833D01*
X64750Y-259667D01*
X65333Y-259833D01*
X65750Y-260167D01*
X66000Y-260583D01*
Y-263000D01*
G01Y-260583D02*
X66250Y-260167D01*
X66667Y-259833D01*
X67250Y-259667D01*
X67833Y-259833D01*
X68250Y-260167D01*
X68500Y-260667D01*
Y-263000D01*
G01X71600Y-259667D02*
Y-263000D01*
G01Y-258333D02*
X71433Y-258250D01*
Y-258083D01*
X71600Y-258000D01*
X71767Y-258083D01*
Y-258250D01*
X71600Y-258333D01*
G01X77200Y-263000D02*
Y-258000D01*
G01X-184920Y-240330D02*
Y-245330D01*
G01X-186837Y-240330D02*
X-183003D01*
G01X-180737Y-245330D02*
Y-240330D01*
G01Y-242747D02*
X-180320Y-242330D01*
X-179903Y-242080D01*
X-179237Y-241997D01*
X-178737Y-242080D01*
X-178153Y-242413D01*
X-177903Y-242913D01*
Y-245330D01*
G01X-174970Y-243080D02*
X-172303D01*
X-172553Y-242497D01*
X-172970Y-242163D01*
X-173553Y-241997D01*
X-174137Y-242080D01*
X-174637Y-242330D01*
X-174970Y-242913D01*
X-175137Y-243413D01*
Y-243913D01*
X-174970Y-244413D01*
X-174553Y-244913D01*
X-174053Y-245247D01*
X-173470Y-245330D01*
X-172887Y-245163D01*
X-172303Y-244663D01*
G01X-162520Y-245330D02*
Y-240330D01*
G01X-155420Y-245330D02*
Y-241997D01*
G01Y-242580D02*
X-155753Y-242247D01*
X-156253Y-242080D01*
X-156837Y-241997D01*
X-157420Y-242163D01*
X-157920Y-242497D01*
X-158253Y-242997D01*
X-158420Y-243663D01*
X-158253Y-244330D01*
X-157920Y-244830D01*
X-157420Y-245163D01*
X-156837Y-245330D01*
X-156253Y-245247D01*
X-155753Y-244997D01*
X-155420Y-244663D01*
G01X-152487Y-245330D02*
Y-241997D01*
G01Y-242663D02*
X-152070Y-242330D01*
X-151653Y-242080D01*
X-151070Y-241997D01*
X-150653Y-242080D01*
X-150153Y-242330D01*
G01X-146887Y-246580D02*
X-146303Y-246913D01*
X-145637Y-246997D01*
X-145053Y-246913D01*
X-144553Y-246497D01*
X-144220Y-245913D01*
Y-241997D01*
G01Y-242663D02*
X-144553Y-242330D01*
X-145053Y-242080D01*
X-145637Y-241997D01*
X-146303Y-242163D01*
X-146720Y-242497D01*
X-147053Y-243080D01*
X-147220Y-243663D01*
X-147137Y-244163D01*
X-146803Y-244747D01*
X-146303Y-245163D01*
X-145637Y-245330D01*
X-145137Y-245247D01*
X-144553Y-244913D01*
X-144220Y-244580D01*
G01X-141370Y-243080D02*
X-138703D01*
X-138953Y-242497D01*
X-139370Y-242163D01*
X-139953Y-241997D01*
X-140537Y-242080D01*
X-141037Y-242330D01*
X-141370Y-242913D01*
X-141537Y-243413D01*
Y-243913D01*
X-141370Y-244413D01*
X-140953Y-244913D01*
X-140453Y-245247D01*
X-139870Y-245330D01*
X-139287Y-245163D01*
X-138703Y-244663D01*
G01X-135770Y-244747D02*
X-135353Y-245080D01*
X-134770Y-245330D01*
X-134270D01*
X-133770Y-245163D01*
X-133437Y-244913D01*
X-133270Y-244580D01*
X-133353Y-244080D01*
X-133687Y-243830D01*
X-135187Y-243330D01*
X-135520Y-242747D01*
X-135353Y-242330D01*
X-135020Y-242080D01*
X-134520Y-241997D01*
X-134020Y-242080D01*
X-133520Y-242330D01*
G01X-128920Y-240330D02*
Y-245330D01*
G01X-130087Y-241997D02*
X-127753D01*
G01X-116220Y-240330D02*
Y-245330D01*
G01Y-244580D02*
X-116553Y-244997D01*
X-117053Y-245247D01*
X-117637Y-245330D01*
X-118303Y-245163D01*
X-118803Y-244747D01*
X-119137Y-244247D01*
X-119220Y-243663D01*
X-119137Y-243080D01*
X-118803Y-242580D01*
X-118303Y-242163D01*
X-117637Y-241997D01*
X-117053Y-242080D01*
X-116637Y-242247D01*
X-116220Y-242580D01*
G01X-112120Y-241997D02*
Y-245330D01*
G01Y-240663D02*
X-112287Y-240580D01*
Y-240413D01*
X-112120Y-240330D01*
X-111953Y-240413D01*
Y-240580D01*
X-112120Y-240663D01*
G01X-109020Y-245330D02*
Y-241997D01*
G01Y-242913D02*
X-108770Y-242497D01*
X-108353Y-242163D01*
X-107770Y-241997D01*
X-107187Y-242163D01*
X-106770Y-242497D01*
X-106520Y-242913D01*
Y-245330D01*
G01Y-242913D02*
X-106270Y-242497D01*
X-105853Y-242163D01*
X-105270Y-241997D01*
X-104687Y-242163D01*
X-104270Y-242497D01*
X-104020Y-242997D01*
Y-245330D01*
G01X-102170Y-243080D02*
X-99503D01*
X-99753Y-242497D01*
X-100170Y-242163D01*
X-100753Y-241997D01*
X-101337Y-242080D01*
X-101837Y-242330D01*
X-102170Y-242913D01*
X-102337Y-243413D01*
Y-243913D01*
X-102170Y-244413D01*
X-101753Y-244913D01*
X-101253Y-245247D01*
X-100670Y-245330D01*
X-100087Y-245163D01*
X-99503Y-244663D01*
G01X-96737Y-245330D02*
Y-241997D01*
G01Y-242830D02*
X-96403Y-242413D01*
X-95903Y-242080D01*
X-95237Y-241997D01*
X-94653Y-242080D01*
X-94153Y-242413D01*
X-93903Y-242997D01*
Y-245330D01*
G01X-90970Y-244747D02*
X-90553Y-245080D01*
X-89970Y-245330D01*
X-89470D01*
X-88970Y-245163D01*
X-88637Y-244913D01*
X-88470Y-244580D01*
X-88553Y-244080D01*
X-88887Y-243830D01*
X-90387Y-243330D01*
X-90720Y-242747D01*
X-90553Y-242330D01*
X-90220Y-242080D01*
X-89720Y-241997D01*
X-89220Y-242080D01*
X-88720Y-242330D01*
G01X-84120Y-241997D02*
Y-245330D01*
G01Y-240663D02*
X-84287Y-240580D01*
Y-240413D01*
X-84120Y-240330D01*
X-83953Y-240413D01*
Y-240580D01*
X-84120Y-240663D01*
G01X-78520Y-245330D02*
X-79020Y-245247D01*
X-79520Y-244913D01*
X-79853Y-244330D01*
X-80020Y-243663D01*
X-79853Y-242997D01*
X-79520Y-242413D01*
X-79020Y-242080D01*
X-78520Y-241997D01*
X-78020Y-242080D01*
X-77520Y-242413D01*
X-77187Y-242997D01*
X-77103Y-243663D01*
X-77187Y-244330D01*
X-77520Y-244913D01*
X-78020Y-245247D01*
X-78520Y-245330D01*
G01X-74337D02*
Y-241997D01*
G01Y-242830D02*
X-74003Y-242413D01*
X-73503Y-242080D01*
X-72837Y-241997D01*
X-72253Y-242080D01*
X-71753Y-242413D01*
X-71503Y-242997D01*
Y-245330D01*
G01X-61720D02*
X-62220Y-245247D01*
X-62720Y-244913D01*
X-63053Y-244330D01*
X-63220Y-243663D01*
X-63053Y-242997D01*
X-62720Y-242413D01*
X-62220Y-242080D01*
X-61720Y-241997D01*
X-61220Y-242080D01*
X-60720Y-242413D01*
X-60387Y-242997D01*
X-60303Y-243663D01*
X-60387Y-244330D01*
X-60720Y-244913D01*
X-61220Y-245247D01*
X-61720Y-245330D01*
G01X-56620D02*
Y-241080D01*
X-56453Y-240663D01*
X-56120Y-240413D01*
X-55620Y-240330D01*
X-55120Y-240497D01*
X-54870Y-240913D01*
G01X-55870Y-242330D02*
X-57537D01*
G01X-46420Y-246997D02*
Y-241997D01*
G01Y-242747D02*
X-46003Y-242330D01*
X-45587Y-242080D01*
X-44920Y-241997D01*
X-44337Y-242080D01*
X-43753Y-242497D01*
X-43503Y-243080D01*
X-43420Y-243663D01*
X-43503Y-244247D01*
X-43753Y-244830D01*
X-44253Y-245163D01*
X-44920Y-245330D01*
X-45503Y-245247D01*
X-46087Y-244997D01*
X-46420Y-244663D01*
G01X-37820Y-245330D02*
Y-241997D01*
G01Y-242580D02*
X-38153Y-242247D01*
X-38653Y-242080D01*
X-39237Y-241997D01*
X-39820Y-242163D01*
X-40320Y-242497D01*
X-40653Y-242997D01*
X-40820Y-243663D01*
X-40653Y-244330D01*
X-40320Y-244830D01*
X-39820Y-245163D01*
X-39237Y-245330D01*
X-38653Y-245247D01*
X-38153Y-244997D01*
X-37820Y-244663D01*
G01X-32220Y-240330D02*
Y-245330D01*
G01Y-244580D02*
X-32553Y-244997D01*
X-33053Y-245247D01*
X-33637Y-245330D01*
X-34303Y-245163D01*
X-34803Y-244747D01*
X-35137Y-244247D01*
X-35220Y-243663D01*
X-35137Y-243080D01*
X-34803Y-242580D01*
X-34303Y-242163D01*
X-33637Y-241997D01*
X-33053Y-242080D01*
X-32637Y-242247D01*
X-32220Y-242580D01*
G01X-22520Y-245330D02*
X-23020Y-245247D01*
X-23520Y-244913D01*
X-23853Y-244330D01*
X-24020Y-243663D01*
X-23853Y-242997D01*
X-23520Y-242413D01*
X-23020Y-242080D01*
X-22520Y-241997D01*
X-22020Y-242080D01*
X-21520Y-242413D01*
X-21187Y-242997D01*
X-21103Y-243663D01*
X-21187Y-244330D01*
X-21520Y-244913D01*
X-22020Y-245247D01*
X-22520Y-245330D01*
G01X-18087D02*
Y-241997D01*
G01Y-242663D02*
X-17670Y-242330D01*
X-17253Y-242080D01*
X-16670Y-241997D01*
X-16253Y-242080D01*
X-15753Y-242330D01*
G01X-4220Y-240330D02*
Y-245330D01*
G01Y-244580D02*
X-4553Y-244997D01*
X-5053Y-245247D01*
X-5637Y-245330D01*
X-6303Y-245163D01*
X-6803Y-244747D01*
X-7137Y-244247D01*
X-7220Y-243663D01*
X-7137Y-243080D01*
X-6803Y-242580D01*
X-6303Y-242163D01*
X-5637Y-241997D01*
X-5053Y-242080D01*
X-4637Y-242247D01*
X-4220Y-242580D01*
G01X-120Y-241997D02*
Y-245330D01*
G01Y-240663D02*
X-287Y-240580D01*
Y-240413D01*
X-120Y-240330D01*
X47Y-240413D01*
Y-240580D01*
X-120Y-240663D01*
G01X6980Y-245330D02*
Y-241997D01*
G01Y-242580D02*
X6647Y-242247D01*
X6147Y-242080D01*
X5563Y-241997D01*
X4980Y-242163D01*
X4480Y-242497D01*
X4147Y-242997D01*
X3980Y-243663D01*
X4147Y-244330D01*
X4480Y-244830D01*
X4980Y-245163D01*
X5563Y-245330D01*
X6147Y-245247D01*
X6647Y-244997D01*
X6980Y-244663D01*
G01X8580Y-245330D02*
Y-241997D01*
G01Y-242913D02*
X8830Y-242497D01*
X9247Y-242163D01*
X9830Y-241997D01*
X10413Y-242163D01*
X10830Y-242497D01*
X11080Y-242913D01*
Y-245330D01*
G01Y-242913D02*
X11330Y-242497D01*
X11747Y-242163D01*
X12330Y-241997D01*
X12913Y-242163D01*
X13330Y-242497D01*
X13580Y-242997D01*
Y-245330D01*
G01X15430Y-243080D02*
X18097D01*
X17847Y-242497D01*
X17430Y-242163D01*
X16847Y-241997D01*
X16263Y-242080D01*
X15763Y-242330D01*
X15430Y-242913D01*
X15263Y-243413D01*
Y-243913D01*
X15430Y-244413D01*
X15847Y-244913D01*
X16347Y-245247D01*
X16930Y-245330D01*
X17513Y-245163D01*
X18097Y-244663D01*
G01X22280Y-240330D02*
Y-245330D01*
G01X21113Y-241997D02*
X23447D01*
G01X26630Y-243080D02*
X29297D01*
X29047Y-242497D01*
X28630Y-242163D01*
X28047Y-241997D01*
X27463Y-242080D01*
X26963Y-242330D01*
X26630Y-242913D01*
X26463Y-243413D01*
Y-243913D01*
X26630Y-244413D01*
X27047Y-244913D01*
X27547Y-245247D01*
X28130Y-245330D01*
X28713Y-245163D01*
X29297Y-244663D01*
G01X32313Y-245330D02*
Y-241997D01*
G01Y-242663D02*
X32730Y-242330D01*
X33147Y-242080D01*
X33730Y-241997D01*
X34147Y-242080D01*
X34647Y-242330D01*
G01X46347Y-245330D02*
X43013Y-243663D01*
X46347Y-241997D01*
G01X49197Y-244413D02*
X51363D01*
G01Y-242913D02*
X49197D01*
G01X61480Y-245330D02*
Y-240330D01*
X60480Y-241330D01*
G01Y-245330D02*
X62480D01*
G01X68080D02*
Y-240330D01*
X64997Y-243913D01*
X69163D01*
G01X75780Y-245330D02*
Y-241997D01*
G01Y-242913D02*
X76030Y-242497D01*
X76447Y-242163D01*
X77030Y-241997D01*
X77613Y-242163D01*
X78030Y-242497D01*
X78280Y-242913D01*
Y-245330D01*
G01Y-242913D02*
X78530Y-242497D01*
X78947Y-242163D01*
X79530Y-241997D01*
X80113Y-242163D01*
X80530Y-242497D01*
X80780Y-242997D01*
Y-245330D01*
G01X83880Y-241997D02*
Y-245330D01*
G01Y-240663D02*
X83713Y-240580D01*
Y-240413D01*
X83880Y-240330D01*
X84047Y-240413D01*
Y-240580D01*
X83880Y-240663D01*
G01X89480Y-245330D02*
Y-240330D01*
G01X-186000Y-221000D02*
Y-226000D01*
G01X-187917Y-221000D02*
X-184083D01*
G01X-181817Y-226000D02*
Y-221000D01*
G01Y-223417D02*
X-181400Y-223000D01*
X-180983Y-222750D01*
X-180317Y-222667D01*
X-179817Y-222750D01*
X-179233Y-223083D01*
X-178983Y-223583D01*
Y-226000D01*
G01X-176050Y-223750D02*
X-173383D01*
X-173633Y-223167D01*
X-174050Y-222833D01*
X-174633Y-222667D01*
X-175217Y-222750D01*
X-175717Y-223000D01*
X-176050Y-223583D01*
X-176217Y-224083D01*
Y-224583D01*
X-176050Y-225083D01*
X-175633Y-225583D01*
X-175133Y-225917D01*
X-174550Y-226000D01*
X-173967Y-225833D01*
X-173383Y-225333D01*
G01X-163600Y-226000D02*
Y-221000D01*
G01X-156500Y-226000D02*
Y-222667D01*
G01Y-223250D02*
X-156833Y-222917D01*
X-157333Y-222750D01*
X-157917Y-222667D01*
X-158500Y-222833D01*
X-159000Y-223167D01*
X-159333Y-223667D01*
X-159500Y-224333D01*
X-159333Y-225000D01*
X-159000Y-225500D01*
X-158500Y-225833D01*
X-157917Y-226000D01*
X-157333Y-225917D01*
X-156833Y-225667D01*
X-156500Y-225333D01*
G01X-153567Y-226000D02*
Y-222667D01*
G01Y-223333D02*
X-153150Y-223000D01*
X-152733Y-222750D01*
X-152150Y-222667D01*
X-151733Y-222750D01*
X-151233Y-223000D01*
G01X-147967Y-227250D02*
X-147383Y-227583D01*
X-146717Y-227667D01*
X-146133Y-227583D01*
X-145633Y-227167D01*
X-145300Y-226583D01*
Y-222667D01*
G01Y-223333D02*
X-145633Y-223000D01*
X-146133Y-222750D01*
X-146717Y-222667D01*
X-147383Y-222833D01*
X-147800Y-223167D01*
X-148133Y-223750D01*
X-148300Y-224333D01*
X-148217Y-224833D01*
X-147883Y-225417D01*
X-147383Y-225833D01*
X-146717Y-226000D01*
X-146217Y-225917D01*
X-145633Y-225583D01*
X-145300Y-225250D01*
G01X-142450Y-223750D02*
X-139783D01*
X-140033Y-223167D01*
X-140450Y-222833D01*
X-141033Y-222667D01*
X-141617Y-222750D01*
X-142117Y-223000D01*
X-142450Y-223583D01*
X-142617Y-224083D01*
Y-224583D01*
X-142450Y-225083D01*
X-142033Y-225583D01*
X-141533Y-225917D01*
X-140950Y-226000D01*
X-140367Y-225833D01*
X-139783Y-225333D01*
G01X-136850Y-225417D02*
X-136433Y-225750D01*
X-135850Y-226000D01*
X-135350D01*
X-134850Y-225833D01*
X-134517Y-225583D01*
X-134350Y-225250D01*
X-134433Y-224750D01*
X-134767Y-224500D01*
X-136267Y-224000D01*
X-136600Y-223417D01*
X-136433Y-223000D01*
X-136100Y-222750D01*
X-135600Y-222667D01*
X-135100Y-222750D01*
X-134600Y-223000D01*
G01X-130000Y-221000D02*
Y-226000D01*
G01X-131167Y-222667D02*
X-128833D01*
G01X-117300Y-221000D02*
Y-226000D01*
G01Y-225250D02*
X-117633Y-225667D01*
X-118133Y-225917D01*
X-118717Y-226000D01*
X-119383Y-225833D01*
X-119883Y-225417D01*
X-120217Y-224917D01*
X-120300Y-224333D01*
X-120217Y-223750D01*
X-119883Y-223250D01*
X-119383Y-222833D01*
X-118717Y-222667D01*
X-118133Y-222750D01*
X-117717Y-222917D01*
X-117300Y-223250D01*
G01X-113200Y-222667D02*
Y-226000D01*
G01Y-221333D02*
X-113367Y-221250D01*
Y-221083D01*
X-113200Y-221000D01*
X-113033Y-221083D01*
Y-221250D01*
X-113200Y-221333D01*
G01X-110100Y-226000D02*
Y-222667D01*
G01Y-223583D02*
X-109850Y-223167D01*
X-109433Y-222833D01*
X-108850Y-222667D01*
X-108267Y-222833D01*
X-107850Y-223167D01*
X-107600Y-223583D01*
Y-226000D01*
G01Y-223583D02*
X-107350Y-223167D01*
X-106933Y-222833D01*
X-106350Y-222667D01*
X-105767Y-222833D01*
X-105350Y-223167D01*
X-105100Y-223667D01*
Y-226000D01*
G01X-103250Y-223750D02*
X-100583D01*
X-100833Y-223167D01*
X-101250Y-222833D01*
X-101833Y-222667D01*
X-102417Y-222750D01*
X-102917Y-223000D01*
X-103250Y-223583D01*
X-103417Y-224083D01*
Y-224583D01*
X-103250Y-225083D01*
X-102833Y-225583D01*
X-102333Y-225917D01*
X-101750Y-226000D01*
X-101167Y-225833D01*
X-100583Y-225333D01*
G01X-97817Y-226000D02*
Y-222667D01*
G01Y-223500D02*
X-97483Y-223083D01*
X-96983Y-222750D01*
X-96317Y-222667D01*
X-95733Y-222750D01*
X-95233Y-223083D01*
X-94983Y-223667D01*
Y-226000D01*
G01X-92050Y-225417D02*
X-91633Y-225750D01*
X-91050Y-226000D01*
X-90550D01*
X-90050Y-225833D01*
X-89717Y-225583D01*
X-89550Y-225250D01*
X-89633Y-224750D01*
X-89967Y-224500D01*
X-91467Y-224000D01*
X-91800Y-223417D01*
X-91633Y-223000D01*
X-91300Y-222750D01*
X-90800Y-222667D01*
X-90300Y-222750D01*
X-89800Y-223000D01*
G01X-85200Y-222667D02*
Y-226000D01*
G01Y-221333D02*
X-85367Y-221250D01*
Y-221083D01*
X-85200Y-221000D01*
X-85033Y-221083D01*
Y-221250D01*
X-85200Y-221333D01*
G01X-79600Y-226000D02*
X-80100Y-225917D01*
X-80600Y-225583D01*
X-80933Y-225000D01*
X-81100Y-224333D01*
X-80933Y-223667D01*
X-80600Y-223083D01*
X-80100Y-222750D01*
X-79600Y-222667D01*
X-79100Y-222750D01*
X-78600Y-223083D01*
X-78267Y-223667D01*
X-78183Y-224333D01*
X-78267Y-225000D01*
X-78600Y-225583D01*
X-79100Y-225917D01*
X-79600Y-226000D01*
G01X-75417D02*
Y-222667D01*
G01Y-223500D02*
X-75083Y-223083D01*
X-74583Y-222750D01*
X-73917Y-222667D01*
X-73333Y-222750D01*
X-72833Y-223083D01*
X-72583Y-223667D01*
Y-226000D01*
G01X-62800D02*
X-63300Y-225917D01*
X-63800Y-225583D01*
X-64133Y-225000D01*
X-64300Y-224333D01*
X-64133Y-223667D01*
X-63800Y-223083D01*
X-63300Y-222750D01*
X-62800Y-222667D01*
X-62300Y-222750D01*
X-61800Y-223083D01*
X-61467Y-223667D01*
X-61383Y-224333D01*
X-61467Y-225000D01*
X-61800Y-225583D01*
X-62300Y-225917D01*
X-62800Y-226000D01*
G01X-57700D02*
Y-221750D01*
X-57533Y-221333D01*
X-57200Y-221083D01*
X-56700Y-221000D01*
X-56200Y-221167D01*
X-55950Y-221583D01*
G01X-56950Y-223000D02*
X-58617D01*
G01X-47500Y-227667D02*
Y-222667D01*
G01Y-223417D02*
X-47083Y-223000D01*
X-46667Y-222750D01*
X-46000Y-222667D01*
X-45417Y-222750D01*
X-44833Y-223167D01*
X-44583Y-223750D01*
X-44500Y-224333D01*
X-44583Y-224917D01*
X-44833Y-225500D01*
X-45333Y-225833D01*
X-46000Y-226000D01*
X-46583Y-225917D01*
X-47167Y-225667D01*
X-47500Y-225333D01*
G01X-38900Y-226000D02*
Y-222667D01*
G01Y-223250D02*
X-39233Y-222917D01*
X-39733Y-222750D01*
X-40317Y-222667D01*
X-40900Y-222833D01*
X-41400Y-223167D01*
X-41733Y-223667D01*
X-41900Y-224333D01*
X-41733Y-225000D01*
X-41400Y-225500D01*
X-40900Y-225833D01*
X-40317Y-226000D01*
X-39733Y-225917D01*
X-39233Y-225667D01*
X-38900Y-225333D01*
G01X-33300Y-221000D02*
Y-226000D01*
G01Y-225250D02*
X-33633Y-225667D01*
X-34133Y-225917D01*
X-34717Y-226000D01*
X-35383Y-225833D01*
X-35883Y-225417D01*
X-36217Y-224917D01*
X-36300Y-224333D01*
X-36217Y-223750D01*
X-35883Y-223250D01*
X-35383Y-222833D01*
X-34717Y-222667D01*
X-34133Y-222750D01*
X-33717Y-222917D01*
X-33300Y-223250D01*
G01X-23600Y-226000D02*
X-24100Y-225917D01*
X-24600Y-225583D01*
X-24933Y-225000D01*
X-25100Y-224333D01*
X-24933Y-223667D01*
X-24600Y-223083D01*
X-24100Y-222750D01*
X-23600Y-222667D01*
X-23100Y-222750D01*
X-22600Y-223083D01*
X-22267Y-223667D01*
X-22183Y-224333D01*
X-22267Y-225000D01*
X-22600Y-225583D01*
X-23100Y-225917D01*
X-23600Y-226000D01*
G01X-19167D02*
Y-222667D01*
G01Y-223333D02*
X-18750Y-223000D01*
X-18333Y-222750D01*
X-17750Y-222667D01*
X-17333Y-222750D01*
X-16833Y-223000D01*
G01X-5300Y-221000D02*
Y-226000D01*
G01Y-225250D02*
X-5633Y-225667D01*
X-6133Y-225917D01*
X-6717Y-226000D01*
X-7383Y-225833D01*
X-7883Y-225417D01*
X-8217Y-224917D01*
X-8300Y-224333D01*
X-8217Y-223750D01*
X-7883Y-223250D01*
X-7383Y-222833D01*
X-6717Y-222667D01*
X-6133Y-222750D01*
X-5717Y-222917D01*
X-5300Y-223250D01*
G01X-1200Y-222667D02*
Y-226000D01*
G01Y-221333D02*
X-1367Y-221250D01*
Y-221083D01*
X-1200Y-221000D01*
X-1033Y-221083D01*
Y-221250D01*
X-1200Y-221333D01*
G01X5900Y-226000D02*
Y-222667D01*
G01Y-223250D02*
X5567Y-222917D01*
X5067Y-222750D01*
X4483Y-222667D01*
X3900Y-222833D01*
X3400Y-223167D01*
X3067Y-223667D01*
X2900Y-224333D01*
X3067Y-225000D01*
X3400Y-225500D01*
X3900Y-225833D01*
X4483Y-226000D01*
X5067Y-225917D01*
X5567Y-225667D01*
X5900Y-225333D01*
G01X7500Y-226000D02*
Y-222667D01*
G01Y-223583D02*
X7750Y-223167D01*
X8167Y-222833D01*
X8750Y-222667D01*
X9333Y-222833D01*
X9750Y-223167D01*
X10000Y-223583D01*
Y-226000D01*
G01Y-223583D02*
X10250Y-223167D01*
X10667Y-222833D01*
X11250Y-222667D01*
X11833Y-222833D01*
X12250Y-223167D01*
X12500Y-223667D01*
Y-226000D01*
G01X14350Y-223750D02*
X17017D01*
X16767Y-223167D01*
X16350Y-222833D01*
X15767Y-222667D01*
X15183Y-222750D01*
X14683Y-223000D01*
X14350Y-223583D01*
X14183Y-224083D01*
Y-224583D01*
X14350Y-225083D01*
X14767Y-225583D01*
X15267Y-225917D01*
X15850Y-226000D01*
X16433Y-225833D01*
X17017Y-225333D01*
G01X21200Y-221000D02*
Y-226000D01*
G01X20033Y-222667D02*
X22367D01*
G01X25550Y-223750D02*
X28217D01*
X27967Y-223167D01*
X27550Y-222833D01*
X26967Y-222667D01*
X26383Y-222750D01*
X25883Y-223000D01*
X25550Y-223583D01*
X25383Y-224083D01*
Y-224583D01*
X25550Y-225083D01*
X25967Y-225583D01*
X26467Y-225917D01*
X27050Y-226000D01*
X27633Y-225833D01*
X28217Y-225333D01*
G01X31233Y-226000D02*
Y-222667D01*
G01Y-223333D02*
X31650Y-223000D01*
X32067Y-222750D01*
X32650Y-222667D01*
X33067Y-222750D01*
X33567Y-223000D01*
G01X41933Y-226000D02*
X45267Y-224333D01*
X41933Y-222667D01*
G01X54800Y-226000D02*
Y-221000D01*
X53800Y-222000D01*
G01Y-226000D02*
X55800D01*
G01X61400D02*
Y-221000D01*
X58317Y-224583D01*
X62483D01*
G01X69100Y-226000D02*
Y-222667D01*
G01Y-223583D02*
X69350Y-223167D01*
X69767Y-222833D01*
X70350Y-222667D01*
X70933Y-222833D01*
X71350Y-223167D01*
X71600Y-223583D01*
Y-226000D01*
G01Y-223583D02*
X71850Y-223167D01*
X72267Y-222833D01*
X72850Y-222667D01*
X73433Y-222833D01*
X73850Y-223167D01*
X74100Y-223667D01*
Y-226000D01*
G01X77200Y-222667D02*
Y-226000D01*
G01Y-221333D02*
X77033Y-221250D01*
Y-221083D01*
X77200Y-221000D01*
X77367Y-221083D01*
Y-221250D01*
X77200Y-221333D01*
G01X82800Y-226000D02*
Y-221000D01*
G01X-186000Y-201500D02*
Y-206500D01*
G01X-187167Y-203167D02*
X-184833D01*
G01X-181567Y-206500D02*
Y-203167D01*
G01Y-203833D02*
X-181150Y-203500D01*
X-180733Y-203250D01*
X-180150Y-203167D01*
X-179733Y-203250D01*
X-179233Y-203500D01*
G01X-173300Y-206500D02*
Y-203167D01*
G01Y-203750D02*
X-173633Y-203417D01*
X-174133Y-203250D01*
X-174717Y-203167D01*
X-175300Y-203333D01*
X-175800Y-203667D01*
X-176133Y-204167D01*
X-176300Y-204833D01*
X-176133Y-205500D01*
X-175800Y-206000D01*
X-175300Y-206333D01*
X-174717Y-206500D01*
X-174133Y-206417D01*
X-173633Y-206167D01*
X-173300Y-205833D01*
G01X-167867Y-203583D02*
X-168450Y-203250D01*
X-168950Y-203167D01*
X-169617Y-203333D01*
X-170117Y-203667D01*
X-170450Y-204250D01*
X-170533Y-204833D01*
X-170450Y-205417D01*
X-170117Y-205917D01*
X-169617Y-206333D01*
X-168950Y-206500D01*
X-168367Y-206333D01*
X-167867Y-206000D01*
G01X-164850Y-204250D02*
X-162183D01*
X-162433Y-203667D01*
X-162850Y-203333D01*
X-163433Y-203167D01*
X-164017Y-203250D01*
X-164517Y-203500D01*
X-164850Y-204083D01*
X-165017Y-204583D01*
Y-205083D01*
X-164850Y-205583D01*
X-164433Y-206083D01*
X-163933Y-206417D01*
X-163350Y-206500D01*
X-162767Y-206333D01*
X-162183Y-205833D01*
G01X-154483Y-203167D02*
X-153483Y-206500D01*
X-152400Y-203167D01*
X-151317Y-206500D01*
X-150317Y-203167D01*
G01X-146800D02*
Y-206500D01*
G01Y-201833D02*
X-146967Y-201750D01*
Y-201583D01*
X-146800Y-201500D01*
X-146633Y-201583D01*
Y-201750D01*
X-146800Y-201833D01*
G01X-139700Y-201500D02*
Y-206500D01*
G01Y-205750D02*
X-140033Y-206167D01*
X-140533Y-206417D01*
X-141117Y-206500D01*
X-141783Y-206333D01*
X-142283Y-205917D01*
X-142617Y-205417D01*
X-142700Y-204833D01*
X-142617Y-204250D01*
X-142283Y-203750D01*
X-141783Y-203333D01*
X-141117Y-203167D01*
X-140533Y-203250D01*
X-140117Y-203417D01*
X-139700Y-203750D01*
G01X-135600Y-201500D02*
Y-206500D01*
G01X-136767Y-203167D02*
X-134433D01*
G01X-131417Y-206500D02*
Y-201500D01*
G01Y-203917D02*
X-131000Y-203500D01*
X-130583Y-203250D01*
X-129917Y-203167D01*
X-129417Y-203250D01*
X-128833Y-203583D01*
X-128583Y-204083D01*
Y-206500D01*
G01X-120467D02*
X-117133Y-204833D01*
X-120467Y-203167D01*
G01X-107767Y-206500D02*
X-107600Y-205417D01*
X-107350Y-204500D01*
X-107017Y-203667D01*
X-106600Y-202750D01*
X-105933Y-201500D01*
X-109267D01*
G01X-98900Y-206500D02*
Y-203167D01*
G01Y-204083D02*
X-98650Y-203667D01*
X-98233Y-203333D01*
X-97650Y-203167D01*
X-97067Y-203333D01*
X-96650Y-203667D01*
X-96400Y-204083D01*
Y-206500D01*
G01Y-204083D02*
X-96150Y-203667D01*
X-95733Y-203333D01*
X-95150Y-203167D01*
X-94567Y-203333D01*
X-94150Y-203667D01*
X-93900Y-204167D01*
Y-206500D01*
G01X-90800Y-203167D02*
Y-206500D01*
G01Y-201833D02*
X-90967Y-201750D01*
Y-201583D01*
X-90800Y-201500D01*
X-90633Y-201583D01*
Y-201750D01*
X-90800Y-201833D01*
G01X-85200Y-206500D02*
Y-201500D01*
G01X-187833Y-190750D02*
X-187333Y-191167D01*
X-186750Y-191417D01*
X-186000Y-191500D01*
X-185250Y-191333D01*
X-184667Y-191000D01*
X-184250Y-190417D01*
X-184167Y-189750D01*
X-184333Y-189083D01*
X-184750Y-188667D01*
X-185333Y-188333D01*
X-185917Y-188250D01*
X-186500Y-188333D01*
X-187250Y-188667D01*
X-187000Y-186500D01*
X-184750D01*
G01X-177300Y-191500D02*
Y-188167D01*
G01Y-189083D02*
X-177050Y-188667D01*
X-176633Y-188333D01*
X-176050Y-188167D01*
X-175467Y-188333D01*
X-175050Y-188667D01*
X-174800Y-189083D01*
Y-191500D01*
G01Y-189083D02*
X-174550Y-188667D01*
X-174133Y-188333D01*
X-173550Y-188167D01*
X-172967Y-188333D01*
X-172550Y-188667D01*
X-172300Y-189167D01*
Y-191500D01*
G01X-169200Y-188167D02*
Y-191500D01*
G01Y-186833D02*
X-169367Y-186750D01*
Y-186583D01*
X-169200Y-186500D01*
X-169033Y-186583D01*
Y-186750D01*
X-169200Y-186833D01*
G01X-163600Y-191500D02*
Y-186500D01*
G01X-150733Y-191500D02*
X-154067Y-189833D01*
X-150733Y-188167D01*
G01X-141200Y-186500D02*
Y-191500D01*
G01X-142367Y-188167D02*
X-140033D01*
G01X-136767Y-191500D02*
Y-188167D01*
G01Y-188833D02*
X-136350Y-188500D01*
X-135933Y-188250D01*
X-135350Y-188167D01*
X-134933Y-188250D01*
X-134433Y-188500D01*
G01X-128500Y-191500D02*
Y-188167D01*
G01Y-188750D02*
X-128833Y-188417D01*
X-129333Y-188250D01*
X-129917Y-188167D01*
X-130500Y-188333D01*
X-131000Y-188667D01*
X-131333Y-189167D01*
X-131500Y-189833D01*
X-131333Y-190500D01*
X-131000Y-191000D01*
X-130500Y-191333D01*
X-129917Y-191500D01*
X-129333Y-191417D01*
X-128833Y-191167D01*
X-128500Y-190833D01*
G01X-123067Y-188583D02*
X-123650Y-188250D01*
X-124150Y-188167D01*
X-124817Y-188333D01*
X-125317Y-188667D01*
X-125650Y-189250D01*
X-125733Y-189833D01*
X-125650Y-190417D01*
X-125317Y-190917D01*
X-124817Y-191333D01*
X-124150Y-191500D01*
X-123567Y-191333D01*
X-123067Y-191000D01*
G01X-120050Y-189250D02*
X-117383D01*
X-117633Y-188667D01*
X-118050Y-188333D01*
X-118633Y-188167D01*
X-119217Y-188250D01*
X-119717Y-188500D01*
X-120050Y-189083D01*
X-120217Y-189583D01*
Y-190083D01*
X-120050Y-190583D01*
X-119633Y-191083D01*
X-119133Y-191417D01*
X-118550Y-191500D01*
X-117967Y-191333D01*
X-117383Y-190833D01*
G01X-109683Y-188167D02*
X-108683Y-191500D01*
X-107600Y-188167D01*
X-106517Y-191500D01*
X-105517Y-188167D01*
G01X-102000D02*
Y-191500D01*
G01Y-186833D02*
X-102167Y-186750D01*
Y-186583D01*
X-102000Y-186500D01*
X-101833Y-186583D01*
Y-186750D01*
X-102000Y-186833D01*
G01X-94900Y-186500D02*
Y-191500D01*
G01Y-190750D02*
X-95233Y-191167D01*
X-95733Y-191417D01*
X-96317Y-191500D01*
X-96983Y-191333D01*
X-97483Y-190917D01*
X-97817Y-190417D01*
X-97900Y-189833D01*
X-97817Y-189250D01*
X-97483Y-188750D01*
X-96983Y-188333D01*
X-96317Y-188167D01*
X-95733Y-188250D01*
X-95317Y-188417D01*
X-94900Y-188750D01*
G01X-90800Y-186500D02*
Y-191500D01*
G01X-91967Y-188167D02*
X-89633D01*
G01X-86617Y-191500D02*
Y-186500D01*
G01Y-188917D02*
X-86200Y-188500D01*
X-85783Y-188250D01*
X-85117Y-188167D01*
X-84617Y-188250D01*
X-84033Y-188583D01*
X-83783Y-189083D01*
Y-191500D01*
G01X-72333D02*
X-75667Y-189833D01*
X-72333Y-188167D01*
G01X-69483Y-190583D02*
X-67317D01*
G01Y-189083D02*
X-69483D01*
G01X-57367Y-191500D02*
X-57200Y-190417D01*
X-56950Y-189500D01*
X-56617Y-188667D01*
X-56200Y-187750D01*
X-55533Y-186500D01*
X-58867D01*
G01X-48500Y-191500D02*
Y-188167D01*
G01Y-189083D02*
X-48250Y-188667D01*
X-47833Y-188333D01*
X-47250Y-188167D01*
X-46667Y-188333D01*
X-46250Y-188667D01*
X-46000Y-189083D01*
Y-191500D01*
G01Y-189083D02*
X-45750Y-188667D01*
X-45333Y-188333D01*
X-44750Y-188167D01*
X-44167Y-188333D01*
X-43750Y-188667D01*
X-43500Y-189167D01*
Y-191500D01*
G01X-40400Y-188167D02*
Y-191500D01*
G01Y-186833D02*
X-40567Y-186750D01*
Y-186583D01*
X-40400Y-186500D01*
X-40233Y-186583D01*
Y-186750D01*
X-40400Y-186833D01*
G01X-34800Y-191500D02*
Y-186500D01*
G01X-186000Y-171500D02*
Y-176500D01*
G01X-187167Y-173167D02*
X-184833D01*
G01X-181567Y-176500D02*
Y-173167D01*
G01Y-173833D02*
X-181150Y-173500D01*
X-180733Y-173250D01*
X-180150Y-173167D01*
X-179733Y-173250D01*
X-179233Y-173500D01*
G01X-173300Y-176500D02*
Y-173167D01*
G01Y-173750D02*
X-173633Y-173417D01*
X-174133Y-173250D01*
X-174717Y-173167D01*
X-175300Y-173333D01*
X-175800Y-173667D01*
X-176133Y-174167D01*
X-176300Y-174833D01*
X-176133Y-175500D01*
X-175800Y-176000D01*
X-175300Y-176333D01*
X-174717Y-176500D01*
X-174133Y-176417D01*
X-173633Y-176167D01*
X-173300Y-175833D01*
G01X-167867Y-173583D02*
X-168450Y-173250D01*
X-168950Y-173167D01*
X-169617Y-173333D01*
X-170117Y-173667D01*
X-170450Y-174250D01*
X-170533Y-174833D01*
X-170450Y-175417D01*
X-170117Y-175917D01*
X-169617Y-176333D01*
X-168950Y-176500D01*
X-168367Y-176333D01*
X-167867Y-176000D01*
G01X-164850Y-174250D02*
X-162183D01*
X-162433Y-173667D01*
X-162850Y-173333D01*
X-163433Y-173167D01*
X-164017Y-173250D01*
X-164517Y-173500D01*
X-164850Y-174083D01*
X-165017Y-174583D01*
Y-175083D01*
X-164850Y-175583D01*
X-164433Y-176083D01*
X-163933Y-176417D01*
X-163350Y-176500D01*
X-162767Y-176333D01*
X-162183Y-175833D01*
G01X-154483Y-173167D02*
X-153483Y-176500D01*
X-152400Y-173167D01*
X-151317Y-176500D01*
X-150317Y-173167D01*
G01X-146800D02*
Y-176500D01*
G01Y-171833D02*
X-146967Y-171750D01*
Y-171583D01*
X-146800Y-171500D01*
X-146633Y-171583D01*
Y-171750D01*
X-146800Y-171833D01*
G01X-139700Y-171500D02*
Y-176500D01*
G01Y-175750D02*
X-140033Y-176167D01*
X-140533Y-176417D01*
X-141117Y-176500D01*
X-141783Y-176333D01*
X-142283Y-175917D01*
X-142617Y-175417D01*
X-142700Y-174833D01*
X-142617Y-174250D01*
X-142283Y-173750D01*
X-141783Y-173333D01*
X-141117Y-173167D01*
X-140533Y-173250D01*
X-140117Y-173417D01*
X-139700Y-173750D01*
G01X-135600Y-171500D02*
Y-176500D01*
G01X-136767Y-173167D02*
X-134433D01*
G01X-131417Y-176500D02*
Y-171500D01*
G01Y-173917D02*
X-131000Y-173500D01*
X-130583Y-173250D01*
X-129917Y-173167D01*
X-129417Y-173250D01*
X-128833Y-173583D01*
X-128583Y-174083D01*
Y-176500D01*
G01X-117133D02*
X-120467Y-174833D01*
X-117133Y-173167D01*
G01X-114283Y-175583D02*
X-112117D01*
G01Y-174083D02*
X-114283D01*
G01X-103833Y-175750D02*
X-103333Y-176167D01*
X-102750Y-176417D01*
X-102000Y-176500D01*
X-101250Y-176333D01*
X-100667Y-176000D01*
X-100250Y-175417D01*
X-100167Y-174750D01*
X-100333Y-174083D01*
X-100750Y-173667D01*
X-101333Y-173333D01*
X-101917Y-173250D01*
X-102500Y-173333D01*
X-103250Y-173667D01*
X-103000Y-171500D01*
X-100750D01*
G01X-93300Y-176500D02*
Y-173167D01*
G01Y-174083D02*
X-93050Y-173667D01*
X-92633Y-173333D01*
X-92050Y-173167D01*
X-91467Y-173333D01*
X-91050Y-173667D01*
X-90800Y-174083D01*
Y-176500D01*
G01Y-174083D02*
X-90550Y-173667D01*
X-90133Y-173333D01*
X-89550Y-173167D01*
X-88967Y-173333D01*
X-88550Y-173667D01*
X-88300Y-174167D01*
Y-176500D01*
G01X-85200Y-173167D02*
Y-176500D01*
G01Y-171833D02*
X-85367Y-171750D01*
Y-171583D01*
X-85200Y-171500D01*
X-85033Y-171583D01*
Y-171750D01*
X-85200Y-171833D01*
G01X-79600Y-176500D02*
Y-171500D01*
G01X-187667Y-163000D02*
Y-158000D01*
X-185583D01*
X-184917Y-158250D01*
X-184500Y-158583D01*
X-184333Y-159250D01*
X-184500Y-159917D01*
X-185000Y-160333D01*
X-185583Y-160583D01*
X-187667D01*
G01X-185583D02*
X-184333Y-163000D01*
G01X-181650Y-160750D02*
X-178983D01*
X-179233Y-160167D01*
X-179650Y-159833D01*
X-180233Y-159667D01*
X-180817Y-159750D01*
X-181317Y-160000D01*
X-181650Y-160583D01*
X-181817Y-161083D01*
Y-161583D01*
X-181650Y-162083D01*
X-181233Y-162583D01*
X-180733Y-162917D01*
X-180150Y-163000D01*
X-179567Y-162833D01*
X-178983Y-162333D01*
G01X-174800Y-163000D02*
Y-158000D01*
G01X-167700Y-163000D02*
Y-159667D01*
G01Y-160250D02*
X-168033Y-159917D01*
X-168533Y-159750D01*
X-169117Y-159667D01*
X-169700Y-159833D01*
X-170200Y-160167D01*
X-170533Y-160667D01*
X-170700Y-161333D01*
X-170533Y-162000D01*
X-170200Y-162500D01*
X-169700Y-162833D01*
X-169117Y-163000D01*
X-168533Y-162917D01*
X-168033Y-162667D01*
X-167700Y-162333D01*
G01X-163600Y-158000D02*
Y-163000D01*
G01X-164767Y-159667D02*
X-162433D01*
G01X-158000D02*
Y-163000D01*
G01Y-158333D02*
X-158167Y-158250D01*
Y-158083D01*
X-158000Y-158000D01*
X-157833Y-158083D01*
Y-158250D01*
X-158000Y-158333D01*
G01X-153900Y-159667D02*
X-152400Y-163000D01*
X-150900Y-159667D01*
G01X-148050Y-160750D02*
X-145383D01*
X-145633Y-160167D01*
X-146050Y-159833D01*
X-146633Y-159667D01*
X-147217Y-159750D01*
X-147717Y-160000D01*
X-148050Y-160583D01*
X-148217Y-161083D01*
Y-161583D01*
X-148050Y-162083D01*
X-147633Y-162583D01*
X-147133Y-162917D01*
X-146550Y-163000D01*
X-145967Y-162833D01*
X-145383Y-162333D01*
G01X-137100Y-164667D02*
Y-159667D01*
G01Y-160417D02*
X-136683Y-160000D01*
X-136267Y-159750D01*
X-135600Y-159667D01*
X-135017Y-159750D01*
X-134433Y-160167D01*
X-134183Y-160750D01*
X-134100Y-161333D01*
X-134183Y-161917D01*
X-134433Y-162500D01*
X-134933Y-162833D01*
X-135600Y-163000D01*
X-136183Y-162917D01*
X-136767Y-162667D01*
X-137100Y-162333D01*
G01X-130000Y-163000D02*
X-130500Y-162917D01*
X-131000Y-162583D01*
X-131333Y-162000D01*
X-131500Y-161333D01*
X-131333Y-160667D01*
X-131000Y-160083D01*
X-130500Y-159750D01*
X-130000Y-159667D01*
X-129500Y-159750D01*
X-129000Y-160083D01*
X-128667Y-160667D01*
X-128583Y-161333D01*
X-128667Y-162000D01*
X-129000Y-162583D01*
X-129500Y-162917D01*
X-130000Y-163000D01*
G01X-125650Y-162417D02*
X-125233Y-162750D01*
X-124650Y-163000D01*
X-124150D01*
X-123650Y-162833D01*
X-123317Y-162583D01*
X-123150Y-162250D01*
X-123233Y-161750D01*
X-123567Y-161500D01*
X-125067Y-161000D01*
X-125400Y-160417D01*
X-125233Y-160000D01*
X-124900Y-159750D01*
X-124400Y-159667D01*
X-123900Y-159750D01*
X-123400Y-160000D01*
G01X-118800Y-159667D02*
Y-163000D01*
G01Y-158333D02*
X-118967Y-158250D01*
Y-158083D01*
X-118800Y-158000D01*
X-118633Y-158083D01*
Y-158250D01*
X-118800Y-158333D01*
G01X-113200Y-158000D02*
Y-163000D01*
G01X-114367Y-159667D02*
X-112033D01*
G01X-107600D02*
Y-163000D01*
G01Y-158333D02*
X-107767Y-158250D01*
Y-158083D01*
X-107600Y-158000D01*
X-107433Y-158083D01*
Y-158250D01*
X-107600Y-158333D01*
G01X-102000Y-163000D02*
X-102500Y-162917D01*
X-103000Y-162583D01*
X-103333Y-162000D01*
X-103500Y-161333D01*
X-103333Y-160667D01*
X-103000Y-160083D01*
X-102500Y-159750D01*
X-102000Y-159667D01*
X-101500Y-159750D01*
X-101000Y-160083D01*
X-100667Y-160667D01*
X-100583Y-161333D01*
X-100667Y-162000D01*
X-101000Y-162583D01*
X-101500Y-162917D01*
X-102000Y-163000D01*
G01X-97817D02*
Y-159667D01*
G01Y-160500D02*
X-97483Y-160083D01*
X-96983Y-159750D01*
X-96317Y-159667D01*
X-95733Y-159750D01*
X-95233Y-160083D01*
X-94983Y-160667D01*
Y-163000D01*
G01X-86700D02*
Y-158000D01*
G01Y-160500D02*
X-86283Y-160000D01*
X-85783Y-159750D01*
X-85283Y-159667D01*
X-84533Y-159833D01*
X-84033Y-160167D01*
X-83700Y-160750D01*
Y-161417D01*
X-83867Y-162083D01*
X-84200Y-162583D01*
X-84783Y-162917D01*
X-85283Y-163000D01*
X-85783Y-162917D01*
X-86283Y-162667D01*
X-86700Y-162250D01*
G01X-80850Y-160750D02*
X-78183D01*
X-78433Y-160167D01*
X-78850Y-159833D01*
X-79433Y-159667D01*
X-80017Y-159750D01*
X-80517Y-160000D01*
X-80850Y-160583D01*
X-81017Y-161083D01*
Y-161583D01*
X-80850Y-162083D01*
X-80433Y-162583D01*
X-79933Y-162917D01*
X-79350Y-163000D01*
X-78767Y-162833D01*
X-78183Y-162333D01*
G01X-74000Y-158000D02*
Y-163000D01*
G01X-75167Y-159667D02*
X-72833D01*
G01X-70483D02*
X-69483Y-163000D01*
X-68400Y-159667D01*
X-67317Y-163000D01*
X-66317Y-159667D01*
G01X-64050Y-160750D02*
X-61383D01*
X-61633Y-160167D01*
X-62050Y-159833D01*
X-62633Y-159667D01*
X-63217Y-159750D01*
X-63717Y-160000D01*
X-64050Y-160583D01*
X-64217Y-161083D01*
Y-161583D01*
X-64050Y-162083D01*
X-63633Y-162583D01*
X-63133Y-162917D01*
X-62550Y-163000D01*
X-61967Y-162833D01*
X-61383Y-162333D01*
G01X-58450Y-160750D02*
X-55783D01*
X-56033Y-160167D01*
X-56450Y-159833D01*
X-57033Y-159667D01*
X-57617Y-159750D01*
X-58117Y-160000D01*
X-58450Y-160583D01*
X-58617Y-161083D01*
Y-161583D01*
X-58450Y-162083D01*
X-58033Y-162583D01*
X-57533Y-162917D01*
X-56950Y-163000D01*
X-56367Y-162833D01*
X-55783Y-162333D01*
G01X-53017Y-163000D02*
Y-159667D01*
G01Y-160500D02*
X-52683Y-160083D01*
X-52183Y-159750D01*
X-51517Y-159667D01*
X-50933Y-159750D01*
X-50433Y-160083D01*
X-50183Y-160667D01*
Y-163000D01*
G01X-38900D02*
Y-159667D01*
G01Y-160250D02*
X-39233Y-159917D01*
X-39733Y-159750D01*
X-40317Y-159667D01*
X-40900Y-159833D01*
X-41400Y-160167D01*
X-41733Y-160667D01*
X-41900Y-161333D01*
X-41733Y-162000D01*
X-41400Y-162500D01*
X-40900Y-162833D01*
X-40317Y-163000D01*
X-39733Y-162917D01*
X-39233Y-162667D01*
X-38900Y-162333D01*
G01X-36217Y-163000D02*
Y-159667D01*
G01Y-160500D02*
X-35883Y-160083D01*
X-35383Y-159750D01*
X-34717Y-159667D01*
X-34133Y-159750D01*
X-33633Y-160083D01*
X-33383Y-160667D01*
Y-163000D01*
G01X-30950Y-164500D02*
X-30450Y-164667D01*
X-29783Y-164500D01*
X-29367Y-164167D01*
X-29033Y-163750D01*
X-28533Y-162417D01*
X-27450Y-159667D01*
G01X-30117D02*
X-28533Y-162417D01*
G01X-19500Y-164667D02*
Y-159667D01*
G01Y-160417D02*
X-19083Y-160000D01*
X-18667Y-159750D01*
X-18000Y-159667D01*
X-17417Y-159750D01*
X-16833Y-160167D01*
X-16583Y-160750D01*
X-16500Y-161333D01*
X-16583Y-161917D01*
X-16833Y-162500D01*
X-17333Y-162833D01*
X-18000Y-163000D01*
X-18583Y-162917D01*
X-19167Y-162667D01*
X-19500Y-162333D01*
G01X-10900Y-163000D02*
Y-159667D01*
G01Y-160250D02*
X-11233Y-159917D01*
X-11733Y-159750D01*
X-12317Y-159667D01*
X-12900Y-159833D01*
X-13400Y-160167D01*
X-13733Y-160667D01*
X-13900Y-161333D01*
X-13733Y-162000D01*
X-13400Y-162500D01*
X-12900Y-162833D01*
X-12317Y-163000D01*
X-11733Y-162917D01*
X-11233Y-162667D01*
X-10900Y-162333D01*
G01X-5300Y-158000D02*
Y-163000D01*
G01Y-162250D02*
X-5633Y-162667D01*
X-6133Y-162917D01*
X-6717Y-163000D01*
X-7383Y-162833D01*
X-7883Y-162417D01*
X-8217Y-161917D01*
X-8300Y-161333D01*
X-8217Y-160750D01*
X-7883Y-160250D01*
X-7383Y-159833D01*
X-6717Y-159667D01*
X-6133Y-159750D01*
X-5717Y-159917D01*
X-5300Y-160250D01*
G01X4400Y-158000D02*
Y-163000D01*
G01X3233Y-159667D02*
X5567D01*
G01X10000Y-163000D02*
X9500Y-162917D01*
X9000Y-162583D01*
X8667Y-162000D01*
X8500Y-161333D01*
X8667Y-160667D01*
X9000Y-160083D01*
X9500Y-159750D01*
X10000Y-159667D01*
X10500Y-159750D01*
X11000Y-160083D01*
X11333Y-160667D01*
X11417Y-161333D01*
X11333Y-162000D01*
X11000Y-162583D01*
X10500Y-162917D01*
X10000Y-163000D01*
G01X19700Y-164667D02*
Y-159667D01*
G01Y-160417D02*
X20117Y-160000D01*
X20533Y-159750D01*
X21200Y-159667D01*
X21783Y-159750D01*
X22367Y-160167D01*
X22617Y-160750D01*
X22700Y-161333D01*
X22617Y-161917D01*
X22367Y-162500D01*
X21867Y-162833D01*
X21200Y-163000D01*
X20617Y-162917D01*
X20033Y-162667D01*
X19700Y-162333D01*
G01X28300Y-163000D02*
Y-159667D01*
G01Y-160250D02*
X27967Y-159917D01*
X27467Y-159750D01*
X26883Y-159667D01*
X26300Y-159833D01*
X25800Y-160167D01*
X25467Y-160667D01*
X25300Y-161333D01*
X25467Y-162000D01*
X25800Y-162500D01*
X26300Y-162833D01*
X26883Y-163000D01*
X27467Y-162917D01*
X27967Y-162667D01*
X28300Y-162333D01*
G01X33900Y-158000D02*
Y-163000D01*
G01Y-162250D02*
X33567Y-162667D01*
X33067Y-162917D01*
X32483Y-163000D01*
X31817Y-162833D01*
X31317Y-162417D01*
X30983Y-161917D01*
X30900Y-161333D01*
X30983Y-160750D01*
X31317Y-160250D01*
X31817Y-159833D01*
X32483Y-159667D01*
X33067Y-159750D01*
X33483Y-159917D01*
X33900Y-160250D01*
G01X-187750Y-148000D02*
Y-143000D01*
G01X-184250D02*
Y-148000D01*
G01Y-145500D02*
X-187750D01*
G01X-182233Y-148000D02*
Y-143000D01*
X-180567D01*
X-179900Y-143250D01*
X-179400Y-143583D01*
X-178983Y-144083D01*
X-178650Y-144667D01*
X-178567Y-145500D01*
X-178650Y-146333D01*
X-178983Y-146917D01*
X-179400Y-147417D01*
X-179900Y-147750D01*
X-180567Y-148000D01*
X-182233D01*
G01X-175800Y-143000D02*
X-173800D01*
G01X-174800D02*
Y-148000D01*
G01X-175800D02*
X-173800D01*
G01X-165267D02*
Y-143000D01*
X-163267D01*
X-162600Y-143250D01*
X-162100Y-143833D01*
X-161933Y-144500D01*
X-162100Y-145167D01*
X-162517Y-145667D01*
X-163267Y-145917D01*
X-165267D01*
G01X-156167Y-143417D02*
X-156667Y-143167D01*
X-157250Y-143000D01*
X-157917D01*
X-158667Y-143250D01*
X-159250Y-143667D01*
X-159667Y-144167D01*
X-160000Y-145000D01*
X-160083Y-145750D01*
X-159917Y-146500D01*
X-159667Y-147000D01*
X-159167Y-147500D01*
X-158583Y-147833D01*
X-158000Y-148000D01*
X-157417D01*
X-156833Y-147833D01*
X-156333Y-147583D01*
X-155917Y-147250D01*
G01X-151733Y-145333D02*
X-151400Y-145083D01*
X-151150Y-144667D01*
X-150983Y-144083D01*
X-151150Y-143583D01*
X-151483Y-143250D01*
X-152067Y-143000D01*
X-154317D01*
Y-148000D01*
X-151567D01*
X-150983Y-147667D01*
X-150650Y-147167D01*
X-150483Y-146583D01*
X-150650Y-146000D01*
X-151150Y-145500D01*
X-151733Y-145333D01*
X-154317D01*
G01X-146800Y-148167D02*
X-146967Y-148083D01*
Y-147917D01*
X-146800Y-147833D01*
X-146633Y-147917D01*
Y-148083D01*
X-146800Y-148167D01*
G01X-187250Y-131417D02*
X-186833Y-131750D01*
X-186250Y-132000D01*
X-185750D01*
X-185250Y-131833D01*
X-184917Y-131583D01*
X-184750Y-131250D01*
X-184833Y-130750D01*
X-185167Y-130500D01*
X-186667Y-130000D01*
X-187000Y-129417D01*
X-186833Y-129000D01*
X-186500Y-128750D01*
X-186000Y-128667D01*
X-185500Y-128750D01*
X-185000Y-129000D01*
G01X-181900Y-133667D02*
Y-128667D01*
G01Y-129417D02*
X-181483Y-129000D01*
X-181067Y-128750D01*
X-180400Y-128667D01*
X-179817Y-128750D01*
X-179233Y-129167D01*
X-178983Y-129750D01*
X-178900Y-130333D01*
X-178983Y-130917D01*
X-179233Y-131500D01*
X-179733Y-131833D01*
X-180400Y-132000D01*
X-180983Y-131917D01*
X-181567Y-131667D01*
X-181900Y-131333D01*
G01X-176050Y-129750D02*
X-173383D01*
X-173633Y-129167D01*
X-174050Y-128833D01*
X-174633Y-128667D01*
X-175217Y-128750D01*
X-175717Y-129000D01*
X-176050Y-129583D01*
X-176217Y-130083D01*
Y-130583D01*
X-176050Y-131083D01*
X-175633Y-131583D01*
X-175133Y-131917D01*
X-174550Y-132000D01*
X-173967Y-131833D01*
X-173383Y-131333D01*
G01X-167867Y-129083D02*
X-168450Y-128750D01*
X-168950Y-128667D01*
X-169617Y-128833D01*
X-170117Y-129167D01*
X-170450Y-129750D01*
X-170533Y-130333D01*
X-170450Y-130917D01*
X-170117Y-131417D01*
X-169617Y-131833D01*
X-168950Y-132000D01*
X-168367Y-131833D01*
X-167867Y-131500D01*
G01X-163600Y-128667D02*
Y-132000D01*
G01Y-127333D02*
X-163767Y-127250D01*
Y-127083D01*
X-163600Y-127000D01*
X-163433Y-127083D01*
Y-127250D01*
X-163600Y-127333D01*
G01X-158500Y-132000D02*
Y-127750D01*
X-158333Y-127333D01*
X-158000Y-127083D01*
X-157500Y-127000D01*
X-157000Y-127167D01*
X-156750Y-127583D01*
G01X-157750Y-129000D02*
X-159417D01*
G01X-152400Y-128667D02*
Y-132000D01*
G01Y-127333D02*
X-152567Y-127250D01*
Y-127083D01*
X-152400Y-127000D01*
X-152233Y-127083D01*
Y-127250D01*
X-152400Y-127333D01*
G01X-145467Y-129083D02*
X-146050Y-128750D01*
X-146550Y-128667D01*
X-147217Y-128833D01*
X-147717Y-129167D01*
X-148050Y-129750D01*
X-148133Y-130333D01*
X-148050Y-130917D01*
X-147717Y-131417D01*
X-147217Y-131833D01*
X-146550Y-132000D01*
X-145967Y-131833D01*
X-145467Y-131500D01*
G01X-139700Y-132000D02*
Y-128667D01*
G01Y-129250D02*
X-140033Y-128917D01*
X-140533Y-128750D01*
X-141117Y-128667D01*
X-141700Y-128833D01*
X-142200Y-129167D01*
X-142533Y-129667D01*
X-142700Y-130333D01*
X-142533Y-131000D01*
X-142200Y-131500D01*
X-141700Y-131833D01*
X-141117Y-132000D01*
X-140533Y-131917D01*
X-140033Y-131667D01*
X-139700Y-131333D01*
G01X-135600Y-127000D02*
Y-132000D01*
G01X-136767Y-128667D02*
X-134433D01*
G01X-130000D02*
Y-132000D01*
G01Y-127333D02*
X-130167Y-127250D01*
Y-127083D01*
X-130000Y-127000D01*
X-129833Y-127083D01*
Y-127250D01*
X-130000Y-127333D01*
G01X-124400Y-132000D02*
X-124900Y-131917D01*
X-125400Y-131583D01*
X-125733Y-131000D01*
X-125900Y-130333D01*
X-125733Y-129667D01*
X-125400Y-129083D01*
X-124900Y-128750D01*
X-124400Y-128667D01*
X-123900Y-128750D01*
X-123400Y-129083D01*
X-123067Y-129667D01*
X-122983Y-130333D01*
X-123067Y-131000D01*
X-123400Y-131583D01*
X-123900Y-131917D01*
X-124400Y-132000D01*
G01X-120217D02*
Y-128667D01*
G01Y-129500D02*
X-119883Y-129083D01*
X-119383Y-128750D01*
X-118717Y-128667D01*
X-118133Y-128750D01*
X-117633Y-129083D01*
X-117383Y-129667D01*
Y-132000D01*
G01X-113200Y-132167D02*
X-113367Y-132083D01*
Y-131917D01*
X-113200Y-131833D01*
X-113033Y-131917D01*
Y-132083D01*
X-113200Y-132167D01*
G01X-187750Y-122333D02*
X-187083Y-122750D01*
X-186333Y-123000D01*
X-185667D01*
X-185000Y-122750D01*
X-184500Y-122333D01*
X-184250Y-121750D01*
X-184417Y-121167D01*
X-184833Y-120667D01*
X-185583Y-120333D01*
X-186583Y-120167D01*
X-187167Y-119833D01*
X-187417Y-119250D01*
X-187250Y-118667D01*
X-186833Y-118250D01*
X-186250Y-118000D01*
X-185667D01*
X-185083Y-118167D01*
X-184583Y-118583D01*
G01X-181650Y-120750D02*
X-178983D01*
X-179233Y-120167D01*
X-179650Y-119833D01*
X-180233Y-119667D01*
X-180817Y-119750D01*
X-181317Y-120000D01*
X-181650Y-120583D01*
X-181817Y-121083D01*
Y-121583D01*
X-181650Y-122083D01*
X-181233Y-122583D01*
X-180733Y-122917D01*
X-180150Y-123000D01*
X-179567Y-122833D01*
X-178983Y-122333D01*
G01X-175967Y-123000D02*
Y-119667D01*
G01Y-120333D02*
X-175550Y-120000D01*
X-175133Y-119750D01*
X-174550Y-119667D01*
X-174133Y-119750D01*
X-173633Y-120000D01*
G01X-170700Y-119667D02*
X-169200Y-123000D01*
X-167700Y-119667D01*
G01X-164850Y-120750D02*
X-162183D01*
X-162433Y-120167D01*
X-162850Y-119833D01*
X-163433Y-119667D01*
X-164017Y-119750D01*
X-164517Y-120000D01*
X-164850Y-120583D01*
X-165017Y-121083D01*
Y-121583D01*
X-164850Y-122083D01*
X-164433Y-122583D01*
X-163933Y-122917D01*
X-163350Y-123000D01*
X-162767Y-122833D01*
X-162183Y-122333D01*
G01X-159167Y-123000D02*
Y-119667D01*
G01Y-120333D02*
X-158750Y-120000D01*
X-158333Y-119750D01*
X-157750Y-119667D01*
X-157333Y-119750D01*
X-156833Y-120000D01*
G01X-148467Y-123000D02*
Y-118000D01*
X-146467D01*
X-145800Y-118250D01*
X-145300Y-118833D01*
X-145133Y-119500D01*
X-145300Y-120167D01*
X-145717Y-120667D01*
X-146467Y-120917D01*
X-148467D01*
G01X-139367Y-118417D02*
X-139867Y-118167D01*
X-140450Y-118000D01*
X-141117D01*
X-141867Y-118250D01*
X-142450Y-118667D01*
X-142867Y-119167D01*
X-143200Y-120000D01*
X-143283Y-120750D01*
X-143117Y-121500D01*
X-142867Y-122000D01*
X-142367Y-122500D01*
X-141783Y-122833D01*
X-141200Y-123000D01*
X-140617D01*
X-140033Y-122833D01*
X-139533Y-122583D01*
X-139117Y-122250D01*
G01X-134933Y-120333D02*
X-134600Y-120083D01*
X-134350Y-119667D01*
X-134183Y-119083D01*
X-134350Y-118583D01*
X-134683Y-118250D01*
X-135267Y-118000D01*
X-137517D01*
Y-123000D01*
X-134767D01*
X-134183Y-122667D01*
X-133850Y-122167D01*
X-133683Y-121583D01*
X-133850Y-121000D01*
X-134350Y-120500D01*
X-134933Y-120333D01*
X-137517D01*
G01X-130000Y-123167D02*
X-130167Y-123083D01*
Y-122917D01*
X-130000Y-122833D01*
X-129833Y-122917D01*
Y-123083D01*
X-130000Y-123167D01*
G01Y-120917D02*
X-130167Y-120833D01*
Y-120667D01*
X-130000Y-120583D01*
X-129833Y-120667D01*
Y-120833D01*
X-130000Y-120917D01*
G01X-125983Y-123000D02*
Y-118000D01*
X-122817D01*
G01X-123983Y-120417D02*
X-125983D01*
G01X-118800Y-123000D02*
X-119300Y-122917D01*
X-119800Y-122583D01*
X-120133Y-122000D01*
X-120300Y-121333D01*
X-120133Y-120667D01*
X-119800Y-120083D01*
X-119300Y-119750D01*
X-118800Y-119667D01*
X-118300Y-119750D01*
X-117800Y-120083D01*
X-117467Y-120667D01*
X-117383Y-121333D01*
X-117467Y-122000D01*
X-117800Y-122583D01*
X-118300Y-122917D01*
X-118800Y-123000D01*
G01X-113200D02*
Y-118000D01*
G01X-107600Y-123000D02*
Y-118000D01*
G01X-102000Y-123000D02*
X-102500Y-122917D01*
X-103000Y-122583D01*
X-103333Y-122000D01*
X-103500Y-121333D01*
X-103333Y-120667D01*
X-103000Y-120083D01*
X-102500Y-119750D01*
X-102000Y-119667D01*
X-101500Y-119750D01*
X-101000Y-120083D01*
X-100667Y-120667D01*
X-100583Y-121333D01*
X-100667Y-122000D01*
X-101000Y-122583D01*
X-101500Y-122917D01*
X-102000Y-123000D01*
G01X-98483Y-119667D02*
X-97483Y-123000D01*
X-96400Y-119667D01*
X-95317Y-123000D01*
X-94317Y-119667D01*
G01X-86367Y-123000D02*
Y-119667D01*
G01Y-120333D02*
X-85950Y-120000D01*
X-85533Y-119750D01*
X-84950Y-119667D01*
X-84533Y-119750D01*
X-84033Y-120000D01*
G01X-79600Y-119667D02*
Y-123000D01*
G01Y-118333D02*
X-79767Y-118250D01*
Y-118083D01*
X-79600Y-118000D01*
X-79433Y-118083D01*
Y-118250D01*
X-79600Y-118333D01*
G01X-75167Y-124250D02*
X-74583Y-124583D01*
X-73917Y-124667D01*
X-73333Y-124583D01*
X-72833Y-124167D01*
X-72500Y-123583D01*
Y-119667D01*
G01Y-120333D02*
X-72833Y-120000D01*
X-73333Y-119750D01*
X-73917Y-119667D01*
X-74583Y-119833D01*
X-75000Y-120167D01*
X-75333Y-120750D01*
X-75500Y-121333D01*
X-75417Y-121833D01*
X-75083Y-122417D01*
X-74583Y-122833D01*
X-73917Y-123000D01*
X-73417Y-122917D01*
X-72833Y-122583D01*
X-72500Y-122250D01*
G01X-69817Y-123000D02*
Y-118000D01*
G01Y-120417D02*
X-69400Y-120000D01*
X-68983Y-119750D01*
X-68317Y-119667D01*
X-67817Y-119750D01*
X-67233Y-120083D01*
X-66983Y-120583D01*
Y-123000D01*
G01X-62800Y-118000D02*
Y-123000D01*
G01X-63967Y-119667D02*
X-61633D01*
G01X-52850Y-122417D02*
X-52433Y-122750D01*
X-51850Y-123000D01*
X-51350D01*
X-50850Y-122833D01*
X-50517Y-122583D01*
X-50350Y-122250D01*
X-50433Y-121750D01*
X-50767Y-121500D01*
X-52267Y-121000D01*
X-52600Y-120417D01*
X-52433Y-120000D01*
X-52100Y-119750D01*
X-51600Y-119667D01*
X-51100Y-119750D01*
X-50600Y-120000D01*
G01X-46000Y-119667D02*
Y-123000D01*
G01Y-118333D02*
X-46167Y-118250D01*
Y-118083D01*
X-46000Y-118000D01*
X-45833Y-118083D01*
Y-118250D01*
X-46000Y-118333D01*
G01X-38900Y-118000D02*
Y-123000D01*
G01Y-122250D02*
X-39233Y-122667D01*
X-39733Y-122917D01*
X-40317Y-123000D01*
X-40983Y-122833D01*
X-41483Y-122417D01*
X-41817Y-121917D01*
X-41900Y-121333D01*
X-41817Y-120750D01*
X-41483Y-120250D01*
X-40983Y-119833D01*
X-40317Y-119667D01*
X-39733Y-119750D01*
X-39317Y-119917D01*
X-38900Y-120250D01*
G01X-36050Y-120750D02*
X-33383D01*
X-33633Y-120167D01*
X-34050Y-119833D01*
X-34633Y-119667D01*
X-35217Y-119750D01*
X-35717Y-120000D01*
X-36050Y-120583D01*
X-36217Y-121083D01*
Y-121583D01*
X-36050Y-122083D01*
X-35633Y-122583D01*
X-35133Y-122917D01*
X-34550Y-123000D01*
X-33967Y-122833D01*
X-33383Y-122333D01*
G01X-24850Y-122417D02*
X-24433Y-122750D01*
X-23850Y-123000D01*
X-23350D01*
X-22850Y-122833D01*
X-22517Y-122583D01*
X-22350Y-122250D01*
X-22433Y-121750D01*
X-22767Y-121500D01*
X-24267Y-121000D01*
X-24600Y-120417D01*
X-24433Y-120000D01*
X-24100Y-119750D01*
X-23600Y-119667D01*
X-23100Y-119750D01*
X-22600Y-120000D01*
G01X-19500Y-124667D02*
Y-119667D01*
G01Y-120417D02*
X-19083Y-120000D01*
X-18667Y-119750D01*
X-18000Y-119667D01*
X-17417Y-119750D01*
X-16833Y-120167D01*
X-16583Y-120750D01*
X-16500Y-121333D01*
X-16583Y-121917D01*
X-16833Y-122500D01*
X-17333Y-122833D01*
X-18000Y-123000D01*
X-18583Y-122917D01*
X-19167Y-122667D01*
X-19500Y-122333D01*
G01X-13650Y-120750D02*
X-10983D01*
X-11233Y-120167D01*
X-11650Y-119833D01*
X-12233Y-119667D01*
X-12817Y-119750D01*
X-13317Y-120000D01*
X-13650Y-120583D01*
X-13817Y-121083D01*
Y-121583D01*
X-13650Y-122083D01*
X-13233Y-122583D01*
X-12733Y-122917D01*
X-12150Y-123000D01*
X-11567Y-122833D01*
X-10983Y-122333D01*
G01X-5467Y-120083D02*
X-6050Y-119750D01*
X-6550Y-119667D01*
X-7217Y-119833D01*
X-7717Y-120167D01*
X-8050Y-120750D01*
X-8133Y-121333D01*
X-8050Y-121917D01*
X-7717Y-122417D01*
X-7217Y-122833D01*
X-6550Y-123000D01*
X-5967Y-122833D01*
X-5467Y-122500D01*
G01X4233Y-123917D02*
X4567Y-122833D01*
G01X10000Y-119667D02*
Y-123000D01*
G01Y-118333D02*
X9833Y-118250D01*
Y-118083D01*
X10000Y-118000D01*
X10167Y-118083D01*
Y-118250D01*
X10000Y-118333D01*
G01X15100Y-123000D02*
Y-118750D01*
X15267Y-118333D01*
X15600Y-118083D01*
X16100Y-118000D01*
X16600Y-118167D01*
X16850Y-118583D01*
G01X15850Y-120000D02*
X14183D01*
G01X25550Y-122417D02*
X25967Y-122750D01*
X26550Y-123000D01*
X27050D01*
X27550Y-122833D01*
X27883Y-122583D01*
X28050Y-122250D01*
X27967Y-121750D01*
X27633Y-121500D01*
X26133Y-121000D01*
X25800Y-120417D01*
X25967Y-120000D01*
X26300Y-119750D01*
X26800Y-119667D01*
X27300Y-119750D01*
X27800Y-120000D01*
G01X32400Y-118000D02*
Y-123000D01*
G01X31233Y-119667D02*
X33567D01*
G01X39500Y-123000D02*
Y-119667D01*
G01Y-120250D02*
X39167Y-119917D01*
X38667Y-119750D01*
X38083Y-119667D01*
X37500Y-119833D01*
X37000Y-120167D01*
X36667Y-120667D01*
X36500Y-121333D01*
X36667Y-122000D01*
X37000Y-122500D01*
X37500Y-122833D01*
X38083Y-123000D01*
X38667Y-122917D01*
X39167Y-122667D01*
X39500Y-122333D01*
G01X44933Y-120083D02*
X44350Y-119750D01*
X43850Y-119667D01*
X43183Y-119833D01*
X42683Y-120167D01*
X42350Y-120750D01*
X42267Y-121333D01*
X42350Y-121917D01*
X42683Y-122417D01*
X43183Y-122833D01*
X43850Y-123000D01*
X44433Y-122833D01*
X44933Y-122500D01*
G01X47783Y-123000D02*
Y-118000D01*
G01X50450Y-119667D02*
X47783Y-121583D01*
G01X48867Y-120833D02*
X50617Y-123000D01*
G01X58983Y-119667D02*
Y-122000D01*
X59317Y-122583D01*
X59817Y-122917D01*
X60400Y-123000D01*
X60983Y-122917D01*
X61483Y-122583D01*
X61817Y-122000D01*
G01Y-123000D02*
Y-119667D01*
G01X64500Y-124667D02*
Y-119667D01*
G01Y-120417D02*
X64917Y-120000D01*
X65333Y-119750D01*
X66000Y-119667D01*
X66583Y-119750D01*
X67167Y-120167D01*
X67417Y-120750D01*
X67500Y-121333D01*
X67417Y-121917D01*
X67167Y-122500D01*
X66667Y-122833D01*
X66000Y-123000D01*
X65417Y-122917D01*
X64833Y-122667D01*
X64500Y-122333D01*
G01X75117Y-119667D02*
X76117Y-123000D01*
X77200Y-119667D01*
X78283Y-123000D01*
X79283Y-119667D01*
G01X82800D02*
Y-123000D01*
G01Y-118333D02*
X82633Y-118250D01*
Y-118083D01*
X82800Y-118000D01*
X82967Y-118083D01*
Y-118250D01*
X82800Y-118333D01*
G01X88400Y-118000D02*
Y-123000D01*
G01X87233Y-119667D02*
X89567D01*
G01X92583Y-123000D02*
Y-118000D01*
G01Y-120417D02*
X93000Y-120000D01*
X93417Y-119750D01*
X94083Y-119667D01*
X94583Y-119750D01*
X95167Y-120083D01*
X95417Y-120583D01*
Y-123000D01*
G01X99600D02*
X99100Y-122917D01*
X98600Y-122583D01*
X98267Y-122000D01*
X98100Y-121333D01*
X98267Y-120667D01*
X98600Y-120083D01*
X99100Y-119750D01*
X99600Y-119667D01*
X100100Y-119750D01*
X100600Y-120083D01*
X100933Y-120667D01*
X101017Y-121333D01*
X100933Y-122000D01*
X100600Y-122583D01*
X100100Y-122917D01*
X99600Y-123000D01*
G01X103783Y-119667D02*
Y-122000D01*
X104117Y-122583D01*
X104617Y-122917D01*
X105200Y-123000D01*
X105783Y-122917D01*
X106283Y-122583D01*
X106617Y-122000D01*
G01Y-123000D02*
Y-119667D01*
G01X110800Y-118000D02*
Y-123000D01*
G01X109633Y-119667D02*
X111967D01*
G01X-186000Y-103000D02*
Y-108000D01*
G01X-187917Y-103000D02*
X-184083D01*
G01X-181567Y-108000D02*
Y-104667D01*
G01Y-105333D02*
X-181150Y-105000D01*
X-180733Y-104750D01*
X-180150Y-104667D01*
X-179733Y-104750D01*
X-179233Y-105000D01*
G01X-173300Y-108000D02*
Y-104667D01*
G01Y-105250D02*
X-173633Y-104917D01*
X-174133Y-104750D01*
X-174717Y-104667D01*
X-175300Y-104833D01*
X-175800Y-105167D01*
X-176133Y-105667D01*
X-176300Y-106333D01*
X-176133Y-107000D01*
X-175800Y-107500D01*
X-175300Y-107833D01*
X-174717Y-108000D01*
X-174133Y-107917D01*
X-173633Y-107667D01*
X-173300Y-107333D01*
G01X-167700Y-103000D02*
Y-108000D01*
G01Y-107250D02*
X-168033Y-107667D01*
X-168533Y-107917D01*
X-169117Y-108000D01*
X-169783Y-107833D01*
X-170283Y-107417D01*
X-170617Y-106917D01*
X-170700Y-106333D01*
X-170617Y-105750D01*
X-170283Y-105250D01*
X-169783Y-104833D01*
X-169117Y-104667D01*
X-168533Y-104750D01*
X-168117Y-104917D01*
X-167700Y-105250D01*
G01X-163600Y-104667D02*
Y-108000D01*
G01Y-103333D02*
X-163767Y-103250D01*
Y-103083D01*
X-163600Y-103000D01*
X-163433Y-103083D01*
Y-103250D01*
X-163600Y-103333D01*
G01X-158000Y-103000D02*
Y-108000D01*
G01X-159167Y-104667D02*
X-156833D01*
G01X-152400D02*
Y-108000D01*
G01Y-103333D02*
X-152567Y-103250D01*
Y-103083D01*
X-152400Y-103000D01*
X-152233Y-103083D01*
Y-103250D01*
X-152400Y-103333D01*
G01X-146800Y-108000D02*
X-147300Y-107917D01*
X-147800Y-107583D01*
X-148133Y-107000D01*
X-148300Y-106333D01*
X-148133Y-105667D01*
X-147800Y-105083D01*
X-147300Y-104750D01*
X-146800Y-104667D01*
X-146300Y-104750D01*
X-145800Y-105083D01*
X-145467Y-105667D01*
X-145383Y-106333D01*
X-145467Y-107000D01*
X-145800Y-107583D01*
X-146300Y-107917D01*
X-146800Y-108000D01*
G01X-142617D02*
Y-104667D01*
G01Y-105500D02*
X-142283Y-105083D01*
X-141783Y-104750D01*
X-141117Y-104667D01*
X-140533Y-104750D01*
X-140033Y-105083D01*
X-139783Y-105667D01*
Y-108000D01*
G01X-134100D02*
Y-104667D01*
G01Y-105250D02*
X-134433Y-104917D01*
X-134933Y-104750D01*
X-135517Y-104667D01*
X-136100Y-104833D01*
X-136600Y-105167D01*
X-136933Y-105667D01*
X-137100Y-106333D01*
X-136933Y-107000D01*
X-136600Y-107500D01*
X-136100Y-107833D01*
X-135517Y-108000D01*
X-134933Y-107917D01*
X-134433Y-107667D01*
X-134100Y-107333D01*
G01X-130000Y-108000D02*
Y-103000D01*
G01X-120467Y-108000D02*
Y-103000D01*
X-118467D01*
X-117800Y-103250D01*
X-117300Y-103833D01*
X-117133Y-104500D01*
X-117300Y-105167D01*
X-117717Y-105667D01*
X-118467Y-105917D01*
X-120467D01*
G01X-111367Y-103417D02*
X-111867Y-103167D01*
X-112450Y-103000D01*
X-113117D01*
X-113867Y-103250D01*
X-114450Y-103667D01*
X-114867Y-104167D01*
X-115200Y-105000D01*
X-115283Y-105750D01*
X-115117Y-106500D01*
X-114867Y-107000D01*
X-114367Y-107500D01*
X-113783Y-107833D01*
X-113200Y-108000D01*
X-112617D01*
X-112033Y-107833D01*
X-111533Y-107583D01*
X-111117Y-107250D01*
G01X-106933Y-105333D02*
X-106600Y-105083D01*
X-106350Y-104667D01*
X-106183Y-104083D01*
X-106350Y-103583D01*
X-106683Y-103250D01*
X-107267Y-103000D01*
X-109517D01*
Y-108000D01*
X-106767D01*
X-106183Y-107667D01*
X-105850Y-107167D01*
X-105683Y-106583D01*
X-105850Y-106000D01*
X-106350Y-105500D01*
X-106933Y-105333D01*
X-109517D01*
G01X-102000Y-108167D02*
X-102167Y-108083D01*
Y-107917D01*
X-102000Y-107833D01*
X-101833Y-107917D01*
Y-108083D01*
X-102000Y-108167D01*
G01X-188500Y101000D02*
Y96000D01*
G01X-189667Y99333D02*
X-187333D01*
G01X-182900Y96000D02*
X-183400Y96083D01*
X-183900Y96417D01*
X-184233Y97000D01*
X-184400Y97667D01*
X-184233Y98333D01*
X-183900Y98917D01*
X-183400Y99250D01*
X-182900Y99333D01*
X-182400Y99250D01*
X-181900Y98917D01*
X-181567Y98333D01*
X-181483Y97667D01*
X-181567Y97000D01*
X-181900Y96417D01*
X-182400Y96083D01*
X-182900Y96000D01*
G01X-177300D02*
Y101000D01*
G01X-172950Y98250D02*
X-170283D01*
X-170533Y98833D01*
X-170950Y99167D01*
X-171533Y99333D01*
X-172117Y99250D01*
X-172617Y99000D01*
X-172950Y98417D01*
X-173117Y97917D01*
Y97417D01*
X-172950Y96917D01*
X-172533Y96417D01*
X-172033Y96083D01*
X-171450Y96000D01*
X-170867Y96167D01*
X-170283Y96667D01*
G01X-167267Y96000D02*
Y99333D01*
G01Y98667D02*
X-166850Y99000D01*
X-166433Y99250D01*
X-165850Y99333D01*
X-165433Y99250D01*
X-164933Y99000D01*
G01X-159000Y96000D02*
Y99333D01*
G01Y98750D02*
X-159333Y99083D01*
X-159833Y99250D01*
X-160417Y99333D01*
X-161000Y99167D01*
X-161500Y98833D01*
X-161833Y98333D01*
X-162000Y97667D01*
X-161833Y97000D01*
X-161500Y96500D01*
X-161000Y96167D01*
X-160417Y96000D01*
X-159833Y96083D01*
X-159333Y96333D01*
X-159000Y96667D01*
G01X-156317Y96000D02*
Y99333D01*
G01Y98500D02*
X-155983Y98917D01*
X-155483Y99250D01*
X-154817Y99333D01*
X-154233Y99250D01*
X-153733Y98917D01*
X-153483Y98333D01*
Y96000D01*
G01X-147967Y98917D02*
X-148550Y99250D01*
X-149050Y99333D01*
X-149717Y99167D01*
X-150217Y98833D01*
X-150550Y98250D01*
X-150633Y97667D01*
X-150550Y97083D01*
X-150217Y96583D01*
X-149717Y96167D01*
X-149050Y96000D01*
X-148467Y96167D01*
X-147967Y96500D01*
G01X-144950Y98250D02*
X-142283D01*
X-142533Y98833D01*
X-142950Y99167D01*
X-143533Y99333D01*
X-144117Y99250D01*
X-144617Y99000D01*
X-144950Y98417D01*
X-145117Y97917D01*
Y97417D01*
X-144950Y96917D01*
X-144533Y96417D01*
X-144033Y96083D01*
X-143450Y96000D01*
X-142867Y96167D01*
X-142283Y96667D01*
G01X-132500Y101000D02*
Y96000D01*
G01X-133667Y99333D02*
X-131333D01*
G01X-125400Y96000D02*
Y99333D01*
G01Y98750D02*
X-125733Y99083D01*
X-126233Y99250D01*
X-126817Y99333D01*
X-127400Y99167D01*
X-127900Y98833D01*
X-128233Y98333D01*
X-128400Y97667D01*
X-128233Y97000D01*
X-127900Y96500D01*
X-127400Y96167D01*
X-126817Y96000D01*
X-126233Y96083D01*
X-125733Y96333D01*
X-125400Y96667D01*
G01X-122800Y96000D02*
Y101000D01*
G01Y98500D02*
X-122383Y99000D01*
X-121883Y99250D01*
X-121383Y99333D01*
X-120633Y99167D01*
X-120133Y98833D01*
X-119800Y98250D01*
Y97583D01*
X-119967Y96917D01*
X-120300Y96417D01*
X-120883Y96083D01*
X-121383Y96000D01*
X-121883Y96083D01*
X-122383Y96333D01*
X-122800Y96750D01*
G01X-115700Y96000D02*
Y101000D01*
G01X-111350Y98250D02*
X-108683D01*
X-108933Y98833D01*
X-109350Y99167D01*
X-109933Y99333D01*
X-110517Y99250D01*
X-111017Y99000D01*
X-111350Y98417D01*
X-111517Y97917D01*
Y97417D01*
X-111350Y96917D01*
X-110933Y96417D01*
X-110433Y96083D01*
X-109850Y96000D01*
X-109267Y96167D01*
X-108683Y96667D01*
G01X-104500Y95833D02*
X-104667Y95917D01*
Y96083D01*
X-104500Y96167D01*
X-104333Y96083D01*
Y95917D01*
X-104500Y95833D01*
G01X-189833Y106750D02*
X-189250Y106417D01*
X-188750Y106333D01*
X-188083Y106500D01*
X-187583Y106917D01*
X-187333Y107667D01*
Y111333D01*
G01Y112667D02*
X-187500Y112750D01*
Y112917D01*
X-187333Y113000D01*
X-187167Y112917D01*
Y112750D01*
X-187333Y112667D01*
G01X-184317Y111333D02*
Y109000D01*
X-183983Y108417D01*
X-183483Y108083D01*
X-182900Y108000D01*
X-182317Y108083D01*
X-181817Y108417D01*
X-181483Y109000D01*
G01Y108000D02*
Y111333D01*
G01X-178717Y108000D02*
Y111333D01*
G01Y110500D02*
X-178383Y110917D01*
X-177883Y111250D01*
X-177217Y111333D01*
X-176633Y111250D01*
X-176133Y110917D01*
X-175883Y110333D01*
Y108000D01*
G01X-170367Y110917D02*
X-170950Y111250D01*
X-171450Y111333D01*
X-172117Y111167D01*
X-172617Y110833D01*
X-172950Y110250D01*
X-173033Y109667D01*
X-172950Y109083D01*
X-172617Y108583D01*
X-172117Y108167D01*
X-171450Y108000D01*
X-170867Y108167D01*
X-170367Y108500D01*
G01X-166100Y113000D02*
Y108000D01*
G01X-167267Y111333D02*
X-164933D01*
G01X-160500D02*
Y108000D01*
G01Y112667D02*
X-160667Y112750D01*
Y112917D01*
X-160500Y113000D01*
X-160333Y112917D01*
Y112750D01*
X-160500Y112667D01*
G01X-154900Y108000D02*
X-155400Y108083D01*
X-155900Y108417D01*
X-156233Y109000D01*
X-156400Y109667D01*
X-156233Y110333D01*
X-155900Y110917D01*
X-155400Y111250D01*
X-154900Y111333D01*
X-154400Y111250D01*
X-153900Y110917D01*
X-153567Y110333D01*
X-153483Y109667D01*
X-153567Y109000D01*
X-153900Y108417D01*
X-154400Y108083D01*
X-154900Y108000D01*
G01X-150717D02*
Y111333D01*
G01Y110500D02*
X-150383Y110917D01*
X-149883Y111250D01*
X-149217Y111333D01*
X-148633Y111250D01*
X-148133Y110917D01*
X-147883Y110333D01*
Y108000D01*
G01X-139600D02*
Y113000D01*
G01Y110500D02*
X-139183Y111000D01*
X-138683Y111250D01*
X-138183Y111333D01*
X-137433Y111167D01*
X-136933Y110833D01*
X-136600Y110250D01*
Y109583D01*
X-136767Y108917D01*
X-137100Y108417D01*
X-137683Y108083D01*
X-138183Y108000D01*
X-138683Y108083D01*
X-139183Y108333D01*
X-139600Y108750D01*
G01X-133750Y110250D02*
X-131083D01*
X-131333Y110833D01*
X-131750Y111167D01*
X-132333Y111333D01*
X-132917Y111250D01*
X-133417Y111000D01*
X-133750Y110417D01*
X-133917Y109917D01*
Y109417D01*
X-133750Y108917D01*
X-133333Y108417D01*
X-132833Y108083D01*
X-132250Y108000D01*
X-131667Y108167D01*
X-131083Y108667D01*
G01X-126900Y108000D02*
Y113000D01*
G01X-121300Y108000D02*
X-121800Y108083D01*
X-122300Y108417D01*
X-122633Y109000D01*
X-122800Y109667D01*
X-122633Y110333D01*
X-122300Y110917D01*
X-121800Y111250D01*
X-121300Y111333D01*
X-120800Y111250D01*
X-120300Y110917D01*
X-119967Y110333D01*
X-119883Y109667D01*
X-119967Y109000D01*
X-120300Y108417D01*
X-120800Y108083D01*
X-121300Y108000D01*
G01X-117783Y111333D02*
X-116783Y108000D01*
X-115700Y111333D01*
X-114617Y108000D01*
X-113617Y111333D01*
G01X-104500Y113000D02*
Y108000D01*
G01X-105667Y111333D02*
X-103333D01*
G01X-100317Y108000D02*
Y113000D01*
G01Y110583D02*
X-99900Y111000D01*
X-99483Y111250D01*
X-98817Y111333D01*
X-98317Y111250D01*
X-97733Y110917D01*
X-97483Y110417D01*
Y108000D01*
G01X-94550Y110250D02*
X-91883D01*
X-92133Y110833D01*
X-92550Y111167D01*
X-93133Y111333D01*
X-93717Y111250D01*
X-94217Y111000D01*
X-94550Y110417D01*
X-94717Y109917D01*
Y109417D01*
X-94550Y108917D01*
X-94133Y108417D01*
X-93633Y108083D01*
X-93050Y108000D01*
X-92467Y108167D01*
X-91883Y108667D01*
G01X-84600Y108000D02*
Y111333D01*
G01Y110417D02*
X-84350Y110833D01*
X-83933Y111167D01*
X-83350Y111333D01*
X-82767Y111167D01*
X-82350Y110833D01*
X-82100Y110417D01*
Y108000D01*
G01Y110417D02*
X-81850Y110833D01*
X-81433Y111167D01*
X-80850Y111333D01*
X-80267Y111167D01*
X-79850Y110833D01*
X-79600Y110333D01*
Y108000D01*
G01X-76500Y111333D02*
Y108000D01*
G01Y112667D02*
X-76667Y112750D01*
Y112917D01*
X-76500Y113000D01*
X-76333Y112917D01*
Y112750D01*
X-76500Y112667D01*
G01X-72317Y108000D02*
Y111333D01*
G01Y110500D02*
X-71983Y110917D01*
X-71483Y111250D01*
X-70817Y111333D01*
X-70233Y111250D01*
X-69733Y110917D01*
X-69483Y110333D01*
Y108000D01*
G01X-58367Y110917D02*
X-58950Y111250D01*
X-59450Y111333D01*
X-60117Y111167D01*
X-60617Y110833D01*
X-60950Y110250D01*
X-61033Y109667D01*
X-60950Y109083D01*
X-60617Y108583D01*
X-60117Y108167D01*
X-59450Y108000D01*
X-58867Y108167D01*
X-58367Y108500D01*
G01X-54100Y108000D02*
X-54600Y108083D01*
X-55100Y108417D01*
X-55433Y109000D01*
X-55600Y109667D01*
X-55433Y110333D01*
X-55100Y110917D01*
X-54600Y111250D01*
X-54100Y111333D01*
X-53600Y111250D01*
X-53100Y110917D01*
X-52767Y110333D01*
X-52683Y109667D01*
X-52767Y109000D01*
X-53100Y108417D01*
X-53600Y108083D01*
X-54100Y108000D01*
G01X-49917D02*
Y111333D01*
G01Y110500D02*
X-49583Y110917D01*
X-49083Y111250D01*
X-48417Y111333D01*
X-47833Y111250D01*
X-47333Y110917D01*
X-47083Y110333D01*
Y108000D01*
G01X-41400Y113000D02*
Y108000D01*
G01Y108750D02*
X-41733Y108333D01*
X-42233Y108083D01*
X-42817Y108000D01*
X-43483Y108167D01*
X-43983Y108583D01*
X-44317Y109083D01*
X-44400Y109667D01*
X-44317Y110250D01*
X-43983Y110750D01*
X-43483Y111167D01*
X-42817Y111333D01*
X-42233Y111250D01*
X-41817Y111083D01*
X-41400Y110750D01*
G01X-38717Y111333D02*
Y109000D01*
X-38383Y108417D01*
X-37883Y108083D01*
X-37300Y108000D01*
X-36717Y108083D01*
X-36217Y108417D01*
X-35883Y109000D01*
G01Y108000D02*
Y111333D01*
G01X-30367Y110917D02*
X-30950Y111250D01*
X-31450Y111333D01*
X-32117Y111167D01*
X-32617Y110833D01*
X-32950Y110250D01*
X-33033Y109667D01*
X-32950Y109083D01*
X-32617Y108583D01*
X-32117Y108167D01*
X-31450Y108000D01*
X-30867Y108167D01*
X-30367Y108500D01*
G01X-26100Y113000D02*
Y108000D01*
G01X-27267Y111333D02*
X-24933D01*
G01X-20500Y108000D02*
X-21000Y108083D01*
X-21500Y108417D01*
X-21833Y109000D01*
X-22000Y109667D01*
X-21833Y110333D01*
X-21500Y110917D01*
X-21000Y111250D01*
X-20500Y111333D01*
X-20000Y111250D01*
X-19500Y110917D01*
X-19167Y110333D01*
X-19083Y109667D01*
X-19167Y109000D01*
X-19500Y108417D01*
X-20000Y108083D01*
X-20500Y108000D01*
G01X-16067D02*
Y111333D01*
G01Y110667D02*
X-15650Y111000D01*
X-15233Y111250D01*
X-14650Y111333D01*
X-14233Y111250D01*
X-13733Y111000D01*
G01X-5783Y111333D02*
X-4783Y108000D01*
X-3700Y111333D01*
X-2617Y108000D01*
X-1617Y111333D01*
G01X1900D02*
Y108000D01*
G01Y112667D02*
X1733Y112750D01*
Y112917D01*
X1900Y113000D01*
X2067Y112917D01*
Y112750D01*
X1900Y112667D01*
G01X9000Y113000D02*
Y108000D01*
G01Y108750D02*
X8667Y108333D01*
X8167Y108083D01*
X7583Y108000D01*
X6917Y108167D01*
X6417Y108583D01*
X6083Y109083D01*
X6000Y109667D01*
X6083Y110250D01*
X6417Y110750D01*
X6917Y111167D01*
X7583Y111333D01*
X8167Y111250D01*
X8583Y111083D01*
X9000Y110750D01*
G01X13100Y113000D02*
Y108000D01*
G01X11933Y111333D02*
X14267D01*
G01X17283Y108000D02*
Y113000D01*
G01Y110583D02*
X17700Y111000D01*
X18117Y111250D01*
X18783Y111333D01*
X19283Y111250D01*
X19867Y110917D01*
X20117Y110417D01*
Y108000D01*
G01X28650Y108583D02*
X29067Y108250D01*
X29650Y108000D01*
X30150D01*
X30650Y108167D01*
X30983Y108417D01*
X31150Y108750D01*
X31067Y109250D01*
X30733Y109500D01*
X29233Y110000D01*
X28900Y110583D01*
X29067Y111000D01*
X29400Y111250D01*
X29900Y111333D01*
X30400Y111250D01*
X30900Y111000D01*
G01X34000Y106333D02*
Y111333D01*
G01Y110583D02*
X34417Y111000D01*
X34833Y111250D01*
X35500Y111333D01*
X36083Y111250D01*
X36667Y110833D01*
X36917Y110250D01*
X37000Y109667D01*
X36917Y109083D01*
X36667Y108500D01*
X36167Y108167D01*
X35500Y108000D01*
X34917Y108083D01*
X34333Y108333D01*
X34000Y108667D01*
G01X39850Y110250D02*
X42517D01*
X42267Y110833D01*
X41850Y111167D01*
X41267Y111333D01*
X40683Y111250D01*
X40183Y111000D01*
X39850Y110417D01*
X39683Y109917D01*
Y109417D01*
X39850Y108917D01*
X40267Y108417D01*
X40767Y108083D01*
X41350Y108000D01*
X41933Y108167D01*
X42517Y108667D01*
G01X48033Y110917D02*
X47450Y111250D01*
X46950Y111333D01*
X46283Y111167D01*
X45783Y110833D01*
X45450Y110250D01*
X45367Y109667D01*
X45450Y109083D01*
X45783Y108583D01*
X46283Y108167D01*
X46950Y108000D01*
X47533Y108167D01*
X48033Y108500D01*
G01X52300Y111333D02*
Y108000D01*
G01Y112667D02*
X52133Y112750D01*
Y112917D01*
X52300Y113000D01*
X52467Y112917D01*
Y112750D01*
X52300Y112667D01*
G01X57400Y108000D02*
Y112250D01*
X57567Y112667D01*
X57900Y112917D01*
X58400Y113000D01*
X58900Y112833D01*
X59150Y112417D01*
G01X58150Y111000D02*
X56483D01*
G01X63500Y111333D02*
Y108000D01*
G01Y112667D02*
X63333Y112750D01*
Y112917D01*
X63500Y113000D01*
X63667Y112917D01*
Y112750D01*
X63500Y112667D01*
G01X67850Y110250D02*
X70517D01*
X70267Y110833D01*
X69850Y111167D01*
X69267Y111333D01*
X68683Y111250D01*
X68183Y111000D01*
X67850Y110417D01*
X67683Y109917D01*
Y109417D01*
X67850Y108917D01*
X68267Y108417D01*
X68767Y108083D01*
X69350Y108000D01*
X69933Y108167D01*
X70517Y108667D01*
G01X76200Y113000D02*
Y108000D01*
G01Y108750D02*
X75867Y108333D01*
X75367Y108083D01*
X74783Y108000D01*
X74117Y108167D01*
X73617Y108583D01*
X73283Y109083D01*
X73200Y109667D01*
X73283Y110250D01*
X73617Y110750D01*
X74117Y111167D01*
X74783Y111333D01*
X75367Y111250D01*
X75783Y111083D01*
X76200Y110750D01*
G01X85900Y108000D02*
X85400Y108083D01*
X84900Y108417D01*
X84567Y109000D01*
X84400Y109667D01*
X84567Y110333D01*
X84900Y110917D01*
X85400Y111250D01*
X85900Y111333D01*
X86400Y111250D01*
X86900Y110917D01*
X87233Y110333D01*
X87317Y109667D01*
X87233Y109000D01*
X86900Y108417D01*
X86400Y108083D01*
X85900Y108000D01*
G01X90083D02*
Y111333D01*
G01Y110500D02*
X90417Y110917D01*
X90917Y111250D01*
X91583Y111333D01*
X92167Y111250D01*
X92667Y110917D01*
X92917Y110333D01*
Y108000D01*
G01X102700Y113000D02*
Y108000D01*
G01X101533Y111333D02*
X103867D01*
G01X106883Y108000D02*
Y113000D01*
G01Y110583D02*
X107300Y111000D01*
X107717Y111250D01*
X108383Y111333D01*
X108883Y111250D01*
X109467Y110917D01*
X109717Y110417D01*
Y108000D01*
G01X112650Y110250D02*
X115317D01*
X115067Y110833D01*
X114650Y111167D01*
X114067Y111333D01*
X113483Y111250D01*
X112983Y111000D01*
X112650Y110417D01*
X112483Y109917D01*
Y109417D01*
X112650Y108917D01*
X113067Y108417D01*
X113567Y108083D01*
X114150Y108000D01*
X114733Y108167D01*
X115317Y108667D01*
G01X-190250Y118500D02*
Y123500D01*
G01X-186750D02*
Y118500D01*
G01Y121000D02*
X-190250D01*
G01X-182900Y118500D02*
X-183400Y118583D01*
X-183900Y118917D01*
X-184233Y119500D01*
X-184400Y120167D01*
X-184233Y120833D01*
X-183900Y121417D01*
X-183400Y121750D01*
X-182900Y121833D01*
X-182400Y121750D01*
X-181900Y121417D01*
X-181567Y120833D01*
X-181483Y120167D01*
X-181567Y119500D01*
X-181900Y118917D01*
X-182400Y118583D01*
X-182900Y118500D01*
G01X-179383Y121833D02*
X-178383Y118500D01*
X-177300Y121833D01*
X-176217Y118500D01*
X-175217Y121833D01*
G01X-172950Y120750D02*
X-170283D01*
X-170533Y121333D01*
X-170950Y121667D01*
X-171533Y121833D01*
X-172117Y121750D01*
X-172617Y121500D01*
X-172950Y120917D01*
X-173117Y120417D01*
Y119917D01*
X-172950Y119417D01*
X-172533Y118917D01*
X-172033Y118583D01*
X-171450Y118500D01*
X-170867Y118667D01*
X-170283Y119167D01*
G01X-167600Y121833D02*
X-166100Y118500D01*
X-164600Y121833D01*
G01X-161750Y120750D02*
X-159083D01*
X-159333Y121333D01*
X-159750Y121667D01*
X-160333Y121833D01*
X-160917Y121750D01*
X-161417Y121500D01*
X-161750Y120917D01*
X-161917Y120417D01*
Y119917D01*
X-161750Y119417D01*
X-161333Y118917D01*
X-160833Y118583D01*
X-160250Y118500D01*
X-159667Y118667D01*
X-159083Y119167D01*
G01X-156067Y118500D02*
Y121833D01*
G01Y121167D02*
X-155650Y121500D01*
X-155233Y121750D01*
X-154650Y121833D01*
X-154233Y121750D01*
X-153733Y121500D01*
G01X-149467Y117583D02*
X-149133Y118667D01*
G01X-143700Y123500D02*
Y118500D01*
G01X-144867Y121833D02*
X-142533D01*
G01X-139517Y118500D02*
Y123500D01*
G01Y121083D02*
X-139100Y121500D01*
X-138683Y121750D01*
X-138017Y121833D01*
X-137517Y121750D01*
X-136933Y121417D01*
X-136683Y120917D01*
Y118500D01*
G01X-133750Y120750D02*
X-131083D01*
X-131333Y121333D01*
X-131750Y121667D01*
X-132333Y121833D01*
X-132917Y121750D01*
X-133417Y121500D01*
X-133750Y120917D01*
X-133917Y120417D01*
Y119917D01*
X-133750Y119417D01*
X-133333Y118917D01*
X-132833Y118583D01*
X-132250Y118500D01*
X-131667Y118667D01*
X-131083Y119167D01*
G01X-121300Y123500D02*
Y118500D01*
G01X-122467Y121833D02*
X-120133D01*
G01X-114200Y118500D02*
Y121833D01*
G01Y121250D02*
X-114533Y121583D01*
X-115033Y121750D01*
X-115617Y121833D01*
X-116200Y121667D01*
X-116700Y121333D01*
X-117033Y120833D01*
X-117200Y120167D01*
X-117033Y119500D01*
X-116700Y119000D01*
X-116200Y118667D01*
X-115617Y118500D01*
X-115033Y118583D01*
X-114533Y118833D01*
X-114200Y119167D01*
G01X-111517Y118500D02*
Y121833D01*
G01Y121000D02*
X-111183Y121417D01*
X-110683Y121750D01*
X-110017Y121833D01*
X-109433Y121750D01*
X-108933Y121417D01*
X-108683Y120833D01*
Y118500D01*
G01X-105667Y117250D02*
X-105083Y116917D01*
X-104417Y116833D01*
X-103833Y116917D01*
X-103333Y117333D01*
X-103000Y117917D01*
Y121833D01*
G01Y121167D02*
X-103333Y121500D01*
X-103833Y121750D01*
X-104417Y121833D01*
X-105083Y121667D01*
X-105500Y121333D01*
X-105833Y120750D01*
X-106000Y120167D01*
X-105917Y119667D01*
X-105583Y119083D01*
X-105083Y118667D01*
X-104417Y118500D01*
X-103917Y118583D01*
X-103333Y118917D01*
X-103000Y119250D01*
G01X-100150Y120750D02*
X-97483D01*
X-97733Y121333D01*
X-98150Y121667D01*
X-98733Y121833D01*
X-99317Y121750D01*
X-99817Y121500D01*
X-100150Y120917D01*
X-100317Y120417D01*
Y119917D01*
X-100150Y119417D01*
X-99733Y118917D01*
X-99233Y118583D01*
X-98650Y118500D01*
X-98067Y118667D01*
X-97483Y119167D01*
G01X-94717Y118500D02*
Y121833D01*
G01Y121000D02*
X-94383Y121417D01*
X-93883Y121750D01*
X-93217Y121833D01*
X-92633Y121750D01*
X-92133Y121417D01*
X-91883Y120833D01*
Y118500D01*
G01X-86367Y121417D02*
X-86950Y121750D01*
X-87450Y121833D01*
X-88117Y121667D01*
X-88617Y121333D01*
X-88950Y120750D01*
X-89033Y120167D01*
X-88950Y119583D01*
X-88617Y119083D01*
X-88117Y118667D01*
X-87450Y118500D01*
X-86867Y118667D01*
X-86367Y119000D01*
G01X-83850Y117000D02*
X-83350Y116833D01*
X-82683Y117000D01*
X-82267Y117333D01*
X-81933Y117750D01*
X-81433Y119083D01*
X-80350Y121833D01*
G01X-83017D02*
X-81433Y119083D01*
G01X-72150D02*
X-71733Y118750D01*
X-71150Y118500D01*
X-70650D01*
X-70150Y118667D01*
X-69817Y118917D01*
X-69650Y119250D01*
X-69733Y119750D01*
X-70067Y120000D01*
X-71567Y120500D01*
X-71900Y121083D01*
X-71733Y121500D01*
X-71400Y121750D01*
X-70900Y121833D01*
X-70400Y121750D01*
X-69900Y121500D01*
G01X-66717Y118500D02*
Y123500D01*
G01Y121083D02*
X-66300Y121500D01*
X-65883Y121750D01*
X-65217Y121833D01*
X-64717Y121750D01*
X-64133Y121417D01*
X-63883Y120917D01*
Y118500D01*
G01X-59700D02*
X-60200Y118583D01*
X-60700Y118917D01*
X-61033Y119500D01*
X-61200Y120167D01*
X-61033Y120833D01*
X-60700Y121417D01*
X-60200Y121750D01*
X-59700Y121833D01*
X-59200Y121750D01*
X-58700Y121417D01*
X-58367Y120833D01*
X-58283Y120167D01*
X-58367Y119500D01*
X-58700Y118917D01*
X-59200Y118583D01*
X-59700Y118500D01*
G01X-55517Y121833D02*
Y119500D01*
X-55183Y118917D01*
X-54683Y118583D01*
X-54100Y118500D01*
X-53517Y118583D01*
X-53017Y118917D01*
X-52683Y119500D01*
G01Y118500D02*
Y121833D01*
G01X-48500Y118500D02*
Y123500D01*
G01X-41400D02*
Y118500D01*
G01Y119250D02*
X-41733Y118833D01*
X-42233Y118583D01*
X-42817Y118500D01*
X-43483Y118667D01*
X-43983Y119083D01*
X-44317Y119583D01*
X-44400Y120167D01*
X-44317Y120750D01*
X-43983Y121250D01*
X-43483Y121667D01*
X-42817Y121833D01*
X-42233Y121750D01*
X-41817Y121583D01*
X-41400Y121250D01*
G01X-33117Y118500D02*
Y121833D01*
G01Y121000D02*
X-32783Y121417D01*
X-32283Y121750D01*
X-31617Y121833D01*
X-31033Y121750D01*
X-30533Y121417D01*
X-30283Y120833D01*
Y118500D01*
G01X-26100D02*
X-26600Y118583D01*
X-27100Y118917D01*
X-27433Y119500D01*
X-27600Y120167D01*
X-27433Y120833D01*
X-27100Y121417D01*
X-26600Y121750D01*
X-26100Y121833D01*
X-25600Y121750D01*
X-25100Y121417D01*
X-24767Y120833D01*
X-24683Y120167D01*
X-24767Y119500D01*
X-25100Y118917D01*
X-25600Y118583D01*
X-26100Y118500D01*
G01X-20500Y123500D02*
Y118500D01*
G01X-21667Y121833D02*
X-19333D01*
G01X-10467Y118500D02*
Y121833D01*
G01Y121167D02*
X-10050Y121500D01*
X-9633Y121750D01*
X-9050Y121833D01*
X-8633Y121750D01*
X-8133Y121500D01*
G01X-4950Y120750D02*
X-2283D01*
X-2533Y121333D01*
X-2950Y121667D01*
X-3533Y121833D01*
X-4117Y121750D01*
X-4617Y121500D01*
X-4950Y120917D01*
X-5117Y120417D01*
Y119917D01*
X-4950Y119417D01*
X-4533Y118917D01*
X-4033Y118583D01*
X-3450Y118500D01*
X-2867Y118667D01*
X-2283Y119167D01*
G01X3400Y123500D02*
Y118500D01*
G01Y119250D02*
X3067Y118833D01*
X2567Y118583D01*
X1983Y118500D01*
X1317Y118667D01*
X817Y119083D01*
X483Y119583D01*
X400Y120167D01*
X483Y120750D01*
X817Y121250D01*
X1317Y121667D01*
X1983Y121833D01*
X2567Y121750D01*
X2983Y121583D01*
X3400Y121250D01*
G01X6083Y121833D02*
Y119500D01*
X6417Y118917D01*
X6917Y118583D01*
X7500Y118500D01*
X8083Y118583D01*
X8583Y118917D01*
X8917Y119500D01*
G01Y118500D02*
Y121833D01*
G01X14433Y121417D02*
X13850Y121750D01*
X13350Y121833D01*
X12683Y121667D01*
X12183Y121333D01*
X11850Y120750D01*
X11767Y120167D01*
X11850Y119583D01*
X12183Y119083D01*
X12683Y118667D01*
X13350Y118500D01*
X13933Y118667D01*
X14433Y119000D01*
G01X17450Y120750D02*
X20117D01*
X19867Y121333D01*
X19450Y121667D01*
X18867Y121833D01*
X18283Y121750D01*
X17783Y121500D01*
X17450Y120917D01*
X17283Y120417D01*
Y119917D01*
X17450Y119417D01*
X17867Y118917D01*
X18367Y118583D01*
X18950Y118500D01*
X19533Y118667D01*
X20117Y119167D01*
G01X29900Y123500D02*
Y118500D01*
G01X28733Y121833D02*
X31067D01*
G01X34083Y118500D02*
Y123500D01*
G01Y121083D02*
X34500Y121500D01*
X34917Y121750D01*
X35583Y121833D01*
X36083Y121750D01*
X36667Y121417D01*
X36917Y120917D01*
Y118500D01*
G01X39850Y120750D02*
X42517D01*
X42267Y121333D01*
X41850Y121667D01*
X41267Y121833D01*
X40683Y121750D01*
X40183Y121500D01*
X39850Y120917D01*
X39683Y120417D01*
Y119917D01*
X39850Y119417D01*
X40267Y118917D01*
X40767Y118583D01*
X41350Y118500D01*
X41933Y118667D01*
X42517Y119167D01*
G01X52300Y118500D02*
Y123500D01*
G01X59400Y118500D02*
Y121833D01*
G01Y121250D02*
X59067Y121583D01*
X58567Y121750D01*
X57983Y121833D01*
X57400Y121667D01*
X56900Y121333D01*
X56567Y120833D01*
X56400Y120167D01*
X56567Y119500D01*
X56900Y119000D01*
X57400Y118667D01*
X57983Y118500D01*
X58567Y118583D01*
X59067Y118833D01*
X59400Y119167D01*
G01X62083Y118500D02*
Y121833D01*
G01Y121000D02*
X62417Y121417D01*
X62917Y121750D01*
X63583Y121833D01*
X64167Y121750D01*
X64667Y121417D01*
X64917Y120833D01*
Y118500D01*
G01X70600Y123500D02*
Y118500D01*
G01Y119250D02*
X70267Y118833D01*
X69767Y118583D01*
X69183Y118500D01*
X68517Y118667D01*
X68017Y119083D01*
X67683Y119583D01*
X67600Y120167D01*
X67683Y120750D01*
X68017Y121250D01*
X68517Y121667D01*
X69183Y121833D01*
X69767Y121750D01*
X70183Y121583D01*
X70600Y121250D01*
G01X73200Y118333D02*
X76200Y123500D01*
G01X81633Y121417D02*
X81050Y121750D01*
X80550Y121833D01*
X79883Y121667D01*
X79383Y121333D01*
X79050Y120750D01*
X78967Y120167D01*
X79050Y119583D01*
X79383Y119083D01*
X79883Y118667D01*
X80550Y118500D01*
X81133Y118667D01*
X81633Y119000D01*
G01X85900Y118500D02*
X85400Y118583D01*
X84900Y118917D01*
X84567Y119500D01*
X84400Y120167D01*
X84567Y120833D01*
X84900Y121417D01*
X85400Y121750D01*
X85900Y121833D01*
X86400Y121750D01*
X86900Y121417D01*
X87233Y120833D01*
X87317Y120167D01*
X87233Y119500D01*
X86900Y118917D01*
X86400Y118583D01*
X85900Y118500D01*
G01X90083D02*
Y121833D01*
G01Y121000D02*
X90417Y121417D01*
X90917Y121750D01*
X91583Y121833D01*
X92167Y121750D01*
X92667Y121417D01*
X92917Y120833D01*
Y118500D01*
G01X98600Y123500D02*
Y118500D01*
G01Y119250D02*
X98267Y118833D01*
X97767Y118583D01*
X97183Y118500D01*
X96517Y118667D01*
X96017Y119083D01*
X95683Y119583D01*
X95600Y120167D01*
X95683Y120750D01*
X96017Y121250D01*
X96517Y121667D01*
X97183Y121833D01*
X97767Y121750D01*
X98183Y121583D01*
X98600Y121250D01*
G01X101283Y121833D02*
Y119500D01*
X101617Y118917D01*
X102117Y118583D01*
X102700Y118500D01*
X103283Y118583D01*
X103783Y118917D01*
X104117Y119500D01*
G01Y118500D02*
Y121833D01*
G01X109633Y121417D02*
X109050Y121750D01*
X108550Y121833D01*
X107883Y121667D01*
X107383Y121333D01*
X107050Y120750D01*
X106967Y120167D01*
X107050Y119583D01*
X107383Y119083D01*
X107883Y118667D01*
X108550Y118500D01*
X109133Y118667D01*
X109633Y119000D01*
G01X113900Y123500D02*
Y118500D01*
G01X112733Y121833D02*
X115067D01*
G01X119500Y118500D02*
X119000Y118583D01*
X118500Y118917D01*
X118167Y119500D01*
X118000Y120167D01*
X118167Y120833D01*
X118500Y121417D01*
X119000Y121750D01*
X119500Y121833D01*
X120000Y121750D01*
X120500Y121417D01*
X120833Y120833D01*
X120917Y120167D01*
X120833Y119500D01*
X120500Y118917D01*
X120000Y118583D01*
X119500Y118500D01*
G01X123933D02*
Y121833D01*
G01Y121167D02*
X124350Y121500D01*
X124767Y121750D01*
X125350Y121833D01*
X125767Y121750D01*
X126267Y121500D01*
G01X-187000Y129000D02*
Y132333D01*
G01Y131750D02*
X-187333Y132083D01*
X-187833Y132250D01*
X-188417Y132333D01*
X-189000Y132167D01*
X-189500Y131833D01*
X-189833Y131333D01*
X-190000Y130667D01*
X-189833Y130000D01*
X-189500Y129500D01*
X-189000Y129167D01*
X-188417Y129000D01*
X-187833Y129083D01*
X-187333Y129333D01*
X-187000Y129667D01*
G01X-181567Y131917D02*
X-182150Y132250D01*
X-182650Y132333D01*
X-183317Y132167D01*
X-183817Y131833D01*
X-184150Y131250D01*
X-184233Y130667D01*
X-184150Y130083D01*
X-183817Y129583D01*
X-183317Y129167D01*
X-182650Y129000D01*
X-182067Y129167D01*
X-181567Y129500D01*
G01X-175967Y131917D02*
X-176550Y132250D01*
X-177050Y132333D01*
X-177717Y132167D01*
X-178217Y131833D01*
X-178550Y131250D01*
X-178633Y130667D01*
X-178550Y130083D01*
X-178217Y129583D01*
X-177717Y129167D01*
X-177050Y129000D01*
X-176467Y129167D01*
X-175967Y129500D01*
G01X-172950Y131250D02*
X-170283D01*
X-170533Y131833D01*
X-170950Y132167D01*
X-171533Y132333D01*
X-172117Y132250D01*
X-172617Y132000D01*
X-172950Y131417D01*
X-173117Y130917D01*
Y130417D01*
X-172950Y129917D01*
X-172533Y129417D01*
X-172033Y129083D01*
X-171450Y129000D01*
X-170867Y129167D01*
X-170283Y129667D01*
G01X-167600Y127333D02*
Y132333D01*
G01Y131583D02*
X-167183Y132000D01*
X-166767Y132250D01*
X-166100Y132333D01*
X-165517Y132250D01*
X-164933Y131833D01*
X-164683Y131250D01*
X-164600Y130667D01*
X-164683Y130083D01*
X-164933Y129500D01*
X-165433Y129167D01*
X-166100Y129000D01*
X-166683Y129083D01*
X-167267Y129333D01*
X-167600Y129667D01*
G01X-160500Y134000D02*
Y129000D01*
G01X-161667Y132333D02*
X-159333D01*
G01X-153400Y129000D02*
Y132333D01*
G01Y131750D02*
X-153733Y132083D01*
X-154233Y132250D01*
X-154817Y132333D01*
X-155400Y132167D01*
X-155900Y131833D01*
X-156233Y131333D01*
X-156400Y130667D01*
X-156233Y130000D01*
X-155900Y129500D01*
X-155400Y129167D01*
X-154817Y129000D01*
X-154233Y129083D01*
X-153733Y129333D01*
X-153400Y129667D01*
G01X-150800Y129000D02*
Y134000D01*
G01Y131500D02*
X-150383Y132000D01*
X-149883Y132250D01*
X-149383Y132333D01*
X-148633Y132167D01*
X-148133Y131833D01*
X-147800Y131250D01*
Y130583D01*
X-147967Y129917D01*
X-148300Y129417D01*
X-148883Y129083D01*
X-149383Y129000D01*
X-149883Y129083D01*
X-150383Y129333D01*
X-150800Y129750D01*
G01X-143700Y129000D02*
Y134000D01*
G01X-139350Y131250D02*
X-136683D01*
X-136933Y131833D01*
X-137350Y132167D01*
X-137933Y132333D01*
X-138517Y132250D01*
X-139017Y132000D01*
X-139350Y131417D01*
X-139517Y130917D01*
Y130417D01*
X-139350Y129917D01*
X-138933Y129417D01*
X-138433Y129083D01*
X-137850Y129000D01*
X-137267Y129167D01*
X-136683Y129667D01*
G01X-132500Y128833D02*
X-132667Y128917D01*
Y129083D01*
X-132500Y129167D01*
X-132333Y129083D01*
Y128917D01*
X-132500Y128833D01*
G01X-188500Y144500D02*
Y139500D01*
G01X-190417Y144500D02*
X-186583D01*
G01X-184317Y139500D02*
Y144500D01*
G01Y142083D02*
X-183900Y142500D01*
X-183483Y142750D01*
X-182817Y142833D01*
X-182317Y142750D01*
X-181733Y142417D01*
X-181483Y141917D01*
Y139500D01*
G01X-178550Y141750D02*
X-175883D01*
X-176133Y142333D01*
X-176550Y142667D01*
X-177133Y142833D01*
X-177717Y142750D01*
X-178217Y142500D01*
X-178550Y141917D01*
X-178717Y141417D01*
Y140917D01*
X-178550Y140417D01*
X-178133Y139917D01*
X-177633Y139583D01*
X-177050Y139500D01*
X-176467Y139667D01*
X-175883Y140167D01*
G01X-167600Y139500D02*
Y144500D01*
G01Y142000D02*
X-167183Y142500D01*
X-166683Y142750D01*
X-166183Y142833D01*
X-165433Y142667D01*
X-164933Y142333D01*
X-164600Y141750D01*
Y141083D01*
X-164767Y140417D01*
X-165100Y139917D01*
X-165683Y139583D01*
X-166183Y139500D01*
X-166683Y139583D01*
X-167183Y139833D01*
X-167600Y140250D01*
G01X-161667Y139500D02*
Y142833D01*
G01Y142167D02*
X-161250Y142500D01*
X-160833Y142750D01*
X-160250Y142833D01*
X-159833Y142750D01*
X-159333Y142500D01*
G01X-156150Y141750D02*
X-153483D01*
X-153733Y142333D01*
X-154150Y142667D01*
X-154733Y142833D01*
X-155317Y142750D01*
X-155817Y142500D01*
X-156150Y141917D01*
X-156317Y141417D01*
Y140917D01*
X-156150Y140417D01*
X-155733Y139917D01*
X-155233Y139583D01*
X-154650Y139500D01*
X-154067Y139667D01*
X-153483Y140167D01*
G01X-147800Y139500D02*
Y142833D01*
G01Y142250D02*
X-148133Y142583D01*
X-148633Y142750D01*
X-149217Y142833D01*
X-149800Y142667D01*
X-150300Y142333D01*
X-150633Y141833D01*
X-150800Y141167D01*
X-150633Y140500D01*
X-150300Y140000D01*
X-149800Y139667D01*
X-149217Y139500D01*
X-148633Y139583D01*
X-148133Y139833D01*
X-147800Y140167D01*
G01X-145117Y139500D02*
Y144500D01*
G01X-142450Y142833D02*
X-145117Y140917D01*
G01X-144033Y141667D02*
X-142283Y139500D01*
G01X-138100D02*
X-138600Y139583D01*
X-139100Y139917D01*
X-139433Y140500D01*
X-139600Y141167D01*
X-139433Y141833D01*
X-139100Y142417D01*
X-138600Y142750D01*
X-138100Y142833D01*
X-137600Y142750D01*
X-137100Y142417D01*
X-136767Y141833D01*
X-136683Y141167D01*
X-136767Y140500D01*
X-137100Y139917D01*
X-137600Y139583D01*
X-138100Y139500D01*
G01X-133917Y142833D02*
Y140500D01*
X-133583Y139917D01*
X-133083Y139583D01*
X-132500Y139500D01*
X-131917Y139583D01*
X-131417Y139917D01*
X-131083Y140500D01*
G01Y139500D02*
Y142833D01*
G01X-126900Y144500D02*
Y139500D01*
G01X-128067Y142833D02*
X-125733D01*
G01X-115700D02*
Y139500D01*
G01Y144167D02*
X-115867Y144250D01*
Y144417D01*
X-115700Y144500D01*
X-115533Y144417D01*
Y144250D01*
X-115700Y144167D01*
G01X-111350Y140083D02*
X-110933Y139750D01*
X-110350Y139500D01*
X-109850D01*
X-109350Y139667D01*
X-109017Y139917D01*
X-108850Y140250D01*
X-108933Y140750D01*
X-109267Y141000D01*
X-110767Y141500D01*
X-111100Y142083D01*
X-110933Y142500D01*
X-110600Y142750D01*
X-110100Y142833D01*
X-109600Y142750D01*
X-109100Y142500D01*
G01X-100317Y139500D02*
Y142833D01*
G01Y142000D02*
X-99983Y142417D01*
X-99483Y142750D01*
X-98817Y142833D01*
X-98233Y142750D01*
X-97733Y142417D01*
X-97483Y141833D01*
Y139500D01*
G01X-93300D02*
X-93800Y139583D01*
X-94300Y139917D01*
X-94633Y140500D01*
X-94800Y141167D01*
X-94633Y141833D01*
X-94300Y142417D01*
X-93800Y142750D01*
X-93300Y142833D01*
X-92800Y142750D01*
X-92300Y142417D01*
X-91967Y141833D01*
X-91883Y141167D01*
X-91967Y140500D01*
X-92300Y139917D01*
X-92800Y139583D01*
X-93300Y139500D01*
G01X-87700Y144500D02*
Y139500D01*
G01X-88867Y142833D02*
X-86533D01*
G01X-75000Y139500D02*
Y142833D01*
G01Y142250D02*
X-75333Y142583D01*
X-75833Y142750D01*
X-76417Y142833D01*
X-77000Y142667D01*
X-77500Y142333D01*
X-77833Y141833D01*
X-78000Y141167D01*
X-77833Y140500D01*
X-77500Y140000D01*
X-77000Y139667D01*
X-76417Y139500D01*
X-75833Y139583D01*
X-75333Y139833D01*
X-75000Y140167D01*
G01X-70900Y139500D02*
Y144500D01*
G01X-65300Y139500D02*
Y144500D01*
G01X-59700Y139500D02*
X-60200Y139583D01*
X-60700Y139917D01*
X-61033Y140500D01*
X-61200Y141167D01*
X-61033Y141833D01*
X-60700Y142417D01*
X-60200Y142750D01*
X-59700Y142833D01*
X-59200Y142750D01*
X-58700Y142417D01*
X-58367Y141833D01*
X-58283Y141167D01*
X-58367Y140500D01*
X-58700Y139917D01*
X-59200Y139583D01*
X-59700Y139500D01*
G01X-56183Y142833D02*
X-55183Y139500D01*
X-54100Y142833D01*
X-53017Y139500D01*
X-52017Y142833D01*
G01X-49750Y141750D02*
X-47083D01*
X-47333Y142333D01*
X-47750Y142667D01*
X-48333Y142833D01*
X-48917Y142750D01*
X-49417Y142500D01*
X-49750Y141917D01*
X-49917Y141417D01*
Y140917D01*
X-49750Y140417D01*
X-49333Y139917D01*
X-48833Y139583D01*
X-48250Y139500D01*
X-47667Y139667D01*
X-47083Y140167D01*
G01X-41400Y144500D02*
Y139500D01*
G01Y140250D02*
X-41733Y139833D01*
X-42233Y139583D01*
X-42817Y139500D01*
X-43483Y139667D01*
X-43983Y140083D01*
X-44317Y140583D01*
X-44400Y141167D01*
X-44317Y141750D01*
X-43983Y142250D01*
X-43483Y142667D01*
X-42817Y142833D01*
X-42233Y142750D01*
X-41817Y142583D01*
X-41400Y142250D01*
G01X-37467Y138583D02*
X-37133Y139667D01*
G01X-22000Y139500D02*
Y144500D01*
G01Y142000D02*
X-21583Y142500D01*
X-21083Y142750D01*
X-20583Y142833D01*
X-19833Y142667D01*
X-19333Y142333D01*
X-19000Y141750D01*
Y141083D01*
X-19167Y140417D01*
X-19500Y139917D01*
X-20083Y139583D01*
X-20583Y139500D01*
X-21083Y139583D01*
X-21583Y139833D01*
X-22000Y140250D01*
G01X-16317Y142833D02*
Y140500D01*
X-15983Y139917D01*
X-15483Y139583D01*
X-14900Y139500D01*
X-14317Y139583D01*
X-13817Y139917D01*
X-13483Y140500D01*
G01Y139500D02*
Y142833D01*
G01X-9300Y144500D02*
Y139500D01*
G01X-10467Y142833D02*
X-8133D01*
G01X3400Y139500D02*
Y142833D01*
G01Y142250D02*
X3067Y142583D01*
X2567Y142750D01*
X1983Y142833D01*
X1400Y142667D01*
X900Y142333D01*
X567Y141833D01*
X400Y141167D01*
X567Y140500D01*
X900Y140000D01*
X1400Y139667D01*
X1983Y139500D01*
X2567Y139583D01*
X3067Y139833D01*
X3400Y140167D01*
G01X6083Y139500D02*
Y142833D01*
G01Y142000D02*
X6417Y142417D01*
X6917Y142750D01*
X7583Y142833D01*
X8167Y142750D01*
X8667Y142417D01*
X8917Y141833D01*
Y139500D01*
G01X11683D02*
Y142833D01*
G01Y142000D02*
X12017Y142417D01*
X12517Y142750D01*
X13183Y142833D01*
X13767Y142750D01*
X14267Y142417D01*
X14517Y141833D01*
Y139500D01*
G01X17283Y142833D02*
Y140500D01*
X17617Y139917D01*
X18117Y139583D01*
X18700Y139500D01*
X19283Y139583D01*
X19783Y139917D01*
X20117Y140500D01*
G01Y139500D02*
Y142833D01*
G01X25800Y139500D02*
Y142833D01*
G01Y142250D02*
X25467Y142583D01*
X24967Y142750D01*
X24383Y142833D01*
X23800Y142667D01*
X23300Y142333D01*
X22967Y141833D01*
X22800Y141167D01*
X22967Y140500D01*
X23300Y140000D01*
X23800Y139667D01*
X24383Y139500D01*
X24967Y139583D01*
X25467Y139833D01*
X25800Y140167D01*
G01X29900Y139500D02*
Y144500D01*
G01X39933Y139500D02*
Y142833D01*
G01Y142167D02*
X40350Y142500D01*
X40767Y142750D01*
X41350Y142833D01*
X41767Y142750D01*
X42267Y142500D01*
G01X46700Y142833D02*
Y139500D01*
G01Y144167D02*
X46533Y144250D01*
Y144417D01*
X46700Y144500D01*
X46867Y144417D01*
Y144250D01*
X46700Y144167D01*
G01X50883Y139500D02*
Y142833D01*
G01Y142000D02*
X51217Y142417D01*
X51717Y142750D01*
X52383Y142833D01*
X52967Y142750D01*
X53467Y142417D01*
X53717Y141833D01*
Y139500D01*
G01X56733Y138250D02*
X57317Y137917D01*
X57983Y137833D01*
X58567Y137917D01*
X59067Y138333D01*
X59400Y138917D01*
Y142833D01*
G01Y142167D02*
X59067Y142500D01*
X58567Y142750D01*
X57983Y142833D01*
X57317Y142667D01*
X56900Y142333D01*
X56567Y141750D01*
X56400Y141167D01*
X56483Y140667D01*
X56817Y140083D01*
X57317Y139667D01*
X57983Y139500D01*
X58483Y139583D01*
X59067Y139917D01*
X59400Y140250D01*
G01X69100Y144500D02*
Y139500D01*
G01X67933Y142833D02*
X70267D01*
G01X76200Y139500D02*
Y142833D01*
G01Y142250D02*
X75867Y142583D01*
X75367Y142750D01*
X74783Y142833D01*
X74200Y142667D01*
X73700Y142333D01*
X73367Y141833D01*
X73200Y141167D01*
X73367Y140500D01*
X73700Y140000D01*
X74200Y139667D01*
X74783Y139500D01*
X75367Y139583D01*
X75867Y139833D01*
X76200Y140167D01*
G01X78883Y139500D02*
Y142833D01*
G01Y142000D02*
X79217Y142417D01*
X79717Y142750D01*
X80383Y142833D01*
X80967Y142750D01*
X81467Y142417D01*
X81717Y141833D01*
Y139500D01*
G01X84733Y138250D02*
X85317Y137917D01*
X85983Y137833D01*
X86567Y137917D01*
X87067Y138333D01*
X87400Y138917D01*
Y142833D01*
G01Y142167D02*
X87067Y142500D01*
X86567Y142750D01*
X85983Y142833D01*
X85317Y142667D01*
X84900Y142333D01*
X84567Y141750D01*
X84400Y141167D01*
X84483Y140667D01*
X84817Y140083D01*
X85317Y139667D01*
X85983Y139500D01*
X86483Y139583D01*
X87067Y139917D01*
X87400Y140250D01*
G01X90250Y141750D02*
X92917D01*
X92667Y142333D01*
X92250Y142667D01*
X91667Y142833D01*
X91083Y142750D01*
X90583Y142500D01*
X90250Y141917D01*
X90083Y141417D01*
Y140917D01*
X90250Y140417D01*
X90667Y139917D01*
X91167Y139583D01*
X91750Y139500D01*
X92333Y139667D01*
X92917Y140167D01*
G01X95683Y139500D02*
Y142833D01*
G01Y142000D02*
X96017Y142417D01*
X96517Y142750D01*
X97183Y142833D01*
X97767Y142750D01*
X98267Y142417D01*
X98517Y141833D01*
Y139500D01*
G01X104033Y142417D02*
X103450Y142750D01*
X102950Y142833D01*
X102283Y142667D01*
X101783Y142333D01*
X101450Y141750D01*
X101367Y141167D01*
X101450Y140583D01*
X101783Y140083D01*
X102283Y139667D01*
X102950Y139500D01*
X103533Y139667D01*
X104033Y140000D01*
G01X106550Y138000D02*
X107050Y137833D01*
X107717Y138000D01*
X108133Y138333D01*
X108467Y138750D01*
X108967Y140083D01*
X110050Y142833D01*
G01X107383D02*
X108967Y140083D01*
G01X119500Y142833D02*
Y139500D01*
G01Y144167D02*
X119333Y144250D01*
Y144417D01*
X119500Y144500D01*
X119667Y144417D01*
Y144250D01*
X119500Y144167D01*
G01X123850Y140083D02*
X124267Y139750D01*
X124850Y139500D01*
X125350D01*
X125850Y139667D01*
X126183Y139917D01*
X126350Y140250D01*
X126267Y140750D01*
X125933Y141000D01*
X124433Y141500D01*
X124100Y142083D01*
X124267Y142500D01*
X124600Y142750D01*
X125100Y142833D01*
X125600Y142750D01*
X126100Y142500D01*
G01X-185500Y164500D02*
Y159500D01*
G01Y160250D02*
X-185833Y159833D01*
X-186333Y159583D01*
X-186917Y159500D01*
X-187583Y159667D01*
X-188083Y160083D01*
X-188417Y160583D01*
X-188500Y161167D01*
X-188417Y161750D01*
X-188083Y162250D01*
X-187583Y162667D01*
X-186917Y162833D01*
X-186333Y162750D01*
X-185917Y162583D01*
X-185500Y162250D01*
G01X-182650Y161750D02*
X-179983D01*
X-180233Y162333D01*
X-180650Y162667D01*
X-181233Y162833D01*
X-181817Y162750D01*
X-182317Y162500D01*
X-182650Y161917D01*
X-182817Y161417D01*
Y160917D01*
X-182650Y160417D01*
X-182233Y159917D01*
X-181733Y159583D01*
X-181150Y159500D01*
X-180567Y159667D01*
X-179983Y160167D01*
G01X-177300Y157833D02*
Y162833D01*
G01Y162083D02*
X-176883Y162500D01*
X-176467Y162750D01*
X-175800Y162833D01*
X-175217Y162750D01*
X-174633Y162333D01*
X-174383Y161750D01*
X-174300Y161167D01*
X-174383Y160583D01*
X-174633Y160000D01*
X-175133Y159667D01*
X-175800Y159500D01*
X-176383Y159583D01*
X-176967Y159833D01*
X-177300Y160167D01*
G01X-170200Y164500D02*
Y159500D01*
G01X-171367Y162833D02*
X-169033D01*
G01X-166017Y159500D02*
Y164500D01*
G01Y162083D02*
X-165600Y162500D01*
X-165183Y162750D01*
X-164517Y162833D01*
X-164017Y162750D01*
X-163433Y162417D01*
X-163183Y161917D01*
Y159500D01*
G01X-153400Y164500D02*
Y159500D01*
G01X-154567Y162833D02*
X-152233D01*
G01X-147800Y159500D02*
X-148300Y159583D01*
X-148800Y159917D01*
X-149133Y160500D01*
X-149300Y161167D01*
X-149133Y161833D01*
X-148800Y162417D01*
X-148300Y162750D01*
X-147800Y162833D01*
X-147300Y162750D01*
X-146800Y162417D01*
X-146467Y161833D01*
X-146383Y161167D01*
X-146467Y160500D01*
X-146800Y159917D01*
X-147300Y159583D01*
X-147800Y159500D01*
G01X-142200D02*
Y164500D01*
G01X-137850Y161750D02*
X-135183D01*
X-135433Y162333D01*
X-135850Y162667D01*
X-136433Y162833D01*
X-137017Y162750D01*
X-137517Y162500D01*
X-137850Y161917D01*
X-138017Y161417D01*
Y160917D01*
X-137850Y160417D01*
X-137433Y159917D01*
X-136933Y159583D01*
X-136350Y159500D01*
X-135767Y159667D01*
X-135183Y160167D01*
G01X-132167Y159500D02*
Y162833D01*
G01Y162167D02*
X-131750Y162500D01*
X-131333Y162750D01*
X-130750Y162833D01*
X-130333Y162750D01*
X-129833Y162500D01*
G01X-123900Y159500D02*
Y162833D01*
G01Y162250D02*
X-124233Y162583D01*
X-124733Y162750D01*
X-125317Y162833D01*
X-125900Y162667D01*
X-126400Y162333D01*
X-126733Y161833D01*
X-126900Y161167D01*
X-126733Y160500D01*
X-126400Y160000D01*
X-125900Y159667D01*
X-125317Y159500D01*
X-124733Y159583D01*
X-124233Y159833D01*
X-123900Y160167D01*
G01X-121217Y159500D02*
Y162833D01*
G01Y162000D02*
X-120883Y162417D01*
X-120383Y162750D01*
X-119717Y162833D01*
X-119133Y162750D01*
X-118633Y162417D01*
X-118383Y161833D01*
Y159500D01*
G01X-112867Y162417D02*
X-113450Y162750D01*
X-113950Y162833D01*
X-114617Y162667D01*
X-115117Y162333D01*
X-115450Y161750D01*
X-115533Y161167D01*
X-115450Y160583D01*
X-115117Y160083D01*
X-114617Y159667D01*
X-113950Y159500D01*
X-113367Y159667D01*
X-112867Y160000D01*
G01X-109850Y161750D02*
X-107183D01*
X-107433Y162333D01*
X-107850Y162667D01*
X-108433Y162833D01*
X-109017Y162750D01*
X-109517Y162500D01*
X-109850Y161917D01*
X-110017Y161417D01*
Y160917D01*
X-109850Y160417D01*
X-109433Y159917D01*
X-108933Y159583D01*
X-108350Y159500D01*
X-107767Y159667D01*
X-107183Y160167D01*
G01X-187750Y180500D02*
Y185500D01*
G01X-184250D02*
Y180500D01*
G01Y183000D02*
X-187750D01*
G01X-180400Y180500D02*
X-180900Y180583D01*
X-181400Y180917D01*
X-181733Y181500D01*
X-181900Y182167D01*
X-181733Y182833D01*
X-181400Y183417D01*
X-180900Y183750D01*
X-180400Y183833D01*
X-179900Y183750D01*
X-179400Y183417D01*
X-179067Y182833D01*
X-178983Y182167D01*
X-179067Y181500D01*
X-179400Y180917D01*
X-179900Y180583D01*
X-180400Y180500D01*
G01X-174800D02*
Y185500D01*
G01X-170450Y182750D02*
X-167783D01*
X-168033Y183333D01*
X-168450Y183667D01*
X-169033Y183833D01*
X-169617Y183750D01*
X-170117Y183500D01*
X-170450Y182917D01*
X-170617Y182417D01*
Y181917D01*
X-170450Y181417D01*
X-170033Y180917D01*
X-169533Y180583D01*
X-168950Y180500D01*
X-168367Y180667D01*
X-167783Y181167D01*
G01X-160500Y185500D02*
X-159333Y180500D01*
X-158000Y185500D01*
X-156667Y180500D01*
X-155500Y185500D01*
G01X-150900Y180500D02*
Y183833D01*
G01Y183250D02*
X-151233Y183583D01*
X-151733Y183750D01*
X-152317Y183833D01*
X-152900Y183667D01*
X-153400Y183333D01*
X-153733Y182833D01*
X-153900Y182167D01*
X-153733Y181500D01*
X-153400Y181000D01*
X-152900Y180667D01*
X-152317Y180500D01*
X-151733Y180583D01*
X-151233Y180833D01*
X-150900Y181167D01*
G01X-146800Y180500D02*
Y185500D01*
G01X-141200Y180500D02*
Y185500D01*
G01X-131667Y180500D02*
Y185500D01*
X-129583D01*
X-128917Y185250D01*
X-128500Y184917D01*
X-128333Y184250D01*
X-128500Y183583D01*
X-129000Y183167D01*
X-129583Y182917D01*
X-131667D01*
G01X-129583D02*
X-128333Y180500D01*
G01X-124400D02*
X-124900Y180583D01*
X-125400Y180917D01*
X-125733Y181500D01*
X-125900Y182167D01*
X-125733Y182833D01*
X-125400Y183417D01*
X-124900Y183750D01*
X-124400Y183833D01*
X-123900Y183750D01*
X-123400Y183417D01*
X-123067Y182833D01*
X-122983Y182167D01*
X-123067Y181500D01*
X-123400Y180917D01*
X-123900Y180583D01*
X-124400Y180500D01*
G01X-120217Y183833D02*
Y181500D01*
X-119883Y180917D01*
X-119383Y180583D01*
X-118800Y180500D01*
X-118217Y180583D01*
X-117717Y180917D01*
X-117383Y181500D01*
G01Y180500D02*
Y183833D01*
G01X-114367Y179250D02*
X-113783Y178917D01*
X-113117Y178833D01*
X-112533Y178917D01*
X-112033Y179333D01*
X-111700Y179917D01*
Y183833D01*
G01Y183167D02*
X-112033Y183500D01*
X-112533Y183750D01*
X-113117Y183833D01*
X-113783Y183667D01*
X-114200Y183333D01*
X-114533Y182750D01*
X-114700Y182167D01*
X-114617Y181667D01*
X-114283Y181083D01*
X-113783Y180667D01*
X-113117Y180500D01*
X-112617Y180583D01*
X-112033Y180917D01*
X-111700Y181250D01*
G01X-109017Y180500D02*
Y185500D01*
G01Y183083D02*
X-108600Y183500D01*
X-108183Y183750D01*
X-107517Y183833D01*
X-107017Y183750D01*
X-106433Y183417D01*
X-106183Y182917D01*
Y180500D01*
G01X-103417D02*
Y183833D01*
G01Y183000D02*
X-103083Y183417D01*
X-102583Y183750D01*
X-101917Y183833D01*
X-101333Y183750D01*
X-100833Y183417D01*
X-100583Y182833D01*
Y180500D01*
G01X-97650Y182750D02*
X-94983D01*
X-95233Y183333D01*
X-95650Y183667D01*
X-96233Y183833D01*
X-96817Y183750D01*
X-97317Y183500D01*
X-97650Y182917D01*
X-97817Y182417D01*
Y181917D01*
X-97650Y181417D01*
X-97233Y180917D01*
X-96733Y180583D01*
X-96150Y180500D01*
X-95567Y180667D01*
X-94983Y181167D01*
G01X-92050Y181083D02*
X-91633Y180750D01*
X-91050Y180500D01*
X-90550D01*
X-90050Y180667D01*
X-89717Y180917D01*
X-89550Y181250D01*
X-89633Y181750D01*
X-89967Y182000D01*
X-91467Y182500D01*
X-91800Y183083D01*
X-91633Y183500D01*
X-91300Y183750D01*
X-90800Y183833D01*
X-90300Y183750D01*
X-89800Y183500D01*
G01X-86450Y181083D02*
X-86033Y180750D01*
X-85450Y180500D01*
X-84950D01*
X-84450Y180667D01*
X-84117Y180917D01*
X-83950Y181250D01*
X-84033Y181750D01*
X-84367Y182000D01*
X-85867Y182500D01*
X-86200Y183083D01*
X-86033Y183500D01*
X-85700Y183750D01*
X-85200Y183833D01*
X-84700Y183750D01*
X-84200Y183500D01*
G01X-186000Y197000D02*
X-186667Y197083D01*
X-187250Y197417D01*
X-187750Y197917D01*
X-188083Y198500D01*
X-188250Y199167D01*
Y199833D01*
X-188083Y200500D01*
X-187750Y201083D01*
X-187250Y201583D01*
X-186667Y201917D01*
X-186000Y202000D01*
X-185333Y201917D01*
X-184750Y201583D01*
X-184250Y201083D01*
X-183917Y200500D01*
X-183750Y199833D01*
Y199167D01*
X-183917Y198500D01*
X-184250Y197917D01*
X-184750Y197417D01*
X-185333Y197083D01*
X-186000Y197000D01*
G01X-180400Y202000D02*
Y197000D01*
G01X-181567Y200333D02*
X-179233D01*
G01X-176217Y197000D02*
Y202000D01*
G01Y199583D02*
X-175800Y200000D01*
X-175383Y200250D01*
X-174717Y200333D01*
X-174217Y200250D01*
X-173633Y199917D01*
X-173383Y199417D01*
Y197000D01*
G01X-170450Y199250D02*
X-167783D01*
X-168033Y199833D01*
X-168450Y200167D01*
X-169033Y200333D01*
X-169617Y200250D01*
X-170117Y200000D01*
X-170450Y199417D01*
X-170617Y198917D01*
Y198417D01*
X-170450Y197917D01*
X-170033Y197417D01*
X-169533Y197083D01*
X-168950Y197000D01*
X-168367Y197167D01*
X-167783Y197667D01*
G01X-164767Y197000D02*
Y200333D01*
G01Y199667D02*
X-164350Y200000D01*
X-163933Y200250D01*
X-163350Y200333D01*
X-162933Y200250D01*
X-162433Y200000D01*
G01X-159250Y197583D02*
X-158833Y197250D01*
X-158250Y197000D01*
X-157750D01*
X-157250Y197167D01*
X-156917Y197417D01*
X-156750Y197750D01*
X-156833Y198250D01*
X-157167Y198500D01*
X-158667Y199000D01*
X-159000Y199583D01*
X-158833Y200000D01*
X-158500Y200250D01*
X-158000Y200333D01*
X-157500Y200250D01*
X-157000Y200000D01*
G01X-147217Y195333D02*
X-148050Y196167D01*
X-148467Y197000D01*
Y200333D01*
X-148050Y201167D01*
X-147217Y202000D01*
G01X-141200Y197000D02*
Y202000D01*
G01X-135600Y200333D02*
Y197000D01*
G01Y201667D02*
X-135767Y201750D01*
Y201917D01*
X-135600Y202000D01*
X-135433Y201917D01*
Y201750D01*
X-135600Y201667D01*
G01X-131417Y197000D02*
Y202000D01*
G01X-128750Y200333D02*
X-131417Y198417D01*
G01X-130333Y199167D02*
X-128583Y197000D01*
G01X-125650Y199250D02*
X-122983D01*
X-123233Y199833D01*
X-123650Y200167D01*
X-124233Y200333D01*
X-124817Y200250D01*
X-125317Y200000D01*
X-125650Y199417D01*
X-125817Y198917D01*
Y198417D01*
X-125650Y197917D01*
X-125233Y197417D01*
X-124733Y197083D01*
X-124150Y197000D01*
X-123567Y197167D01*
X-122983Y197667D01*
G01X-114450Y199250D02*
X-111783D01*
X-112033Y199833D01*
X-112450Y200167D01*
X-113033Y200333D01*
X-113617Y200250D01*
X-114117Y200000D01*
X-114450Y199417D01*
X-114617Y198917D01*
Y198417D01*
X-114450Y197917D01*
X-114033Y197417D01*
X-113533Y197083D01*
X-112950Y197000D01*
X-112367Y197167D01*
X-111783Y197667D01*
G01X-107600Y197000D02*
Y202000D01*
G01X-102000Y197000D02*
Y202000D01*
G01X-96400Y200333D02*
Y197000D01*
G01Y201667D02*
X-96567Y201750D01*
Y201917D01*
X-96400Y202000D01*
X-96233Y201917D01*
Y201750D01*
X-96400Y201667D01*
G01X-92300Y195333D02*
Y200333D01*
G01Y199583D02*
X-91883Y200000D01*
X-91467Y200250D01*
X-90800Y200333D01*
X-90217Y200250D01*
X-89633Y199833D01*
X-89383Y199250D01*
X-89300Y198667D01*
X-89383Y198083D01*
X-89633Y197500D01*
X-90133Y197167D01*
X-90800Y197000D01*
X-91383Y197083D01*
X-91967Y197333D01*
X-92300Y197667D01*
G01X-86450Y197583D02*
X-86033Y197250D01*
X-85450Y197000D01*
X-84950D01*
X-84450Y197167D01*
X-84117Y197417D01*
X-83950Y197750D01*
X-84033Y198250D01*
X-84367Y198500D01*
X-85867Y199000D01*
X-86200Y199583D01*
X-86033Y200000D01*
X-85700Y200250D01*
X-85200Y200333D01*
X-84700Y200250D01*
X-84200Y200000D01*
G01X-80850Y199250D02*
X-78183D01*
X-78433Y199833D01*
X-78850Y200167D01*
X-79433Y200333D01*
X-80017Y200250D01*
X-80517Y200000D01*
X-80850Y199417D01*
X-81017Y198917D01*
Y198417D01*
X-80850Y197917D01*
X-80433Y197417D01*
X-79933Y197083D01*
X-79350Y197000D01*
X-78767Y197167D01*
X-78183Y197667D01*
G01X-66900Y197000D02*
Y200333D01*
G01Y199750D02*
X-67233Y200083D01*
X-67733Y200250D01*
X-68317Y200333D01*
X-68900Y200167D01*
X-69400Y199833D01*
X-69733Y199333D01*
X-69900Y198667D01*
X-69733Y198000D01*
X-69400Y197500D01*
X-68900Y197167D01*
X-68317Y197000D01*
X-67733Y197083D01*
X-67233Y197333D01*
X-66900Y197667D01*
G01X-64217Y197000D02*
Y200333D01*
G01Y199500D02*
X-63883Y199917D01*
X-63383Y200250D01*
X-62717Y200333D01*
X-62133Y200250D01*
X-61633Y199917D01*
X-61383Y199333D01*
Y197000D01*
G01X-55700Y202000D02*
Y197000D01*
G01Y197750D02*
X-56033Y197333D01*
X-56533Y197083D01*
X-57117Y197000D01*
X-57783Y197167D01*
X-58283Y197583D01*
X-58617Y198083D01*
X-58700Y198667D01*
X-58617Y199250D01*
X-58283Y199750D01*
X-57783Y200167D01*
X-57117Y200333D01*
X-56533Y200250D01*
X-56117Y200083D01*
X-55700Y199750D01*
G01X-46000Y197000D02*
X-46500Y197083D01*
X-47000Y197417D01*
X-47333Y198000D01*
X-47500Y198667D01*
X-47333Y199333D01*
X-47000Y199917D01*
X-46500Y200250D01*
X-46000Y200333D01*
X-45500Y200250D01*
X-45000Y199917D01*
X-44667Y199333D01*
X-44583Y198667D01*
X-44667Y198000D01*
X-45000Y197417D01*
X-45500Y197083D01*
X-46000Y197000D01*
G01X-40400Y202000D02*
Y197000D01*
G01X-41567Y200333D02*
X-39233D01*
G01X-36217Y197000D02*
Y202000D01*
G01Y199583D02*
X-35800Y200000D01*
X-35383Y200250D01*
X-34717Y200333D01*
X-34217Y200250D01*
X-33633Y199917D01*
X-33383Y199417D01*
Y197000D01*
G01X-30450Y199250D02*
X-27783D01*
X-28033Y199833D01*
X-28450Y200167D01*
X-29033Y200333D01*
X-29617Y200250D01*
X-30117Y200000D01*
X-30450Y199417D01*
X-30617Y198917D01*
Y198417D01*
X-30450Y197917D01*
X-30033Y197417D01*
X-29533Y197083D01*
X-28950Y197000D01*
X-28367Y197167D01*
X-27783Y197667D01*
G01X-24767Y197000D02*
Y200333D01*
G01Y199667D02*
X-24350Y200000D01*
X-23933Y200250D01*
X-23350Y200333D01*
X-22933Y200250D01*
X-22433Y200000D01*
G01X-19250Y197583D02*
X-18833Y197250D01*
X-18250Y197000D01*
X-17750D01*
X-17250Y197167D01*
X-16917Y197417D01*
X-16750Y197750D01*
X-16833Y198250D01*
X-17167Y198500D01*
X-18667Y199000D01*
X-19000Y199583D01*
X-18833Y200000D01*
X-18500Y200250D01*
X-18000Y200333D01*
X-17500Y200250D01*
X-17000Y200000D01*
G01X-11983Y195333D02*
X-11150Y196167D01*
X-10733Y197000D01*
Y200333D01*
X-11150Y201167D01*
X-11983Y202000D01*
G01X-187667Y212000D02*
Y217000D01*
X-185667D01*
X-185000Y216750D01*
X-184500Y216167D01*
X-184333Y215500D01*
X-184500Y214833D01*
X-184917Y214333D01*
X-185667Y214083D01*
X-187667D01*
G01X-180400Y217000D02*
Y212000D01*
G01X-182317Y217000D02*
X-178483D01*
G01X-176550Y212000D02*
Y217000D01*
G01X-173050D02*
Y212000D01*
G01Y214500D02*
X-176550D01*
G01X-170700Y211833D02*
X-167700Y217000D01*
G01X-165517Y212000D02*
Y217000D01*
X-161683Y212000D01*
Y217000D01*
G01X-159667Y212000D02*
Y217000D01*
X-157667D01*
X-157000Y216750D01*
X-156500Y216167D01*
X-156333Y215500D01*
X-156500Y214833D01*
X-156917Y214333D01*
X-157667Y214083D01*
X-159667D01*
G01X-152400Y217000D02*
Y212000D01*
G01X-154317Y217000D02*
X-150483D01*
G01X-148550Y212000D02*
Y217000D01*
G01X-145050D02*
Y212000D01*
G01Y214500D02*
X-148550D01*
G01X-137267Y212000D02*
X-133933Y213667D01*
X-137267Y215333D01*
G01X-131083Y212917D02*
X-128917D01*
G01Y214417D02*
X-131083D01*
G01X-126233Y212750D02*
X-125733Y212333D01*
X-125150Y212083D01*
X-124400Y212000D01*
X-123650Y212167D01*
X-123067Y212500D01*
X-122650Y213083D01*
X-122567Y213750D01*
X-122733Y214417D01*
X-123150Y214833D01*
X-123733Y215167D01*
X-124317Y215250D01*
X-124900Y215167D01*
X-125650Y214833D01*
X-125400Y217000D01*
X-123150D01*
G01X-115700Y212000D02*
Y215333D01*
G01Y214417D02*
X-115450Y214833D01*
X-115033Y215167D01*
X-114450Y215333D01*
X-113867Y215167D01*
X-113450Y214833D01*
X-113200Y214417D01*
Y212000D01*
G01Y214417D02*
X-112950Y214833D01*
X-112533Y215167D01*
X-111950Y215333D01*
X-111367Y215167D01*
X-110950Y214833D01*
X-110700Y214333D01*
Y212000D01*
G01X-110100D02*
Y215333D01*
G01Y214417D02*
X-109850Y214833D01*
X-109433Y215167D01*
X-108850Y215333D01*
X-108267Y215167D01*
X-107850Y214833D01*
X-107600Y214417D01*
Y212000D01*
G01Y214417D02*
X-107350Y214833D01*
X-106933Y215167D01*
X-106350Y215333D01*
X-105767Y215167D01*
X-105350Y214833D01*
X-105100Y214333D01*
Y212000D01*
G01X-187917Y225500D02*
Y230500D01*
X-184083Y225500D01*
Y230500D01*
G01X-182067Y225500D02*
Y230500D01*
X-180067D01*
X-179400Y230250D01*
X-178900Y229667D01*
X-178733Y229000D01*
X-178900Y228333D01*
X-179317Y227833D01*
X-180067Y227583D01*
X-182067D01*
G01X-174800Y230500D02*
Y225500D01*
G01X-176717Y230500D02*
X-172883D01*
G01X-170950Y225500D02*
Y230500D01*
G01X-167450D02*
Y225500D01*
G01Y228000D02*
X-170950D01*
G01X-159750Y226167D02*
X-159083Y225750D01*
X-158333Y225500D01*
X-157667D01*
X-157000Y225750D01*
X-156500Y226167D01*
X-156250Y226750D01*
X-156417Y227333D01*
X-156833Y227833D01*
X-157583Y228167D01*
X-158583Y228333D01*
X-159167Y228667D01*
X-159417Y229250D01*
X-159250Y229833D01*
X-158833Y230250D01*
X-158250Y230500D01*
X-157667D01*
X-157083Y230333D01*
X-156583Y229917D01*
G01X-152400Y228833D02*
Y225500D01*
G01Y230167D02*
X-152567Y230250D01*
Y230417D01*
X-152400Y230500D01*
X-152233Y230417D01*
Y230250D01*
X-152400Y230167D01*
G01X-148050Y228833D02*
X-145550D01*
X-148050Y225500D01*
X-145550D01*
G01X-142450Y227750D02*
X-139783D01*
X-140033Y228333D01*
X-140450Y228667D01*
X-141033Y228833D01*
X-141617Y228750D01*
X-142117Y228500D01*
X-142450Y227917D01*
X-142617Y227417D01*
Y226917D01*
X-142450Y226417D01*
X-142033Y225917D01*
X-141533Y225583D01*
X-140950Y225500D01*
X-140367Y225667D01*
X-139783Y226167D01*
G01X-131833Y226500D02*
X-131333Y225917D01*
X-130667Y225583D01*
X-129917Y225500D01*
X-129250Y225583D01*
X-128583Y226000D01*
X-128167Y226500D01*
X-128083Y227000D01*
X-128250Y227583D01*
X-128833Y228000D01*
X-129417Y228167D01*
X-130167D01*
G01X-129417D02*
X-128917Y228417D01*
X-128500Y228833D01*
X-128333Y229333D01*
X-128500Y229833D01*
X-128917Y230250D01*
X-129667Y230500D01*
X-130417Y230417D01*
X-131167Y230083D01*
G01X-124400Y225333D02*
X-124567Y225417D01*
Y225583D01*
X-124400Y225667D01*
X-124233Y225583D01*
Y225417D01*
X-124400Y225333D01*
G01X-120633Y226250D02*
X-120133Y225833D01*
X-119550Y225583D01*
X-118800Y225500D01*
X-118050Y225667D01*
X-117467Y226000D01*
X-117050Y226583D01*
X-116967Y227250D01*
X-117133Y227917D01*
X-117550Y228333D01*
X-118133Y228667D01*
X-118717Y228750D01*
X-119300Y228667D01*
X-120050Y228333D01*
X-119800Y230500D01*
X-117550D01*
G01X-115033Y226250D02*
X-114533Y225833D01*
X-113950Y225583D01*
X-113200Y225500D01*
X-112450Y225667D01*
X-111867Y226000D01*
X-111450Y226583D01*
X-111367Y227250D01*
X-111533Y227917D01*
X-111950Y228333D01*
X-112533Y228667D01*
X-113117Y228750D01*
X-113700Y228667D01*
X-114450Y228333D01*
X-114200Y230500D01*
X-111950D01*
G01X-110100Y225500D02*
Y228833D01*
G01Y227917D02*
X-109850Y228333D01*
X-109433Y228667D01*
X-108850Y228833D01*
X-108267Y228667D01*
X-107850Y228333D01*
X-107600Y227917D01*
Y225500D01*
G01Y227917D02*
X-107350Y228333D01*
X-106933Y228667D01*
X-106350Y228833D01*
X-105767Y228667D01*
X-105350Y228333D01*
X-105100Y227833D01*
Y225500D01*
G01X-104500D02*
Y228833D01*
G01Y227917D02*
X-104250Y228333D01*
X-103833Y228667D01*
X-103250Y228833D01*
X-102667Y228667D01*
X-102250Y228333D01*
X-102000Y227917D01*
Y225500D01*
G01Y227917D02*
X-101750Y228333D01*
X-101333Y228667D01*
X-100750Y228833D01*
X-100167Y228667D01*
X-99750Y228333D01*
X-99500Y227833D01*
Y225500D01*
G01X-187917Y240500D02*
Y245500D01*
X-184083Y240500D01*
Y245500D01*
G01X-182067Y240500D02*
Y245500D01*
X-180067D01*
X-179400Y245250D01*
X-178900Y244667D01*
X-178733Y244000D01*
X-178900Y243333D01*
X-179317Y242833D01*
X-180067Y242583D01*
X-182067D01*
G01X-174800Y245500D02*
Y240500D01*
G01X-176717Y245500D02*
X-172883D01*
G01X-170950Y240500D02*
Y245500D01*
G01X-167450D02*
Y240500D01*
G01Y243000D02*
X-170950D01*
G01X-159750Y241167D02*
X-159083Y240750D01*
X-158333Y240500D01*
X-157667D01*
X-157000Y240750D01*
X-156500Y241167D01*
X-156250Y241750D01*
X-156417Y242333D01*
X-156833Y242833D01*
X-157583Y243167D01*
X-158583Y243333D01*
X-159167Y243667D01*
X-159417Y244250D01*
X-159250Y244833D01*
X-158833Y245250D01*
X-158250Y245500D01*
X-157667D01*
X-157083Y245333D01*
X-156583Y244917D01*
G01X-152400Y243833D02*
Y240500D01*
G01Y245167D02*
X-152567Y245250D01*
Y245417D01*
X-152400Y245500D01*
X-152233Y245417D01*
Y245250D01*
X-152400Y245167D01*
G01X-148050Y243833D02*
X-145550D01*
X-148050Y240500D01*
X-145550D01*
G01X-142450Y242750D02*
X-139783D01*
X-140033Y243333D01*
X-140450Y243667D01*
X-141033Y243833D01*
X-141617Y243750D01*
X-142117Y243500D01*
X-142450Y242917D01*
X-142617Y242417D01*
Y241917D01*
X-142450Y241417D01*
X-142033Y240917D01*
X-141533Y240583D01*
X-140950Y240500D01*
X-140367Y240667D01*
X-139783Y241167D01*
G01X-133933Y240500D02*
X-137267Y242167D01*
X-133933Y243833D01*
G01X-126233Y241250D02*
X-125733Y240833D01*
X-125150Y240583D01*
X-124400Y240500D01*
X-123650Y240667D01*
X-123067Y241000D01*
X-122650Y241583D01*
X-122567Y242250D01*
X-122733Y242917D01*
X-123150Y243333D01*
X-123733Y243667D01*
X-124317Y243750D01*
X-124900Y243667D01*
X-125650Y243333D01*
X-125400Y245500D01*
X-123150D01*
G01X-121300Y240500D02*
Y243833D01*
G01Y242917D02*
X-121050Y243333D01*
X-120633Y243667D01*
X-120050Y243833D01*
X-119467Y243667D01*
X-119050Y243333D01*
X-118800Y242917D01*
Y240500D01*
G01Y242917D02*
X-118550Y243333D01*
X-118133Y243667D01*
X-117550Y243833D01*
X-116967Y243667D01*
X-116550Y243333D01*
X-116300Y242833D01*
Y240500D01*
G01X-115700D02*
Y243833D01*
G01Y242917D02*
X-115450Y243333D01*
X-115033Y243667D01*
X-114450Y243833D01*
X-113867Y243667D01*
X-113450Y243333D01*
X-113200Y242917D01*
Y240500D01*
G01Y242917D02*
X-112950Y243333D01*
X-112533Y243667D01*
X-111950Y243833D01*
X-111367Y243667D01*
X-110950Y243333D01*
X-110700Y242833D01*
Y240500D01*
G01X-187833Y262000D02*
Y258417D01*
X-187500Y257667D01*
X-186833Y257167D01*
X-186000Y257000D01*
X-185167Y257167D01*
X-184500Y257667D01*
X-184167Y258417D01*
Y262000D01*
G01X-181817Y257000D02*
Y260333D01*
G01Y259500D02*
X-181483Y259917D01*
X-180983Y260250D01*
X-180317Y260333D01*
X-179733Y260250D01*
X-179233Y259917D01*
X-178983Y259333D01*
Y257000D01*
G01X-175883Y258667D02*
X-173717D01*
G01X-170700Y255333D02*
Y260333D01*
G01Y259583D02*
X-170283Y260000D01*
X-169867Y260250D01*
X-169200Y260333D01*
X-168617Y260250D01*
X-168033Y259833D01*
X-167783Y259250D01*
X-167700Y258667D01*
X-167783Y258083D01*
X-168033Y257500D01*
X-168533Y257167D01*
X-169200Y257000D01*
X-169783Y257083D01*
X-170367Y257333D01*
X-170700Y257667D01*
G01X-163600Y257000D02*
Y262000D01*
G01X-159417Y260333D02*
Y258000D01*
X-159083Y257417D01*
X-158583Y257083D01*
X-158000Y257000D01*
X-157417Y257083D01*
X-156917Y257417D01*
X-156583Y258000D01*
G01Y257000D02*
Y260333D01*
G01X-153567Y255750D02*
X-152983Y255417D01*
X-152317Y255333D01*
X-151733Y255417D01*
X-151233Y255833D01*
X-150900Y256417D01*
Y260333D01*
G01Y259667D02*
X-151233Y260000D01*
X-151733Y260250D01*
X-152317Y260333D01*
X-152983Y260167D01*
X-153400Y259833D01*
X-153733Y259250D01*
X-153900Y258667D01*
X-153817Y258167D01*
X-153483Y257583D01*
X-152983Y257167D01*
X-152317Y257000D01*
X-151817Y257083D01*
X-151233Y257417D01*
X-150900Y257750D01*
G01X-147967Y255750D02*
X-147383Y255417D01*
X-146717Y255333D01*
X-146133Y255417D01*
X-145633Y255833D01*
X-145300Y256417D01*
Y260333D01*
G01Y259667D02*
X-145633Y260000D01*
X-146133Y260250D01*
X-146717Y260333D01*
X-147383Y260167D01*
X-147800Y259833D01*
X-148133Y259250D01*
X-148300Y258667D01*
X-148217Y258167D01*
X-147883Y257583D01*
X-147383Y257167D01*
X-146717Y257000D01*
X-146217Y257083D01*
X-145633Y257417D01*
X-145300Y257750D01*
G01X-142450Y259250D02*
X-139783D01*
X-140033Y259833D01*
X-140450Y260167D01*
X-141033Y260333D01*
X-141617Y260250D01*
X-142117Y260000D01*
X-142450Y259417D01*
X-142617Y258917D01*
Y258417D01*
X-142450Y257917D01*
X-142033Y257417D01*
X-141533Y257083D01*
X-140950Y257000D01*
X-140367Y257167D01*
X-139783Y257667D01*
G01X-134100Y262000D02*
Y257000D01*
G01Y257750D02*
X-134433Y257333D01*
X-134933Y257083D01*
X-135517Y257000D01*
X-136183Y257167D01*
X-136683Y257583D01*
X-137017Y258083D01*
X-137100Y258667D01*
X-137017Y259250D01*
X-136683Y259750D01*
X-136183Y260167D01*
X-135517Y260333D01*
X-134933Y260250D01*
X-134517Y260083D01*
X-134100Y259750D01*
G01X-126067Y257000D02*
Y262000D01*
X-124067D01*
X-123400Y261750D01*
X-122900Y261167D01*
X-122733Y260500D01*
X-122900Y259833D01*
X-123317Y259333D01*
X-124067Y259083D01*
X-126067D01*
G01X-118800Y262000D02*
Y257000D01*
G01X-120717Y262000D02*
X-116883D01*
G01X-114950Y257000D02*
Y262000D01*
G01X-111450D02*
Y257000D01*
G01Y259500D02*
X-114950D01*
G01X-102417Y255333D02*
X-103250Y256167D01*
X-103667Y257000D01*
Y260333D01*
X-103250Y261167D01*
X-102417Y262000D01*
G01X-98150Y257000D02*
Y262000D01*
G01X-94650D02*
Y257000D01*
G01Y259500D02*
X-98150D01*
G01X-90800Y257000D02*
X-91300Y257083D01*
X-91800Y257417D01*
X-92133Y258000D01*
X-92300Y258667D01*
X-92133Y259333D01*
X-91800Y259917D01*
X-91300Y260250D01*
X-90800Y260333D01*
X-90300Y260250D01*
X-89800Y259917D01*
X-89467Y259333D01*
X-89383Y258667D01*
X-89467Y258000D01*
X-89800Y257417D01*
X-90300Y257083D01*
X-90800Y257000D01*
G01X-85200D02*
Y262000D01*
G01X-80850Y259250D02*
X-78183D01*
X-78433Y259833D01*
X-78850Y260167D01*
X-79433Y260333D01*
X-80017Y260250D01*
X-80517Y260000D01*
X-80850Y259417D01*
X-81017Y258917D01*
Y258417D01*
X-80850Y257917D01*
X-80433Y257417D01*
X-79933Y257083D01*
X-79350Y257000D01*
X-78767Y257167D01*
X-78183Y257667D01*
G01X-70150D02*
X-69483Y257250D01*
X-68733Y257000D01*
X-68067D01*
X-67400Y257250D01*
X-66900Y257667D01*
X-66650Y258250D01*
X-66817Y258833D01*
X-67233Y259333D01*
X-67983Y259667D01*
X-68983Y259833D01*
X-69567Y260167D01*
X-69817Y260750D01*
X-69650Y261333D01*
X-69233Y261750D01*
X-68650Y262000D01*
X-68067D01*
X-67483Y261833D01*
X-66983Y261417D01*
G01X-62800Y260333D02*
Y257000D01*
G01Y261667D02*
X-62967Y261750D01*
Y261917D01*
X-62800Y262000D01*
X-62633Y261917D01*
Y261750D01*
X-62800Y261667D01*
G01X-58450Y260333D02*
X-55950D01*
X-58450Y257000D01*
X-55950D01*
G01X-52850Y259250D02*
X-50183D01*
X-50433Y259833D01*
X-50850Y260167D01*
X-51433Y260333D01*
X-52017Y260250D01*
X-52517Y260000D01*
X-52850Y259417D01*
X-53017Y258917D01*
Y258417D01*
X-52850Y257917D01*
X-52433Y257417D01*
X-51933Y257083D01*
X-51350Y257000D01*
X-50767Y257167D01*
X-50183Y257667D01*
G01X-44333Y257000D02*
X-47667Y258667D01*
X-44333Y260333D01*
G01X-40400Y257000D02*
Y262000D01*
X-41400Y261000D01*
G01Y257000D02*
X-39400D01*
G01X-36217Y257583D02*
X-35633Y257167D01*
X-34967Y257000D01*
X-34300Y257167D01*
X-33717Y257667D01*
X-33300Y258417D01*
X-33133Y259167D01*
Y260083D01*
X-33300Y260833D01*
X-33717Y261500D01*
X-34217Y261833D01*
X-34800Y262000D01*
X-35467Y261833D01*
X-35967Y261500D01*
X-36300Y261000D01*
X-36467Y260333D01*
X-36300Y259750D01*
X-35883Y259167D01*
X-35383Y258833D01*
X-34800Y258750D01*
X-34133Y258917D01*
X-33633Y259333D01*
X-33133Y260083D01*
G01X-29367Y257000D02*
X-29200Y258083D01*
X-28950Y259000D01*
X-28617Y259833D01*
X-28200Y260750D01*
X-27533Y262000D01*
X-30867D01*
G01X-26100Y257000D02*
Y260333D01*
G01Y259417D02*
X-25850Y259833D01*
X-25433Y260167D01*
X-24850Y260333D01*
X-24267Y260167D01*
X-23850Y259833D01*
X-23600Y259417D01*
Y257000D01*
G01Y259417D02*
X-23350Y259833D01*
X-22933Y260167D01*
X-22350Y260333D01*
X-21767Y260167D01*
X-21350Y259833D01*
X-21100Y259333D01*
Y257000D01*
G01X-18000Y260333D02*
Y257000D01*
G01Y261667D02*
X-18167Y261750D01*
Y261917D01*
X-18000Y262000D01*
X-17833Y261917D01*
Y261750D01*
X-18000Y261667D01*
G01X-12400Y257000D02*
Y262000D01*
G01X-3283Y260333D02*
X-2283Y257000D01*
X-1200Y260333D01*
X-117Y257000D01*
X883Y260333D01*
G01X4400D02*
Y257000D01*
G01Y261667D02*
X4233Y261750D01*
Y261917D01*
X4400Y262000D01*
X4567Y261917D01*
Y261750D01*
X4400Y261667D01*
G01X10000Y262000D02*
Y257000D01*
G01X8833Y260333D02*
X11167D01*
G01X14183Y257000D02*
Y262000D01*
G01Y259583D02*
X14600Y260000D01*
X15017Y260250D01*
X15683Y260333D01*
X16183Y260250D01*
X16767Y259917D01*
X17017Y259417D01*
Y257000D01*
G01X25050D02*
Y262000D01*
G01X28550D02*
Y257000D01*
G01Y259500D02*
X25050D01*
G01X30317Y257000D02*
X32400Y262000D01*
X34483Y257000D01*
G01X33733Y258750D02*
X31067D01*
G01X36250Y257667D02*
X36917Y257250D01*
X37667Y257000D01*
X38333D01*
X39000Y257250D01*
X39500Y257667D01*
X39750Y258250D01*
X39583Y258833D01*
X39167Y259333D01*
X38417Y259667D01*
X37417Y259833D01*
X36833Y260167D01*
X36583Y260750D01*
X36750Y261333D01*
X37167Y261750D01*
X37750Y262000D01*
X38333D01*
X38917Y261833D01*
X39417Y261417D01*
G01X41933Y262000D02*
Y257000D01*
X45267D01*
G01X53300Y255333D02*
Y260333D01*
G01Y259583D02*
X53717Y260000D01*
X54133Y260250D01*
X54800Y260333D01*
X55383Y260250D01*
X55967Y259833D01*
X56217Y259250D01*
X56300Y258667D01*
X56217Y258083D01*
X55967Y257500D01*
X55467Y257167D01*
X54800Y257000D01*
X54217Y257083D01*
X53633Y257333D01*
X53300Y257667D01*
G01X59233Y257000D02*
Y260333D01*
G01Y259667D02*
X59650Y260000D01*
X60067Y260250D01*
X60650Y260333D01*
X61067Y260250D01*
X61567Y260000D01*
G01X66000Y257000D02*
X65500Y257083D01*
X65000Y257417D01*
X64667Y258000D01*
X64500Y258667D01*
X64667Y259333D01*
X65000Y259917D01*
X65500Y260250D01*
X66000Y260333D01*
X66500Y260250D01*
X67000Y259917D01*
X67333Y259333D01*
X67417Y258667D01*
X67333Y258000D01*
X67000Y257417D01*
X66500Y257083D01*
X66000Y257000D01*
G01X73100Y262000D02*
Y257000D01*
G01Y257750D02*
X72767Y257333D01*
X72267Y257083D01*
X71683Y257000D01*
X71017Y257167D01*
X70517Y257583D01*
X70183Y258083D01*
X70100Y258667D01*
X70183Y259250D01*
X70517Y259750D01*
X71017Y260167D01*
X71683Y260333D01*
X72267Y260250D01*
X72683Y260083D01*
X73100Y259750D01*
G01X75783Y260333D02*
Y258000D01*
X76117Y257417D01*
X76617Y257083D01*
X77200Y257000D01*
X77783Y257083D01*
X78283Y257417D01*
X78617Y258000D01*
G01Y257000D02*
Y260333D01*
G01X84133Y259917D02*
X83550Y260250D01*
X83050Y260333D01*
X82383Y260167D01*
X81883Y259833D01*
X81550Y259250D01*
X81467Y258667D01*
X81550Y258083D01*
X81883Y257583D01*
X82383Y257167D01*
X83050Y257000D01*
X83633Y257167D01*
X84133Y257500D01*
G01X88400Y262000D02*
Y257000D01*
G01X87233Y260333D02*
X89567D01*
G01X92750Y257583D02*
X93167Y257250D01*
X93750Y257000D01*
X94250D01*
X94750Y257167D01*
X95083Y257417D01*
X95250Y257750D01*
X95167Y258250D01*
X94833Y258500D01*
X93333Y259000D01*
X93000Y259583D01*
X93167Y260000D01*
X93500Y260250D01*
X94000Y260333D01*
X94500Y260250D01*
X95000Y260000D01*
G01X100017Y255333D02*
X100850Y256167D01*
X101267Y257000D01*
Y260333D01*
X100850Y261167D01*
X100017Y262000D01*
G01X-187833Y277000D02*
Y273417D01*
X-187500Y272667D01*
X-186833Y272167D01*
X-186000Y272000D01*
X-185167Y272167D01*
X-184500Y272667D01*
X-184167Y273417D01*
Y277000D01*
G01X-181817Y272000D02*
Y275333D01*
G01Y274500D02*
X-181483Y274917D01*
X-180983Y275250D01*
X-180317Y275333D01*
X-179733Y275250D01*
X-179233Y274917D01*
X-178983Y274333D01*
Y272000D01*
G01X-175883Y273667D02*
X-173717D01*
G01X-170700Y270333D02*
Y275333D01*
G01Y274583D02*
X-170283Y275000D01*
X-169867Y275250D01*
X-169200Y275333D01*
X-168617Y275250D01*
X-168033Y274833D01*
X-167783Y274250D01*
X-167700Y273667D01*
X-167783Y273083D01*
X-168033Y272500D01*
X-168533Y272167D01*
X-169200Y272000D01*
X-169783Y272083D01*
X-170367Y272333D01*
X-170700Y272667D01*
G01X-163600Y272000D02*
Y277000D01*
G01X-159417Y275333D02*
Y273000D01*
X-159083Y272417D01*
X-158583Y272083D01*
X-158000Y272000D01*
X-157417Y272083D01*
X-156917Y272417D01*
X-156583Y273000D01*
G01Y272000D02*
Y275333D01*
G01X-153567Y270750D02*
X-152983Y270417D01*
X-152317Y270333D01*
X-151733Y270417D01*
X-151233Y270833D01*
X-150900Y271417D01*
Y275333D01*
G01Y274667D02*
X-151233Y275000D01*
X-151733Y275250D01*
X-152317Y275333D01*
X-152983Y275167D01*
X-153400Y274833D01*
X-153733Y274250D01*
X-153900Y273667D01*
X-153817Y273167D01*
X-153483Y272583D01*
X-152983Y272167D01*
X-152317Y272000D01*
X-151817Y272083D01*
X-151233Y272417D01*
X-150900Y272750D01*
G01X-147967Y270750D02*
X-147383Y270417D01*
X-146717Y270333D01*
X-146133Y270417D01*
X-145633Y270833D01*
X-145300Y271417D01*
Y275333D01*
G01Y274667D02*
X-145633Y275000D01*
X-146133Y275250D01*
X-146717Y275333D01*
X-147383Y275167D01*
X-147800Y274833D01*
X-148133Y274250D01*
X-148300Y273667D01*
X-148217Y273167D01*
X-147883Y272583D01*
X-147383Y272167D01*
X-146717Y272000D01*
X-146217Y272083D01*
X-145633Y272417D01*
X-145300Y272750D01*
G01X-142450Y274250D02*
X-139783D01*
X-140033Y274833D01*
X-140450Y275167D01*
X-141033Y275333D01*
X-141617Y275250D01*
X-142117Y275000D01*
X-142450Y274417D01*
X-142617Y273917D01*
Y273417D01*
X-142450Y272917D01*
X-142033Y272417D01*
X-141533Y272083D01*
X-140950Y272000D01*
X-140367Y272167D01*
X-139783Y272667D01*
G01X-134100Y277000D02*
Y272000D01*
G01Y272750D02*
X-134433Y272333D01*
X-134933Y272083D01*
X-135517Y272000D01*
X-136183Y272167D01*
X-136683Y272583D01*
X-137017Y273083D01*
X-137100Y273667D01*
X-137017Y274250D01*
X-136683Y274750D01*
X-136183Y275167D01*
X-135517Y275333D01*
X-134933Y275250D01*
X-134517Y275083D01*
X-134100Y274750D01*
G01X-126067Y272000D02*
Y277000D01*
X-124067D01*
X-123400Y276750D01*
X-122900Y276167D01*
X-122733Y275500D01*
X-122900Y274833D01*
X-123317Y274333D01*
X-124067Y274083D01*
X-126067D01*
G01X-118800Y277000D02*
Y272000D01*
G01X-120717Y277000D02*
X-116883D01*
G01X-114950Y272000D02*
Y277000D01*
G01X-111450D02*
Y272000D01*
G01Y274500D02*
X-114950D01*
G01X-102417Y270333D02*
X-103250Y271167D01*
X-103667Y272000D01*
Y275333D01*
X-103250Y276167D01*
X-102417Y277000D01*
G01X-98150Y272000D02*
Y277000D01*
G01X-94650D02*
Y272000D01*
G01Y274500D02*
X-98150D01*
G01X-90800Y272000D02*
X-91300Y272083D01*
X-91800Y272417D01*
X-92133Y273000D01*
X-92300Y273667D01*
X-92133Y274333D01*
X-91800Y274917D01*
X-91300Y275250D01*
X-90800Y275333D01*
X-90300Y275250D01*
X-89800Y274917D01*
X-89467Y274333D01*
X-89383Y273667D01*
X-89467Y273000D01*
X-89800Y272417D01*
X-90300Y272083D01*
X-90800Y272000D01*
G01X-85200D02*
Y277000D01*
G01X-80850Y274250D02*
X-78183D01*
X-78433Y274833D01*
X-78850Y275167D01*
X-79433Y275333D01*
X-80017Y275250D01*
X-80517Y275000D01*
X-80850Y274417D01*
X-81017Y273917D01*
Y273417D01*
X-80850Y272917D01*
X-80433Y272417D01*
X-79933Y272083D01*
X-79350Y272000D01*
X-78767Y272167D01*
X-78183Y272667D01*
G01X-70150D02*
X-69483Y272250D01*
X-68733Y272000D01*
X-68067D01*
X-67400Y272250D01*
X-66900Y272667D01*
X-66650Y273250D01*
X-66817Y273833D01*
X-67233Y274333D01*
X-67983Y274667D01*
X-68983Y274833D01*
X-69567Y275167D01*
X-69817Y275750D01*
X-69650Y276333D01*
X-69233Y276750D01*
X-68650Y277000D01*
X-68067D01*
X-67483Y276833D01*
X-66983Y276417D01*
G01X-62800Y275333D02*
Y272000D01*
G01Y276667D02*
X-62967Y276750D01*
Y276917D01*
X-62800Y277000D01*
X-62633Y276917D01*
Y276750D01*
X-62800Y276667D01*
G01X-58450Y275333D02*
X-55950D01*
X-58450Y272000D01*
X-55950D01*
G01X-52850Y274250D02*
X-50183D01*
X-50433Y274833D01*
X-50850Y275167D01*
X-51433Y275333D01*
X-52017Y275250D01*
X-52517Y275000D01*
X-52850Y274417D01*
X-53017Y273917D01*
Y273417D01*
X-52850Y272917D01*
X-52433Y272417D01*
X-51933Y272083D01*
X-51350Y272000D01*
X-50767Y272167D01*
X-50183Y272667D01*
G01X-44333Y272000D02*
X-47667Y273667D01*
X-44333Y275333D01*
G01X-40400Y272000D02*
Y277000D01*
X-41400Y276000D01*
G01Y272000D02*
X-39400D01*
G01X-36217Y272583D02*
X-35633Y272167D01*
X-34967Y272000D01*
X-34300Y272167D01*
X-33717Y272667D01*
X-33300Y273417D01*
X-33133Y274167D01*
Y275083D01*
X-33300Y275833D01*
X-33717Y276500D01*
X-34217Y276833D01*
X-34800Y277000D01*
X-35467Y276833D01*
X-35967Y276500D01*
X-36300Y276000D01*
X-36467Y275333D01*
X-36300Y274750D01*
X-35883Y274167D01*
X-35383Y273833D01*
X-34800Y273750D01*
X-34133Y273917D01*
X-33633Y274333D01*
X-33133Y275083D01*
G01X-29367Y272000D02*
X-29200Y273083D01*
X-28950Y274000D01*
X-28617Y274833D01*
X-28200Y275750D01*
X-27533Y277000D01*
X-30867D01*
G01X-26100Y272000D02*
Y275333D01*
G01Y274417D02*
X-25850Y274833D01*
X-25433Y275167D01*
X-24850Y275333D01*
X-24267Y275167D01*
X-23850Y274833D01*
X-23600Y274417D01*
Y272000D01*
G01Y274417D02*
X-23350Y274833D01*
X-22933Y275167D01*
X-22350Y275333D01*
X-21767Y275167D01*
X-21350Y274833D01*
X-21100Y274333D01*
Y272000D01*
G01X-18000Y275333D02*
Y272000D01*
G01Y276667D02*
X-18167Y276750D01*
Y276917D01*
X-18000Y277000D01*
X-17833Y276917D01*
Y276750D01*
X-18000Y276667D01*
G01X-12400Y272000D02*
Y277000D01*
G01X-3283Y275333D02*
X-2283Y272000D01*
X-1200Y275333D01*
X-117Y272000D01*
X883Y275333D01*
G01X4400D02*
Y272000D01*
G01Y276667D02*
X4233Y276750D01*
Y276917D01*
X4400Y277000D01*
X4567Y276917D01*
Y276750D01*
X4400Y276667D01*
G01X10000Y277000D02*
Y272000D01*
G01X8833Y275333D02*
X11167D01*
G01X14183Y272000D02*
Y277000D01*
G01Y274583D02*
X14600Y275000D01*
X15017Y275250D01*
X15683Y275333D01*
X16183Y275250D01*
X16767Y274917D01*
X17017Y274417D01*
Y272000D01*
G01X25383D02*
Y275333D01*
G01Y274500D02*
X25717Y274917D01*
X26217Y275250D01*
X26883Y275333D01*
X27467Y275250D01*
X27967Y274917D01*
X28217Y274333D01*
Y272000D01*
G01X32400D02*
X31900Y272083D01*
X31400Y272417D01*
X31067Y273000D01*
X30900Y273667D01*
X31067Y274333D01*
X31400Y274917D01*
X31900Y275250D01*
X32400Y275333D01*
X32900Y275250D01*
X33400Y274917D01*
X33733Y274333D01*
X33817Y273667D01*
X33733Y273000D01*
X33400Y272417D01*
X32900Y272083D01*
X32400Y272000D01*
G01X36583D02*
Y275333D01*
G01Y274500D02*
X36917Y274917D01*
X37417Y275250D01*
X38083Y275333D01*
X38667Y275250D01*
X39167Y274917D01*
X39417Y274333D01*
Y272000D01*
G01X42517Y273667D02*
X44683D01*
G01X47450Y272000D02*
Y277000D01*
G01X50950D02*
Y272000D01*
G01Y274500D02*
X47450D01*
G01X52717Y272000D02*
X54800Y277000D01*
X56883Y272000D01*
G01X56133Y273750D02*
X53467D01*
G01X58650Y272667D02*
X59317Y272250D01*
X60067Y272000D01*
X60733D01*
X61400Y272250D01*
X61900Y272667D01*
X62150Y273250D01*
X61983Y273833D01*
X61567Y274333D01*
X60817Y274667D01*
X59817Y274833D01*
X59233Y275167D01*
X58983Y275750D01*
X59150Y276333D01*
X59567Y276750D01*
X60150Y277000D01*
X60733D01*
X61317Y276833D01*
X61817Y276417D01*
G01X64333Y277000D02*
Y272000D01*
X67667D01*
G01X75700Y270333D02*
Y275333D01*
G01Y274583D02*
X76117Y275000D01*
X76533Y275250D01*
X77200Y275333D01*
X77783Y275250D01*
X78367Y274833D01*
X78617Y274250D01*
X78700Y273667D01*
X78617Y273083D01*
X78367Y272500D01*
X77867Y272167D01*
X77200Y272000D01*
X76617Y272083D01*
X76033Y272333D01*
X75700Y272667D01*
G01X81633Y272000D02*
Y275333D01*
G01Y274667D02*
X82050Y275000D01*
X82467Y275250D01*
X83050Y275333D01*
X83467Y275250D01*
X83967Y275000D01*
G01X88400Y272000D02*
X87900Y272083D01*
X87400Y272417D01*
X87067Y273000D01*
X86900Y273667D01*
X87067Y274333D01*
X87400Y274917D01*
X87900Y275250D01*
X88400Y275333D01*
X88900Y275250D01*
X89400Y274917D01*
X89733Y274333D01*
X89817Y273667D01*
X89733Y273000D01*
X89400Y272417D01*
X88900Y272083D01*
X88400Y272000D01*
G01X95500Y277000D02*
Y272000D01*
G01Y272750D02*
X95167Y272333D01*
X94667Y272083D01*
X94083Y272000D01*
X93417Y272167D01*
X92917Y272583D01*
X92583Y273083D01*
X92500Y273667D01*
X92583Y274250D01*
X92917Y274750D01*
X93417Y275167D01*
X94083Y275333D01*
X94667Y275250D01*
X95083Y275083D01*
X95500Y274750D01*
G01X98183Y275333D02*
Y273000D01*
X98517Y272417D01*
X99017Y272083D01*
X99600Y272000D01*
X100183Y272083D01*
X100683Y272417D01*
X101017Y273000D01*
G01Y272000D02*
Y275333D01*
G01X106533Y274917D02*
X105950Y275250D01*
X105450Y275333D01*
X104783Y275167D01*
X104283Y274833D01*
X103950Y274250D01*
X103867Y273667D01*
X103950Y273083D01*
X104283Y272583D01*
X104783Y272167D01*
X105450Y272000D01*
X106033Y272167D01*
X106533Y272500D01*
G01X110800Y277000D02*
Y272000D01*
G01X109633Y275333D02*
X111967D01*
G01X115150Y272583D02*
X115567Y272250D01*
X116150Y272000D01*
X116650D01*
X117150Y272167D01*
X117483Y272417D01*
X117650Y272750D01*
X117567Y273250D01*
X117233Y273500D01*
X115733Y274000D01*
X115400Y274583D01*
X115567Y275000D01*
X115900Y275250D01*
X116400Y275333D01*
X116900Y275250D01*
X117400Y275000D01*
G01X122417Y270333D02*
X123250Y271167D01*
X123667Y272000D01*
Y275333D01*
X123250Y276167D01*
X122417Y277000D01*
G01X-187667Y287000D02*
Y292000D01*
X-185667D01*
X-185000Y291750D01*
X-184500Y291167D01*
X-184333Y290500D01*
X-184500Y289833D01*
X-184917Y289333D01*
X-185667Y289083D01*
X-187667D01*
G01X-180400Y287000D02*
Y292000D01*
G01X-176217Y290333D02*
Y288000D01*
X-175883Y287417D01*
X-175383Y287083D01*
X-174800Y287000D01*
X-174217Y287083D01*
X-173717Y287417D01*
X-173383Y288000D01*
G01Y287000D02*
Y290333D01*
G01X-170367Y285750D02*
X-169783Y285417D01*
X-169117Y285333D01*
X-168533Y285417D01*
X-168033Y285833D01*
X-167700Y286417D01*
Y290333D01*
G01Y289667D02*
X-168033Y290000D01*
X-168533Y290250D01*
X-169117Y290333D01*
X-169783Y290167D01*
X-170200Y289833D01*
X-170533Y289250D01*
X-170700Y288667D01*
X-170617Y288167D01*
X-170283Y287583D01*
X-169783Y287167D01*
X-169117Y287000D01*
X-168617Y287083D01*
X-168033Y287417D01*
X-167700Y287750D01*
G01X-164767Y285750D02*
X-164183Y285417D01*
X-163517Y285333D01*
X-162933Y285417D01*
X-162433Y285833D01*
X-162100Y286417D01*
Y290333D01*
G01Y289667D02*
X-162433Y290000D01*
X-162933Y290250D01*
X-163517Y290333D01*
X-164183Y290167D01*
X-164600Y289833D01*
X-164933Y289250D01*
X-165100Y288667D01*
X-165017Y288167D01*
X-164683Y287583D01*
X-164183Y287167D01*
X-163517Y287000D01*
X-163017Y287083D01*
X-162433Y287417D01*
X-162100Y287750D01*
G01X-159250Y289250D02*
X-156583D01*
X-156833Y289833D01*
X-157250Y290167D01*
X-157833Y290333D01*
X-158417Y290250D01*
X-158917Y290000D01*
X-159250Y289417D01*
X-159417Y288917D01*
Y288417D01*
X-159250Y287917D01*
X-158833Y287417D01*
X-158333Y287083D01*
X-157750Y287000D01*
X-157167Y287167D01*
X-156583Y287667D01*
G01X-150900Y292000D02*
Y287000D01*
G01Y287750D02*
X-151233Y287333D01*
X-151733Y287083D01*
X-152317Y287000D01*
X-152983Y287167D01*
X-153483Y287583D01*
X-153817Y288083D01*
X-153900Y288667D01*
X-153817Y289250D01*
X-153483Y289750D01*
X-152983Y290167D01*
X-152317Y290333D01*
X-151733Y290250D01*
X-151317Y290083D01*
X-150900Y289750D01*
G01X-142867Y287000D02*
Y292000D01*
X-140867D01*
X-140200Y291750D01*
X-139700Y291167D01*
X-139533Y290500D01*
X-139700Y289833D01*
X-140117Y289333D01*
X-140867Y289083D01*
X-142867D01*
G01X-135600Y292000D02*
Y287000D01*
G01X-137517Y292000D02*
X-133683D01*
G01X-131750Y287000D02*
Y292000D01*
G01X-128250D02*
Y287000D01*
G01Y289500D02*
X-131750D01*
G01X-124817Y285333D02*
X-125650Y286167D01*
X-126067Y287000D01*
Y290333D01*
X-125650Y291167D01*
X-124817Y292000D01*
G01X-120217Y287000D02*
Y292000D01*
G01Y289583D02*
X-119800Y290000D01*
X-119383Y290250D01*
X-118717Y290333D01*
X-118217Y290250D01*
X-117633Y289917D01*
X-117383Y289417D01*
Y287000D01*
G01X-113200D02*
X-113700Y287083D01*
X-114200Y287417D01*
X-114533Y288000D01*
X-114700Y288667D01*
X-114533Y289333D01*
X-114200Y289917D01*
X-113700Y290250D01*
X-113200Y290333D01*
X-112700Y290250D01*
X-112200Y289917D01*
X-111867Y289333D01*
X-111783Y288667D01*
X-111867Y288000D01*
X-112200Y287417D01*
X-112700Y287083D01*
X-113200Y287000D01*
G01X-107600D02*
Y292000D01*
G01X-103250Y289250D02*
X-100583D01*
X-100833Y289833D01*
X-101250Y290167D01*
X-101833Y290333D01*
X-102417Y290250D01*
X-102917Y290000D01*
X-103250Y289417D01*
X-103417Y288917D01*
Y288417D01*
X-103250Y287917D01*
X-102833Y287417D01*
X-102333Y287083D01*
X-101750Y287000D01*
X-101167Y287167D01*
X-100583Y287667D01*
G01X-92050Y287583D02*
X-91633Y287250D01*
X-91050Y287000D01*
X-90550D01*
X-90050Y287167D01*
X-89717Y287417D01*
X-89550Y287750D01*
X-89633Y288250D01*
X-89967Y288500D01*
X-91467Y289000D01*
X-91800Y289583D01*
X-91633Y290000D01*
X-91300Y290250D01*
X-90800Y290333D01*
X-90300Y290250D01*
X-89800Y290000D01*
G01X-85200Y290333D02*
Y287000D01*
G01Y291667D02*
X-85367Y291750D01*
Y291917D01*
X-85200Y292000D01*
X-85033Y291917D01*
Y291750D01*
X-85200Y291667D01*
G01X-80850Y290333D02*
X-78350D01*
X-80850Y287000D01*
X-78350D01*
G01X-75250Y289250D02*
X-72583D01*
X-72833Y289833D01*
X-73250Y290167D01*
X-73833Y290333D01*
X-74417Y290250D01*
X-74917Y290000D01*
X-75250Y289417D01*
X-75417Y288917D01*
Y288417D01*
X-75250Y287917D01*
X-74833Y287417D01*
X-74333Y287083D01*
X-73750Y287000D01*
X-73167Y287167D01*
X-72583Y287667D01*
G01X-70067Y287000D02*
X-66733Y288667D01*
X-70067Y290333D01*
G01X-63883Y287917D02*
X-61717D01*
G01Y289417D02*
X-63883D01*
G01X-57200Y287000D02*
Y292000D01*
X-58200Y291000D01*
G01Y287000D02*
X-56200D01*
G01X-53183Y289083D02*
X-52600Y289667D01*
X-52100Y290000D01*
X-51433Y290167D01*
X-50850Y290000D01*
X-50433Y289667D01*
X-50100Y289167D01*
X-50017Y288583D01*
X-50100Y288083D01*
X-50433Y287583D01*
X-50933Y287167D01*
X-51517Y287000D01*
X-52183Y287167D01*
X-52767Y287667D01*
X-53100Y288417D01*
X-53183Y289250D01*
X-53017Y290333D01*
X-52767Y290917D01*
X-52350Y291500D01*
X-51767Y291917D01*
X-51183Y292000D01*
X-50600Y291833D01*
X-50183Y291417D01*
G01X-42900Y287000D02*
Y290333D01*
G01Y289417D02*
X-42650Y289833D01*
X-42233Y290167D01*
X-41650Y290333D01*
X-41067Y290167D01*
X-40650Y289833D01*
X-40400Y289417D01*
Y287000D01*
G01Y289417D02*
X-40150Y289833D01*
X-39733Y290167D01*
X-39150Y290333D01*
X-38567Y290167D01*
X-38150Y289833D01*
X-37900Y289333D01*
Y287000D01*
G01X-34800Y290333D02*
Y287000D01*
G01Y291667D02*
X-34967Y291750D01*
Y291917D01*
X-34800Y292000D01*
X-34633Y291917D01*
Y291750D01*
X-34800Y291667D01*
G01X-29200Y287000D02*
Y292000D01*
G01X-23183Y285333D02*
X-22350Y286167D01*
X-21933Y287000D01*
Y290333D01*
X-22350Y291167D01*
X-23183Y292000D01*
G01X-187667Y302000D02*
Y307000D01*
X-185667D01*
X-185000Y306750D01*
X-184500Y306167D01*
X-184333Y305500D01*
X-184500Y304833D01*
X-184917Y304333D01*
X-185667Y304083D01*
X-187667D01*
G01X-180400Y302000D02*
Y307000D01*
G01X-176217Y305333D02*
Y303000D01*
X-175883Y302417D01*
X-175383Y302083D01*
X-174800Y302000D01*
X-174217Y302083D01*
X-173717Y302417D01*
X-173383Y303000D01*
G01Y302000D02*
Y305333D01*
G01X-170367Y300750D02*
X-169783Y300417D01*
X-169117Y300333D01*
X-168533Y300417D01*
X-168033Y300833D01*
X-167700Y301417D01*
Y305333D01*
G01Y304667D02*
X-168033Y305000D01*
X-168533Y305250D01*
X-169117Y305333D01*
X-169783Y305167D01*
X-170200Y304833D01*
X-170533Y304250D01*
X-170700Y303667D01*
X-170617Y303167D01*
X-170283Y302583D01*
X-169783Y302167D01*
X-169117Y302000D01*
X-168617Y302083D01*
X-168033Y302417D01*
X-167700Y302750D01*
G01X-164767Y300750D02*
X-164183Y300417D01*
X-163517Y300333D01*
X-162933Y300417D01*
X-162433Y300833D01*
X-162100Y301417D01*
Y305333D01*
G01Y304667D02*
X-162433Y305000D01*
X-162933Y305250D01*
X-163517Y305333D01*
X-164183Y305167D01*
X-164600Y304833D01*
X-164933Y304250D01*
X-165100Y303667D01*
X-165017Y303167D01*
X-164683Y302583D01*
X-164183Y302167D01*
X-163517Y302000D01*
X-163017Y302083D01*
X-162433Y302417D01*
X-162100Y302750D01*
G01X-159250Y304250D02*
X-156583D01*
X-156833Y304833D01*
X-157250Y305167D01*
X-157833Y305333D01*
X-158417Y305250D01*
X-158917Y305000D01*
X-159250Y304417D01*
X-159417Y303917D01*
Y303417D01*
X-159250Y302917D01*
X-158833Y302417D01*
X-158333Y302083D01*
X-157750Y302000D01*
X-157167Y302167D01*
X-156583Y302667D01*
G01X-150900Y307000D02*
Y302000D01*
G01Y302750D02*
X-151233Y302333D01*
X-151733Y302083D01*
X-152317Y302000D01*
X-152983Y302167D01*
X-153483Y302583D01*
X-153817Y303083D01*
X-153900Y303667D01*
X-153817Y304250D01*
X-153483Y304750D01*
X-152983Y305167D01*
X-152317Y305333D01*
X-151733Y305250D01*
X-151317Y305083D01*
X-150900Y304750D01*
G01X-143283Y307000D02*
X-141200Y302000D01*
X-139117Y307000D01*
G01X-135600Y305333D02*
Y302000D01*
G01Y306667D02*
X-135767Y306750D01*
Y306917D01*
X-135600Y307000D01*
X-135433Y306917D01*
Y306750D01*
X-135600Y306667D01*
G01X-128500Y302000D02*
Y305333D01*
G01Y304750D02*
X-128833Y305083D01*
X-129333Y305250D01*
X-129917Y305333D01*
X-130500Y305167D01*
X-131000Y304833D01*
X-131333Y304333D01*
X-131500Y303667D01*
X-131333Y303000D01*
X-131000Y302500D01*
X-130500Y302167D01*
X-129917Y302000D01*
X-129333Y302083D01*
X-128833Y302333D01*
X-128500Y302667D01*
G01X-124817Y300333D02*
X-125650Y301167D01*
X-126067Y302000D01*
Y305333D01*
X-125650Y306167D01*
X-124817Y307000D01*
G01X-120217Y302000D02*
Y307000D01*
G01Y304583D02*
X-119800Y305000D01*
X-119383Y305250D01*
X-118717Y305333D01*
X-118217Y305250D01*
X-117633Y304917D01*
X-117383Y304417D01*
Y302000D01*
G01X-113200D02*
X-113700Y302083D01*
X-114200Y302417D01*
X-114533Y303000D01*
X-114700Y303667D01*
X-114533Y304333D01*
X-114200Y304917D01*
X-113700Y305250D01*
X-113200Y305333D01*
X-112700Y305250D01*
X-112200Y304917D01*
X-111867Y304333D01*
X-111783Y303667D01*
X-111867Y303000D01*
X-112200Y302417D01*
X-112700Y302083D01*
X-113200Y302000D01*
G01X-107600D02*
Y307000D01*
G01X-103250Y304250D02*
X-100583D01*
X-100833Y304833D01*
X-101250Y305167D01*
X-101833Y305333D01*
X-102417Y305250D01*
X-102917Y305000D01*
X-103250Y304417D01*
X-103417Y303917D01*
Y303417D01*
X-103250Y302917D01*
X-102833Y302417D01*
X-102333Y302083D01*
X-101750Y302000D01*
X-101167Y302167D01*
X-100583Y302667D01*
G01X-92050Y302583D02*
X-91633Y302250D01*
X-91050Y302000D01*
X-90550D01*
X-90050Y302167D01*
X-89717Y302417D01*
X-89550Y302750D01*
X-89633Y303250D01*
X-89967Y303500D01*
X-91467Y304000D01*
X-91800Y304583D01*
X-91633Y305000D01*
X-91300Y305250D01*
X-90800Y305333D01*
X-90300Y305250D01*
X-89800Y305000D01*
G01X-85200Y305333D02*
Y302000D01*
G01Y306667D02*
X-85367Y306750D01*
Y306917D01*
X-85200Y307000D01*
X-85033Y306917D01*
Y306750D01*
X-85200Y306667D01*
G01X-80850Y305333D02*
X-78350D01*
X-80850Y302000D01*
X-78350D01*
G01X-75250Y304250D02*
X-72583D01*
X-72833Y304833D01*
X-73250Y305167D01*
X-73833Y305333D01*
X-74417Y305250D01*
X-74917Y305000D01*
X-75250Y304417D01*
X-75417Y303917D01*
Y303417D01*
X-75250Y302917D01*
X-74833Y302417D01*
X-74333Y302083D01*
X-73750Y302000D01*
X-73167Y302167D01*
X-72583Y302667D01*
G01X-66733Y302000D02*
X-70067Y303667D01*
X-66733Y305333D01*
G01X-62800Y302000D02*
Y307000D01*
X-63800Y306000D01*
G01Y302000D02*
X-61800D01*
G01X-58783Y304083D02*
X-58200Y304667D01*
X-57700Y305000D01*
X-57033Y305167D01*
X-56450Y305000D01*
X-56033Y304667D01*
X-55700Y304167D01*
X-55617Y303583D01*
X-55700Y303083D01*
X-56033Y302583D01*
X-56533Y302167D01*
X-57117Y302000D01*
X-57783Y302167D01*
X-58367Y302667D01*
X-58700Y303417D01*
X-58783Y304250D01*
X-58617Y305333D01*
X-58367Y305917D01*
X-57950Y306500D01*
X-57367Y306917D01*
X-56783Y307000D01*
X-56200Y306833D01*
X-55783Y306417D01*
G01X-48500Y302000D02*
Y305333D01*
G01Y304417D02*
X-48250Y304833D01*
X-47833Y305167D01*
X-47250Y305333D01*
X-46667Y305167D01*
X-46250Y304833D01*
X-46000Y304417D01*
Y302000D01*
G01Y304417D02*
X-45750Y304833D01*
X-45333Y305167D01*
X-44750Y305333D01*
X-44167Y305167D01*
X-43750Y304833D01*
X-43500Y304333D01*
Y302000D01*
G01X-40400Y305333D02*
Y302000D01*
G01Y306667D02*
X-40567Y306750D01*
Y306917D01*
X-40400Y307000D01*
X-40233Y306917D01*
Y306750D01*
X-40400Y306667D01*
G01X-34800Y302000D02*
Y307000D01*
G01X-28783Y300333D02*
X-27950Y301167D01*
X-27533Y302000D01*
Y305333D01*
X-27950Y306167D01*
X-28783Y307000D01*
G01X-188083Y315500D02*
X-186000Y320500D01*
X-183917Y315500D01*
G01X-184667Y317250D02*
X-187333D01*
G01X-181817Y315500D02*
Y318833D01*
G01Y318000D02*
X-181483Y318417D01*
X-180983Y318750D01*
X-180317Y318833D01*
X-179733Y318750D01*
X-179233Y318417D01*
X-178983Y317833D01*
Y315500D01*
G01X-176550Y314000D02*
X-176050Y313833D01*
X-175383Y314000D01*
X-174967Y314333D01*
X-174633Y314750D01*
X-174133Y316083D01*
X-173050Y318833D01*
G01X-175717D02*
X-174133Y316083D01*
G01X-165017Y315500D02*
Y320500D01*
G01Y318083D02*
X-164600Y318500D01*
X-164183Y318750D01*
X-163517Y318833D01*
X-163017Y318750D01*
X-162433Y318417D01*
X-162183Y317917D01*
Y315500D01*
G01X-158000D02*
X-158500Y315583D01*
X-159000Y315917D01*
X-159333Y316500D01*
X-159500Y317167D01*
X-159333Y317833D01*
X-159000Y318417D01*
X-158500Y318750D01*
X-158000Y318833D01*
X-157500Y318750D01*
X-157000Y318417D01*
X-156667Y317833D01*
X-156583Y317167D01*
X-156667Y316500D01*
X-157000Y315917D01*
X-157500Y315583D01*
X-158000Y315500D01*
G01X-152400D02*
Y320500D01*
G01X-148050Y317750D02*
X-145383D01*
X-145633Y318333D01*
X-146050Y318667D01*
X-146633Y318833D01*
X-147217Y318750D01*
X-147717Y318500D01*
X-148050Y317917D01*
X-148217Y317417D01*
Y316917D01*
X-148050Y316417D01*
X-147633Y315917D01*
X-147133Y315583D01*
X-146550Y315500D01*
X-145967Y315667D01*
X-145383Y316167D01*
G01X-135600Y320500D02*
Y315500D01*
G01X-136767Y318833D02*
X-134433D01*
G01X-130000Y315500D02*
X-130500Y315583D01*
X-131000Y315917D01*
X-131333Y316500D01*
X-131500Y317167D01*
X-131333Y317833D01*
X-131000Y318417D01*
X-130500Y318750D01*
X-130000Y318833D01*
X-129500Y318750D01*
X-129000Y318417D01*
X-128667Y317833D01*
X-128583Y317167D01*
X-128667Y316500D01*
X-129000Y315917D01*
X-129500Y315583D01*
X-130000Y315500D01*
G01X-120217D02*
Y320500D01*
G01Y318083D02*
X-119800Y318500D01*
X-119383Y318750D01*
X-118717Y318833D01*
X-118217Y318750D01*
X-117633Y318417D01*
X-117383Y317917D01*
Y315500D01*
G01X-113200D02*
X-113700Y315583D01*
X-114200Y315917D01*
X-114533Y316500D01*
X-114700Y317167D01*
X-114533Y317833D01*
X-114200Y318417D01*
X-113700Y318750D01*
X-113200Y318833D01*
X-112700Y318750D01*
X-112200Y318417D01*
X-111867Y317833D01*
X-111783Y317167D01*
X-111867Y316500D01*
X-112200Y315917D01*
X-112700Y315583D01*
X-113200Y315500D01*
G01X-107600D02*
Y320500D01*
G01X-103250Y317750D02*
X-100583D01*
X-100833Y318333D01*
X-101250Y318667D01*
X-101833Y318833D01*
X-102417Y318750D01*
X-102917Y318500D01*
X-103250Y317917D01*
X-103417Y317417D01*
Y316917D01*
X-103250Y316417D01*
X-102833Y315917D01*
X-102333Y315583D01*
X-101750Y315500D01*
X-101167Y315667D01*
X-100583Y316167D01*
G01X-185500Y336000D02*
Y331000D01*
G01X-187417Y336000D02*
X-183583D01*
G01X-181317Y331000D02*
Y336000D01*
G01Y333583D02*
X-180900Y334000D01*
X-180483Y334250D01*
X-179817Y334333D01*
X-179317Y334250D01*
X-178733Y333917D01*
X-178483Y333417D01*
Y331000D01*
G01X-175550Y333250D02*
X-172883D01*
X-173133Y333833D01*
X-173550Y334167D01*
X-174133Y334333D01*
X-174717Y334250D01*
X-175217Y334000D01*
X-175550Y333417D01*
X-175717Y332917D01*
Y332417D01*
X-175550Y331917D01*
X-175133Y331417D01*
X-174633Y331083D01*
X-174050Y331000D01*
X-173467Y331167D01*
X-172883Y331667D01*
G01X-169867Y331000D02*
Y334333D01*
G01Y333667D02*
X-169450Y334000D01*
X-169033Y334250D01*
X-168450Y334333D01*
X-168033Y334250D01*
X-167533Y334000D01*
G01X-165600Y331000D02*
Y334333D01*
G01Y333417D02*
X-165350Y333833D01*
X-164933Y334167D01*
X-164350Y334333D01*
X-163767Y334167D01*
X-163350Y333833D01*
X-163100Y333417D01*
Y331000D01*
G01Y333417D02*
X-162850Y333833D01*
X-162433Y334167D01*
X-161850Y334333D01*
X-161267Y334167D01*
X-160850Y333833D01*
X-160600Y333333D01*
Y331000D01*
G01X-156000D02*
Y334333D01*
G01Y333750D02*
X-156333Y334083D01*
X-156833Y334250D01*
X-157417Y334333D01*
X-158000Y334167D01*
X-158500Y333833D01*
X-158833Y333333D01*
X-159000Y332667D01*
X-158833Y332000D01*
X-158500Y331500D01*
X-158000Y331167D01*
X-157417Y331000D01*
X-156833Y331083D01*
X-156333Y331333D01*
X-156000Y331667D01*
G01X-151900Y331000D02*
Y336000D01*
G01X-142200Y329333D02*
Y334333D01*
G01Y333583D02*
X-141783Y334000D01*
X-141367Y334250D01*
X-140700Y334333D01*
X-140117Y334250D01*
X-139533Y333833D01*
X-139283Y333250D01*
X-139200Y332667D01*
X-139283Y332083D01*
X-139533Y331500D01*
X-140033Y331167D01*
X-140700Y331000D01*
X-141283Y331083D01*
X-141867Y331333D01*
X-142200Y331667D01*
G01X-133600Y331000D02*
Y334333D01*
G01Y333750D02*
X-133933Y334083D01*
X-134433Y334250D01*
X-135017Y334333D01*
X-135600Y334167D01*
X-136100Y333833D01*
X-136433Y333333D01*
X-136600Y332667D01*
X-136433Y332000D01*
X-136100Y331500D01*
X-135600Y331167D01*
X-135017Y331000D01*
X-134433Y331083D01*
X-133933Y331333D01*
X-133600Y331667D01*
G01X-128000Y336000D02*
Y331000D01*
G01Y331750D02*
X-128333Y331333D01*
X-128833Y331083D01*
X-129417Y331000D01*
X-130083Y331167D01*
X-130583Y331583D01*
X-130917Y332083D01*
X-131000Y332667D01*
X-130917Y333250D01*
X-130583Y333750D01*
X-130083Y334167D01*
X-129417Y334333D01*
X-128833Y334250D01*
X-128417Y334083D01*
X-128000Y333750D01*
G01X-116967Y333917D02*
X-117550Y334250D01*
X-118050Y334333D01*
X-118717Y334167D01*
X-119217Y333833D01*
X-119550Y333250D01*
X-119633Y332667D01*
X-119550Y332083D01*
X-119217Y331583D01*
X-118717Y331167D01*
X-118050Y331000D01*
X-117467Y331167D01*
X-116967Y331500D01*
G01X-111200Y331000D02*
Y334333D01*
G01Y333750D02*
X-111533Y334083D01*
X-112033Y334250D01*
X-112617Y334333D01*
X-113200Y334167D01*
X-113700Y333833D01*
X-114033Y333333D01*
X-114200Y332667D01*
X-114033Y332000D01*
X-113700Y331500D01*
X-113200Y331167D01*
X-112617Y331000D01*
X-112033Y331083D01*
X-111533Y331333D01*
X-111200Y331667D01*
G01X-108517Y331000D02*
Y334333D01*
G01Y333500D02*
X-108183Y333917D01*
X-107683Y334250D01*
X-107017Y334333D01*
X-106433Y334250D01*
X-105933Y333917D01*
X-105683Y333333D01*
Y331000D01*
G01X-94567Y333917D02*
X-95150Y334250D01*
X-95650Y334333D01*
X-96317Y334167D01*
X-96817Y333833D01*
X-97150Y333250D01*
X-97233Y332667D01*
X-97150Y332083D01*
X-96817Y331583D01*
X-96317Y331167D01*
X-95650Y331000D01*
X-95067Y331167D01*
X-94567Y331500D01*
G01X-91717Y331000D02*
Y336000D01*
G01Y333583D02*
X-91300Y334000D01*
X-90883Y334250D01*
X-90217Y334333D01*
X-89717Y334250D01*
X-89133Y333917D01*
X-88883Y333417D01*
Y331000D01*
G01X-83200D02*
Y334333D01*
G01Y333750D02*
X-83533Y334083D01*
X-84033Y334250D01*
X-84617Y334333D01*
X-85200Y334167D01*
X-85700Y333833D01*
X-86033Y333333D01*
X-86200Y332667D01*
X-86033Y332000D01*
X-85700Y331500D01*
X-85200Y331167D01*
X-84617Y331000D01*
X-84033Y331083D01*
X-83533Y331333D01*
X-83200Y331667D01*
G01X-80517Y331000D02*
Y334333D01*
G01Y333500D02*
X-80183Y333917D01*
X-79683Y334250D01*
X-79017Y334333D01*
X-78433Y334250D01*
X-77933Y333917D01*
X-77683Y333333D01*
Y331000D01*
G01X-74667Y329750D02*
X-74083Y329417D01*
X-73417Y329333D01*
X-72833Y329417D01*
X-72333Y329833D01*
X-72000Y330417D01*
Y334333D01*
G01Y333667D02*
X-72333Y334000D01*
X-72833Y334250D01*
X-73417Y334333D01*
X-74083Y334167D01*
X-74500Y333833D01*
X-74833Y333250D01*
X-75000Y332667D01*
X-74917Y332167D01*
X-74583Y331583D01*
X-74083Y331167D01*
X-73417Y331000D01*
X-72917Y331083D01*
X-72333Y331417D01*
X-72000Y331750D01*
G01X-69150Y333250D02*
X-66483D01*
X-66733Y333833D01*
X-67150Y334167D01*
X-67733Y334333D01*
X-68317Y334250D01*
X-68817Y334000D01*
X-69150Y333417D01*
X-69317Y332917D01*
Y332417D01*
X-69150Y331917D01*
X-68733Y331417D01*
X-68233Y331083D01*
X-67650Y331000D01*
X-67067Y331167D01*
X-66483Y331667D01*
G01X-56700Y334333D02*
Y331000D01*
G01Y335667D02*
X-56867Y335750D01*
Y335917D01*
X-56700Y336000D01*
X-56533Y335917D01*
Y335750D01*
X-56700Y335667D01*
G01X-52517Y331000D02*
Y334333D01*
G01Y333500D02*
X-52183Y333917D01*
X-51683Y334250D01*
X-51017Y334333D01*
X-50433Y334250D01*
X-49933Y333917D01*
X-49683Y333333D01*
Y331000D01*
G01X-45500Y336000D02*
Y331000D01*
G01X-46667Y334333D02*
X-44333D01*
G01X-39900Y331000D02*
X-40400Y331083D01*
X-40900Y331417D01*
X-41233Y332000D01*
X-41400Y332667D01*
X-41233Y333333D01*
X-40900Y333917D01*
X-40400Y334250D01*
X-39900Y334333D01*
X-39400Y334250D01*
X-38900Y333917D01*
X-38567Y333333D01*
X-38483Y332667D01*
X-38567Y332000D01*
X-38900Y331417D01*
X-39400Y331083D01*
X-39900Y331000D01*
G01X-29200D02*
Y335250D01*
X-29033Y335667D01*
X-28700Y335917D01*
X-28200Y336000D01*
X-27700Y335833D01*
X-27450Y335417D01*
G01X-28450Y334000D02*
X-30117D01*
G01X-24517Y334333D02*
Y332000D01*
X-24183Y331417D01*
X-23683Y331083D01*
X-23100Y331000D01*
X-22517Y331083D01*
X-22017Y331417D01*
X-21683Y332000D01*
G01Y331000D02*
Y334333D01*
G01X-17500Y331000D02*
Y336000D01*
G01X-11900Y331000D02*
Y336000D01*
G01X633Y333917D02*
X50Y334250D01*
X-450Y334333D01*
X-1117Y334167D01*
X-1617Y333833D01*
X-1950Y333250D01*
X-2033Y332667D01*
X-1950Y332083D01*
X-1617Y331583D01*
X-1117Y331167D01*
X-450Y331000D01*
X133Y331167D01*
X633Y331500D01*
G01X4900Y331000D02*
X4400Y331083D01*
X3900Y331417D01*
X3567Y332000D01*
X3400Y332667D01*
X3567Y333333D01*
X3900Y333917D01*
X4400Y334250D01*
X4900Y334333D01*
X5400Y334250D01*
X5900Y333917D01*
X6233Y333333D01*
X6317Y332667D01*
X6233Y332000D01*
X5900Y331417D01*
X5400Y331083D01*
X4900Y331000D01*
G01X9083D02*
Y334333D01*
G01Y333500D02*
X9417Y333917D01*
X9917Y334250D01*
X10583Y334333D01*
X11167Y334250D01*
X11667Y333917D01*
X11917Y333333D01*
Y331000D01*
G01X16100Y336000D02*
Y331000D01*
G01X14933Y334333D02*
X17267D01*
G01X23200Y331000D02*
Y334333D01*
G01Y333750D02*
X22867Y334083D01*
X22367Y334250D01*
X21783Y334333D01*
X21200Y334167D01*
X20700Y333833D01*
X20367Y333333D01*
X20200Y332667D01*
X20367Y332000D01*
X20700Y331500D01*
X21200Y331167D01*
X21783Y331000D01*
X22367Y331083D01*
X22867Y331333D01*
X23200Y331667D01*
G01X28633Y333917D02*
X28050Y334250D01*
X27550Y334333D01*
X26883Y334167D01*
X26383Y333833D01*
X26050Y333250D01*
X25967Y332667D01*
X26050Y332083D01*
X26383Y331583D01*
X26883Y331167D01*
X27550Y331000D01*
X28133Y331167D01*
X28633Y331500D01*
G01X32900Y336000D02*
Y331000D01*
G01X31733Y334333D02*
X34067D01*
G01X-187583Y346000D02*
X-185500Y351000D01*
X-183417Y346000D01*
G01X-184167Y347750D02*
X-186833D01*
G01X-181317Y346000D02*
Y349333D01*
G01Y348500D02*
X-180983Y348917D01*
X-180483Y349250D01*
X-179817Y349333D01*
X-179233Y349250D01*
X-178733Y348917D01*
X-178483Y348333D01*
Y346000D01*
G01X-174300Y351000D02*
Y346000D01*
G01X-175467Y349333D02*
X-173133D01*
G01X-168700D02*
Y346000D01*
G01Y350667D02*
X-168867Y350750D01*
Y350917D01*
X-168700Y351000D01*
X-168533Y350917D01*
Y350750D01*
X-168700Y350667D01*
G01X-164183Y347667D02*
X-162017D01*
G01X-159000Y344333D02*
Y349333D01*
G01Y348583D02*
X-158583Y349000D01*
X-158167Y349250D01*
X-157500Y349333D01*
X-156917Y349250D01*
X-156333Y348833D01*
X-156083Y348250D01*
X-156000Y347667D01*
X-156083Y347083D01*
X-156333Y346500D01*
X-156833Y346167D01*
X-157500Y346000D01*
X-158083Y346083D01*
X-158667Y346333D01*
X-159000Y346667D01*
G01X-150400Y346000D02*
Y349333D01*
G01Y348750D02*
X-150733Y349083D01*
X-151233Y349250D01*
X-151817Y349333D01*
X-152400Y349167D01*
X-152900Y348833D01*
X-153233Y348333D01*
X-153400Y347667D01*
X-153233Y347000D01*
X-152900Y346500D01*
X-152400Y346167D01*
X-151817Y346000D01*
X-151233Y346083D01*
X-150733Y346333D01*
X-150400Y346667D01*
G01X-144800Y351000D02*
Y346000D01*
G01Y346750D02*
X-145133Y346333D01*
X-145633Y346083D01*
X-146217Y346000D01*
X-146883Y346167D01*
X-147383Y346583D01*
X-147717Y347083D01*
X-147800Y347667D01*
X-147717Y348250D01*
X-147383Y348750D01*
X-146883Y349167D01*
X-146217Y349333D01*
X-145633Y349250D01*
X-145217Y349083D01*
X-144800Y348750D01*
G01X-136350Y346583D02*
X-135933Y346250D01*
X-135350Y346000D01*
X-134850D01*
X-134350Y346167D01*
X-134017Y346417D01*
X-133850Y346750D01*
X-133933Y347250D01*
X-134267Y347500D01*
X-135767Y348000D01*
X-136100Y348583D01*
X-135933Y349000D01*
X-135600Y349250D01*
X-135100Y349333D01*
X-134600Y349250D01*
X-134100Y349000D01*
G01X-129500Y349333D02*
Y346000D01*
G01Y350667D02*
X-129667Y350750D01*
Y350917D01*
X-129500Y351000D01*
X-129333Y350917D01*
Y350750D01*
X-129500Y350667D01*
G01X-125150Y349333D02*
X-122650D01*
X-125150Y346000D01*
X-122650D01*
G01X-119550Y348250D02*
X-116883D01*
X-117133Y348833D01*
X-117550Y349167D01*
X-118133Y349333D01*
X-118717Y349250D01*
X-119217Y349000D01*
X-119550Y348417D01*
X-119717Y347917D01*
Y347417D01*
X-119550Y346917D01*
X-119133Y346417D01*
X-118633Y346083D01*
X-118050Y346000D01*
X-117467Y346167D01*
X-116883Y346667D01*
G01X-188783Y364573D02*
X-187783Y361240D01*
X-186700Y364573D01*
X-185617Y361240D01*
X-184617Y364573D01*
G01X-181100D02*
Y361240D01*
G01Y365907D02*
X-181267Y365990D01*
Y366157D01*
X-181100Y366240D01*
X-180933Y366157D01*
Y365990D01*
X-181100Y365907D01*
G01X-175500Y366240D02*
Y361240D01*
G01X-176667Y364573D02*
X-174333D01*
G01X-171317Y361240D02*
Y366240D01*
G01Y363823D02*
X-170900Y364240D01*
X-170483Y364490D01*
X-169817Y364573D01*
X-169317Y364490D01*
X-168733Y364157D01*
X-168483Y363657D01*
Y361240D01*
G01X-164300D02*
X-164800Y361323D01*
X-165300Y361657D01*
X-165633Y362240D01*
X-165800Y362907D01*
X-165633Y363573D01*
X-165300Y364157D01*
X-164800Y364490D01*
X-164300Y364573D01*
X-163800Y364490D01*
X-163300Y364157D01*
X-162967Y363573D01*
X-162883Y362907D01*
X-162967Y362240D01*
X-163300Y361657D01*
X-163800Y361323D01*
X-164300Y361240D01*
G01X-160117Y364573D02*
Y362240D01*
X-159783Y361657D01*
X-159283Y361323D01*
X-158700Y361240D01*
X-158117Y361323D01*
X-157617Y361657D01*
X-157283Y362240D01*
G01Y361240D02*
Y364573D01*
G01X-153100Y366240D02*
Y361240D01*
G01X-154267Y364573D02*
X-151933D01*
G01X-140567Y364157D02*
X-141150Y364490D01*
X-141650Y364573D01*
X-142317Y364407D01*
X-142817Y364073D01*
X-143150Y363490D01*
X-143233Y362907D01*
X-143150Y362323D01*
X-142817Y361823D01*
X-142317Y361407D01*
X-141650Y361240D01*
X-141067Y361407D01*
X-140567Y361740D01*
G01X-136300Y361240D02*
X-136800Y361323D01*
X-137300Y361657D01*
X-137633Y362240D01*
X-137800Y362907D01*
X-137633Y363573D01*
X-137300Y364157D01*
X-136800Y364490D01*
X-136300Y364573D01*
X-135800Y364490D01*
X-135300Y364157D01*
X-134967Y363573D01*
X-134883Y362907D01*
X-134967Y362240D01*
X-135300Y361657D01*
X-135800Y361323D01*
X-136300Y361240D01*
G01X-132117D02*
Y364573D01*
G01Y363740D02*
X-131783Y364157D01*
X-131283Y364490D01*
X-130617Y364573D01*
X-130033Y364490D01*
X-129533Y364157D01*
X-129283Y363573D01*
Y361240D01*
G01X-126517D02*
Y364573D01*
G01Y363740D02*
X-126183Y364157D01*
X-125683Y364490D01*
X-125017Y364573D01*
X-124433Y364490D01*
X-123933Y364157D01*
X-123683Y363573D01*
Y361240D01*
G01X-120750Y363490D02*
X-118083D01*
X-118333Y364073D01*
X-118750Y364407D01*
X-119333Y364573D01*
X-119917Y364490D01*
X-120417Y364240D01*
X-120750Y363657D01*
X-120917Y363157D01*
Y362657D01*
X-120750Y362157D01*
X-120333Y361657D01*
X-119833Y361323D01*
X-119250Y361240D01*
X-118667Y361407D01*
X-118083Y361907D01*
G01X-112567Y364157D02*
X-113150Y364490D01*
X-113650Y364573D01*
X-114317Y364407D01*
X-114817Y364073D01*
X-115150Y363490D01*
X-115233Y362907D01*
X-115150Y362323D01*
X-114817Y361823D01*
X-114317Y361407D01*
X-113650Y361240D01*
X-113067Y361407D01*
X-112567Y361740D01*
G01X-108300Y366240D02*
Y361240D01*
G01X-109467Y364573D02*
X-107133D01*
G01X-102700D02*
Y361240D01*
G01Y365907D02*
X-102867Y365990D01*
Y366157D01*
X-102700Y366240D01*
X-102533Y366157D01*
Y365990D01*
X-102700Y365907D01*
G01X-98517Y361240D02*
Y364573D01*
G01Y363740D02*
X-98183Y364157D01*
X-97683Y364490D01*
X-97017Y364573D01*
X-96433Y364490D01*
X-95933Y364157D01*
X-95683Y363573D01*
Y361240D01*
G01X-92667Y359990D02*
X-92083Y359657D01*
X-91417Y359573D01*
X-90833Y359657D01*
X-90333Y360073D01*
X-90000Y360657D01*
Y364573D01*
G01Y363907D02*
X-90333Y364240D01*
X-90833Y364490D01*
X-91417Y364573D01*
X-92083Y364407D01*
X-92500Y364073D01*
X-92833Y363490D01*
X-93000Y362907D01*
X-92917Y362407D01*
X-92583Y361823D01*
X-92083Y361407D01*
X-91417Y361240D01*
X-90917Y361323D01*
X-90333Y361657D01*
X-90000Y361990D01*
G01X-80300Y366240D02*
Y361240D01*
G01X-81467Y364573D02*
X-79133D01*
G01X-74700Y361240D02*
X-75200Y361323D01*
X-75700Y361657D01*
X-76033Y362240D01*
X-76200Y362907D01*
X-76033Y363573D01*
X-75700Y364157D01*
X-75200Y364490D01*
X-74700Y364573D01*
X-74200Y364490D01*
X-73700Y364157D01*
X-73367Y363573D01*
X-73283Y362907D01*
X-73367Y362240D01*
X-73700Y361657D01*
X-74200Y361323D01*
X-74700Y361240D01*
G01X-63500D02*
X-64000Y361323D01*
X-64500Y361657D01*
X-64833Y362240D01*
X-65000Y362907D01*
X-64833Y363573D01*
X-64500Y364157D01*
X-64000Y364490D01*
X-63500Y364573D01*
X-63000Y364490D01*
X-62500Y364157D01*
X-62167Y363573D01*
X-62083Y362907D01*
X-62167Y362240D01*
X-62500Y361657D01*
X-63000Y361323D01*
X-63500Y361240D01*
G01X-57900Y366240D02*
Y361240D01*
G01X-59067Y364573D02*
X-56733D01*
G01X-53717Y361240D02*
Y366240D01*
G01Y363823D02*
X-53300Y364240D01*
X-52883Y364490D01*
X-52217Y364573D01*
X-51717Y364490D01*
X-51133Y364157D01*
X-50883Y363657D01*
Y361240D01*
G01X-47950Y363490D02*
X-45283D01*
X-45533Y364073D01*
X-45950Y364407D01*
X-46533Y364573D01*
X-47117Y364490D01*
X-47617Y364240D01*
X-47950Y363657D01*
X-48117Y363157D01*
Y362657D01*
X-47950Y362157D01*
X-47533Y361657D01*
X-47033Y361323D01*
X-46450Y361240D01*
X-45867Y361407D01*
X-45283Y361907D01*
G01X-42267Y361240D02*
Y364573D01*
G01Y363907D02*
X-41850Y364240D01*
X-41433Y364490D01*
X-40850Y364573D01*
X-40433Y364490D01*
X-39933Y364240D01*
G01X-29900Y361240D02*
Y366240D01*
G01X-22800Y361240D02*
Y364573D01*
G01Y363990D02*
X-23133Y364323D01*
X-23633Y364490D01*
X-24217Y364573D01*
X-24800Y364407D01*
X-25300Y364073D01*
X-25633Y363573D01*
X-25800Y362907D01*
X-25633Y362240D01*
X-25300Y361740D01*
X-24800Y361407D01*
X-24217Y361240D01*
X-23633Y361323D01*
X-23133Y361573D01*
X-22800Y361907D01*
G01X-20450Y359740D02*
X-19950Y359573D01*
X-19283Y359740D01*
X-18867Y360073D01*
X-18533Y360490D01*
X-18033Y361823D01*
X-16950Y364573D01*
G01X-19617D02*
X-18033Y361823D01*
G01X-14350Y363490D02*
X-11683D01*
X-11933Y364073D01*
X-12350Y364407D01*
X-12933Y364573D01*
X-13517Y364490D01*
X-14017Y364240D01*
X-14350Y363657D01*
X-14517Y363157D01*
Y362657D01*
X-14350Y362157D01*
X-13933Y361657D01*
X-13433Y361323D01*
X-12850Y361240D01*
X-12267Y361407D01*
X-11683Y361907D01*
G01X-8667Y361240D02*
Y364573D01*
G01Y363907D02*
X-8250Y364240D01*
X-7833Y364490D01*
X-7250Y364573D01*
X-6833Y364490D01*
X-6333Y364240D01*
G01X-3150Y361823D02*
X-2733Y361490D01*
X-2150Y361240D01*
X-1650D01*
X-1150Y361407D01*
X-817Y361657D01*
X-650Y361990D01*
X-733Y362490D01*
X-1067Y362740D01*
X-2567Y363240D01*
X-2900Y363823D01*
X-2733Y364240D01*
X-2400Y364490D01*
X-1900Y364573D01*
X-1400Y364490D01*
X-900Y364240D01*
G01X4117Y359573D02*
X4950Y360407D01*
X5367Y361240D01*
Y364573D01*
X4950Y365407D01*
X4117Y366240D01*
G01X-188243Y371950D02*
Y376950D01*
X-186577D01*
X-185910Y376700D01*
X-185410Y376367D01*
X-184993Y375867D01*
X-184660Y375283D01*
X-184577Y374450D01*
X-184660Y373617D01*
X-184993Y373033D01*
X-185410Y372533D01*
X-185910Y372200D01*
X-186577Y371950D01*
X-188243D01*
G01X-182060Y374200D02*
X-179393D01*
X-179643Y374783D01*
X-180060Y375117D01*
X-180643Y375283D01*
X-181227Y375200D01*
X-181727Y374950D01*
X-182060Y374367D01*
X-182227Y373867D01*
Y373367D01*
X-182060Y372867D01*
X-181643Y372367D01*
X-181143Y372033D01*
X-180560Y371950D01*
X-179977Y372117D01*
X-179393Y372617D01*
G01X-175210Y371950D02*
Y376950D01*
G01X-170860Y374200D02*
X-168193D01*
X-168443Y374783D01*
X-168860Y375117D01*
X-169443Y375283D01*
X-170027Y375200D01*
X-170527Y374950D01*
X-170860Y374367D01*
X-171027Y373867D01*
Y373367D01*
X-170860Y372867D01*
X-170443Y372367D01*
X-169943Y372033D01*
X-169360Y371950D01*
X-168777Y372117D01*
X-168193Y372617D01*
G01X-164010Y376950D02*
Y371950D01*
G01X-165177Y375283D02*
X-162843D01*
G01X-159660Y374200D02*
X-156993D01*
X-157243Y374783D01*
X-157660Y375117D01*
X-158243Y375283D01*
X-158827Y375200D01*
X-159327Y374950D01*
X-159660Y374367D01*
X-159827Y373867D01*
Y373367D01*
X-159660Y372867D01*
X-159243Y372367D01*
X-158743Y372033D01*
X-158160Y371950D01*
X-157577Y372117D01*
X-156993Y372617D01*
G01X-148627Y371950D02*
Y375283D01*
G01Y374450D02*
X-148293Y374867D01*
X-147793Y375200D01*
X-147127Y375283D01*
X-146543Y375200D01*
X-146043Y374867D01*
X-145793Y374283D01*
Y371950D01*
G01X-141610D02*
X-142110Y372033D01*
X-142610Y372367D01*
X-142943Y372950D01*
X-143110Y373617D01*
X-142943Y374283D01*
X-142610Y374867D01*
X-142110Y375200D01*
X-141610Y375283D01*
X-141110Y375200D01*
X-140610Y374867D01*
X-140277Y374283D01*
X-140193Y373617D01*
X-140277Y372950D01*
X-140610Y372367D01*
X-141110Y372033D01*
X-141610Y371950D01*
G01X-137427D02*
Y375283D01*
G01Y374450D02*
X-137093Y374867D01*
X-136593Y375200D01*
X-135927Y375283D01*
X-135343Y375200D01*
X-134843Y374867D01*
X-134593Y374283D01*
Y371950D01*
G01X-131493Y373617D02*
X-129327D01*
G01X-125310Y371950D02*
Y376200D01*
X-125143Y376617D01*
X-124810Y376867D01*
X-124310Y376950D01*
X-123810Y376783D01*
X-123560Y376367D01*
G01X-124560Y374950D02*
X-126227D01*
G01X-120627Y375283D02*
Y372950D01*
X-120293Y372367D01*
X-119793Y372033D01*
X-119210Y371950D01*
X-118627Y372033D01*
X-118127Y372367D01*
X-117793Y372950D01*
G01Y371950D02*
Y375283D01*
G01X-115027Y371950D02*
Y375283D01*
G01Y374450D02*
X-114693Y374867D01*
X-114193Y375200D01*
X-113527Y375283D01*
X-112943Y375200D01*
X-112443Y374867D01*
X-112193Y374283D01*
Y371950D01*
G01X-106677Y374867D02*
X-107260Y375200D01*
X-107760Y375283D01*
X-108427Y375117D01*
X-108927Y374783D01*
X-109260Y374200D01*
X-109343Y373617D01*
X-109260Y373033D01*
X-108927Y372533D01*
X-108427Y372117D01*
X-107760Y371950D01*
X-107177Y372117D01*
X-106677Y372450D01*
G01X-102410Y376950D02*
Y371950D01*
G01X-103577Y375283D02*
X-101243D01*
G01X-96810D02*
Y371950D01*
G01Y376617D02*
X-96977Y376700D01*
Y376867D01*
X-96810Y376950D01*
X-96643Y376867D01*
Y376700D01*
X-96810Y376617D01*
G01X-91210Y371950D02*
X-91710Y372033D01*
X-92210Y372367D01*
X-92543Y372950D01*
X-92710Y373617D01*
X-92543Y374283D01*
X-92210Y374867D01*
X-91710Y375200D01*
X-91210Y375283D01*
X-90710Y375200D01*
X-90210Y374867D01*
X-89877Y374283D01*
X-89793Y373617D01*
X-89877Y372950D01*
X-90210Y372367D01*
X-90710Y372033D01*
X-91210Y371950D01*
G01X-87027D02*
Y375283D01*
G01Y374450D02*
X-86693Y374867D01*
X-86193Y375200D01*
X-85527Y375283D01*
X-84943Y375200D01*
X-84443Y374867D01*
X-84193Y374283D01*
Y371950D01*
G01X-78510D02*
Y375283D01*
G01Y374700D02*
X-78843Y375033D01*
X-79343Y375200D01*
X-79927Y375283D01*
X-80510Y375117D01*
X-81010Y374783D01*
X-81343Y374283D01*
X-81510Y373617D01*
X-81343Y372950D01*
X-81010Y372450D01*
X-80510Y372117D01*
X-79927Y371950D01*
X-79343Y372033D01*
X-78843Y372283D01*
X-78510Y372617D01*
G01X-74410Y371950D02*
Y376950D01*
G01X-64710Y370283D02*
Y375283D01*
G01Y374533D02*
X-64293Y374950D01*
X-63877Y375200D01*
X-63210Y375283D01*
X-62627Y375200D01*
X-62043Y374783D01*
X-61793Y374200D01*
X-61710Y373617D01*
X-61793Y373033D01*
X-62043Y372450D01*
X-62543Y372117D01*
X-63210Y371950D01*
X-63793Y372033D01*
X-64377Y372283D01*
X-64710Y372617D01*
G01X-56110Y371950D02*
Y375283D01*
G01Y374700D02*
X-56443Y375033D01*
X-56943Y375200D01*
X-57527Y375283D01*
X-58110Y375117D01*
X-58610Y374783D01*
X-58943Y374283D01*
X-59110Y373617D01*
X-58943Y372950D01*
X-58610Y372450D01*
X-58110Y372117D01*
X-57527Y371950D01*
X-56943Y372033D01*
X-56443Y372283D01*
X-56110Y372617D01*
G01X-50510Y376950D02*
Y371950D01*
G01Y372700D02*
X-50843Y372283D01*
X-51343Y372033D01*
X-51927Y371950D01*
X-52593Y372117D01*
X-53093Y372533D01*
X-53427Y373033D01*
X-53510Y373617D01*
X-53427Y374200D01*
X-53093Y374700D01*
X-52593Y375117D01*
X-51927Y375283D01*
X-51343Y375200D01*
X-50927Y375033D01*
X-50510Y374700D01*
G01X-40810Y375283D02*
Y371950D01*
G01Y376617D02*
X-40977Y376700D01*
Y376867D01*
X-40810Y376950D01*
X-40643Y376867D01*
Y376700D01*
X-40810Y376617D01*
G01X-36627Y371950D02*
Y375283D01*
G01Y374450D02*
X-36293Y374867D01*
X-35793Y375200D01*
X-35127Y375283D01*
X-34543Y375200D01*
X-34043Y374867D01*
X-33793Y374283D01*
Y371950D01*
G01X-22510D02*
Y375283D01*
G01Y374700D02*
X-22843Y375033D01*
X-23343Y375200D01*
X-23927Y375283D01*
X-24510Y375117D01*
X-25010Y374783D01*
X-25343Y374283D01*
X-25510Y373617D01*
X-25343Y372950D01*
X-25010Y372450D01*
X-24510Y372117D01*
X-23927Y371950D01*
X-23343Y372033D01*
X-22843Y372283D01*
X-22510Y372617D01*
G01X-18410Y371950D02*
Y376950D01*
G01X-12810Y371950D02*
Y376950D01*
G01X-3110Y370283D02*
Y375283D01*
G01Y374533D02*
X-2693Y374950D01*
X-2277Y375200D01*
X-1610Y375283D01*
X-1027Y375200D01*
X-443Y374783D01*
X-193Y374200D01*
X-110Y373617D01*
X-193Y373033D01*
X-443Y372450D01*
X-943Y372117D01*
X-1610Y371950D01*
X-2193Y372033D01*
X-2777Y372283D01*
X-3110Y372617D01*
G01X2823Y371950D02*
Y375283D01*
G01Y374617D02*
X3240Y374950D01*
X3657Y375200D01*
X4240Y375283D01*
X4657Y375200D01*
X5157Y374950D01*
G01X9590Y371950D02*
X9090Y372033D01*
X8590Y372367D01*
X8257Y372950D01*
X8090Y373617D01*
X8257Y374283D01*
X8590Y374867D01*
X9090Y375200D01*
X9590Y375283D01*
X10090Y375200D01*
X10590Y374867D01*
X10923Y374283D01*
X11007Y373617D01*
X10923Y372950D01*
X10590Y372367D01*
X10090Y372033D01*
X9590Y371950D01*
G01X16690Y376950D02*
Y371950D01*
G01Y372700D02*
X16357Y372283D01*
X15857Y372033D01*
X15273Y371950D01*
X14607Y372117D01*
X14107Y372533D01*
X13773Y373033D01*
X13690Y373617D01*
X13773Y374200D01*
X14107Y374700D01*
X14607Y375117D01*
X15273Y375283D01*
X15857Y375200D01*
X16273Y375033D01*
X16690Y374700D01*
G01X19373Y375283D02*
Y372950D01*
X19707Y372367D01*
X20207Y372033D01*
X20790Y371950D01*
X21373Y372033D01*
X21873Y372367D01*
X22207Y372950D01*
G01Y371950D02*
Y375283D01*
G01X27723Y374867D02*
X27140Y375200D01*
X26640Y375283D01*
X25973Y375117D01*
X25473Y374783D01*
X25140Y374200D01*
X25057Y373617D01*
X25140Y373033D01*
X25473Y372533D01*
X25973Y372117D01*
X26640Y371950D01*
X27223Y372117D01*
X27723Y372450D01*
G01X31990Y376950D02*
Y371950D01*
G01X30823Y375283D02*
X33157D01*
G01X36340Y372533D02*
X36757Y372200D01*
X37340Y371950D01*
X37840D01*
X38340Y372117D01*
X38673Y372367D01*
X38840Y372700D01*
X38757Y373200D01*
X38423Y373450D01*
X36923Y373950D01*
X36590Y374533D01*
X36757Y374950D01*
X37090Y375200D01*
X37590Y375283D01*
X38090Y375200D01*
X38590Y374950D01*
G01X43190Y371783D02*
X43023Y371867D01*
Y372033D01*
X43190Y372117D01*
X43357Y372033D01*
Y371867D01*
X43190Y371783D01*
G01X48373Y370283D02*
X47540Y371117D01*
X47123Y371950D01*
Y375283D01*
X47540Y376117D01*
X48373Y376950D01*
G01X53390D02*
X55390D01*
G01X54390D02*
Y371950D01*
G01X53390D02*
X55390D01*
G01X58740Y372533D02*
X59157Y372200D01*
X59740Y371950D01*
X60240D01*
X60740Y372117D01*
X61073Y372367D01*
X61240Y372700D01*
X61157Y373200D01*
X60823Y373450D01*
X59323Y373950D01*
X58990Y374533D01*
X59157Y374950D01*
X59490Y375200D01*
X59990Y375283D01*
X60490Y375200D01*
X60990Y374950D01*
G01X65590Y371950D02*
X65090Y372033D01*
X64590Y372367D01*
X64257Y372950D01*
X64090Y373617D01*
X64257Y374283D01*
X64590Y374867D01*
X65090Y375200D01*
X65590Y375283D01*
X66090Y375200D01*
X66590Y374867D01*
X66923Y374283D01*
X67007Y373617D01*
X66923Y372950D01*
X66590Y372367D01*
X66090Y372033D01*
X65590Y371950D01*
G01X71190D02*
Y376950D01*
G01X78290Y371950D02*
Y375283D01*
G01Y374700D02*
X77957Y375033D01*
X77457Y375200D01*
X76873Y375283D01*
X76290Y375117D01*
X75790Y374783D01*
X75457Y374283D01*
X75290Y373617D01*
X75457Y372950D01*
X75790Y372450D01*
X76290Y372117D01*
X76873Y371950D01*
X77457Y372033D01*
X77957Y372283D01*
X78290Y372617D01*
G01X82390Y376950D02*
Y371950D01*
G01X81223Y375283D02*
X83557D01*
G01X86740Y374200D02*
X89407D01*
X89157Y374783D01*
X88740Y375117D01*
X88157Y375283D01*
X87573Y375200D01*
X87073Y374950D01*
X86740Y374367D01*
X86573Y373867D01*
Y373367D01*
X86740Y372867D01*
X87157Y372367D01*
X87657Y372033D01*
X88240Y371950D01*
X88823Y372117D01*
X89407Y372617D01*
G01X97690Y370283D02*
Y375283D01*
G01Y374533D02*
X98107Y374950D01*
X98523Y375200D01*
X99190Y375283D01*
X99773Y375200D01*
X100357Y374783D01*
X100607Y374200D01*
X100690Y373617D01*
X100607Y373033D01*
X100357Y372450D01*
X99857Y372117D01*
X99190Y371950D01*
X98607Y372033D01*
X98023Y372283D01*
X97690Y372617D01*
G01X106290Y371950D02*
Y375283D01*
G01Y374700D02*
X105957Y375033D01*
X105457Y375200D01*
X104873Y375283D01*
X104290Y375117D01*
X103790Y374783D01*
X103457Y374283D01*
X103290Y373617D01*
X103457Y372950D01*
X103790Y372450D01*
X104290Y372117D01*
X104873Y371950D01*
X105457Y372033D01*
X105957Y372283D01*
X106290Y372617D01*
G01X111890Y376950D02*
Y371950D01*
G01Y372700D02*
X111557Y372283D01*
X111057Y372033D01*
X110473Y371950D01*
X109807Y372117D01*
X109307Y372533D01*
X108973Y373033D01*
X108890Y373617D01*
X108973Y374200D01*
X109307Y374700D01*
X109807Y375117D01*
X110473Y375283D01*
X111057Y375200D01*
X111473Y375033D01*
X111890Y374700D01*
G01X-135877Y30963D02*
X-135610Y31163D01*
X-135410Y31497D01*
X-135277Y31963D01*
X-135410Y32363D01*
X-135677Y32630D01*
X-136143Y32830D01*
X-137943D01*
Y28830D01*
X-135743D01*
X-135277Y29097D01*
X-135010Y29497D01*
X-134877Y29963D01*
X-135010Y30430D01*
X-135410Y30830D01*
X-135877Y30963D01*
X-137943D01*
G01X-138077Y78330D02*
X-136410Y82330D01*
X-134743Y78330D01*
G01X-135343Y79730D02*
X-137477D01*
G01X-97383Y55537D02*
X-97783Y55737D01*
X-98250Y55870D01*
X-98783D01*
X-99383Y55670D01*
X-99850Y55337D01*
X-100183Y54937D01*
X-100450Y54270D01*
X-100517Y53670D01*
X-100383Y53070D01*
X-100183Y52670D01*
X-99783Y52270D01*
X-99317Y52003D01*
X-98850Y51870D01*
X-98383D01*
X-97917Y52003D01*
X-97517Y52203D01*
X-97183Y52470D01*
G01X-63500Y91500D02*
Y-97500D01*
G01Y32500D02*
X236000D01*
G01X-56723Y58927D02*
X-56390Y59177D01*
X-56140Y59593D01*
X-55973Y60177D01*
X-56140Y60677D01*
X-56473Y61010D01*
X-57057Y61260D01*
X-59307D01*
Y56260D01*
X-56557D01*
X-55973Y56593D01*
X-55640Y57093D01*
X-55473Y57677D01*
X-55640Y58260D01*
X-56140Y58760D01*
X-56723Y58927D01*
X-59307D01*
G01X-53290Y56093D02*
X-50290Y61260D01*
G01X-48273Y56260D02*
X-46190Y61260D01*
X-44107Y56260D01*
G01X-44857Y58010D02*
X-47523D01*
G01X-63500Y64500D02*
X236000D01*
G01X-55523Y-43113D02*
X-55190Y-42863D01*
X-54940Y-42447D01*
X-54773Y-41863D01*
X-54940Y-41363D01*
X-55273Y-41030D01*
X-55857Y-40780D01*
X-58107D01*
Y-45780D01*
X-55357D01*
X-54773Y-45447D01*
X-54440Y-44947D01*
X-54273Y-44363D01*
X-54440Y-43780D01*
X-54940Y-43280D01*
X-55523Y-43113D01*
X-58107D01*
G01X-52007Y-42447D02*
Y-44780D01*
X-51673Y-45363D01*
X-51173Y-45697D01*
X-50590Y-45780D01*
X-50007Y-45697D01*
X-49507Y-45363D01*
X-49173Y-44780D01*
G01Y-45780D02*
Y-42447D01*
G01X-47490Y-45780D02*
Y-42447D01*
G01Y-43363D02*
X-47240Y-42947D01*
X-46823Y-42613D01*
X-46240Y-42447D01*
X-45657Y-42613D01*
X-45240Y-42947D01*
X-44990Y-43363D01*
Y-45780D01*
G01Y-43363D02*
X-44740Y-42947D01*
X-44323Y-42613D01*
X-43740Y-42447D01*
X-43157Y-42613D01*
X-42740Y-42947D01*
X-42490Y-43447D01*
Y-45780D01*
G01X-40890Y-47447D02*
Y-42447D01*
G01Y-43197D02*
X-40473Y-42780D01*
X-40057Y-42530D01*
X-39390Y-42447D01*
X-38807Y-42530D01*
X-38223Y-42947D01*
X-37973Y-43530D01*
X-37890Y-44113D01*
X-37973Y-44697D01*
X-38223Y-45280D01*
X-38723Y-45613D01*
X-39390Y-45780D01*
X-39973Y-45697D01*
X-40557Y-45447D01*
X-40890Y-45113D01*
G01X-56980Y-4787D02*
X-55480Y-8120D01*
X-53980Y-4787D01*
G01X-49880D02*
Y-8120D01*
G01Y-3453D02*
X-50047Y-3370D01*
Y-3203D01*
X-49880Y-3120D01*
X-49713Y-3203D01*
Y-3370D01*
X-49880Y-3453D01*
G01X-42780Y-8120D02*
Y-4787D01*
G01Y-5370D02*
X-43113Y-5037D01*
X-43613Y-4870D01*
X-44197Y-4787D01*
X-44780Y-4953D01*
X-45280Y-5287D01*
X-45613Y-5787D01*
X-45780Y-6453D01*
X-45613Y-7120D01*
X-45280Y-7620D01*
X-44780Y-7953D01*
X-44197Y-8120D01*
X-43613Y-8037D01*
X-43113Y-7787D01*
X-42780Y-7453D01*
G01X-57433Y4360D02*
Y9360D01*
X-55767D01*
X-55100Y9110D01*
X-54600Y8777D01*
X-54183Y8277D01*
X-53850Y7693D01*
X-53767Y6860D01*
X-53850Y6027D01*
X-54183Y5443D01*
X-54600Y4943D01*
X-55100Y4610D01*
X-55767Y4360D01*
X-57433D01*
G01X-50000Y7693D02*
Y4360D01*
G01Y9027D02*
X-50167Y9110D01*
Y9277D01*
X-50000Y9360D01*
X-49833Y9277D01*
Y9110D01*
X-50000Y9027D01*
G01X-46900Y4360D02*
Y7693D01*
G01Y6777D02*
X-46650Y7193D01*
X-46233Y7527D01*
X-45650Y7693D01*
X-45067Y7527D01*
X-44650Y7193D01*
X-44400Y6777D01*
Y4360D01*
G01Y6777D02*
X-44150Y7193D01*
X-43733Y7527D01*
X-43150Y7693D01*
X-42567Y7527D01*
X-42150Y7193D01*
X-41900Y6693D01*
Y4360D01*
G01X-40300Y2693D02*
Y7693D01*
G01Y6943D02*
X-39883Y7360D01*
X-39467Y7610D01*
X-38800Y7693D01*
X-38217Y7610D01*
X-37633Y7193D01*
X-37383Y6610D01*
X-37300Y6027D01*
X-37383Y5443D01*
X-37633Y4860D01*
X-38133Y4527D01*
X-38800Y4360D01*
X-39383Y4443D01*
X-39967Y4693D01*
X-40300Y5027D01*
G01X-33200Y4360D02*
Y9360D01*
G01X-28850Y6610D02*
X-26183D01*
X-26433Y7193D01*
X-26850Y7527D01*
X-27433Y7693D01*
X-28017Y7610D01*
X-28517Y7360D01*
X-28850Y6777D01*
X-29017Y6277D01*
Y5777D01*
X-28850Y5277D01*
X-28433Y4777D01*
X-27933Y4443D01*
X-27350Y4360D01*
X-26767Y4527D01*
X-26183Y5027D01*
G01X-16900Y4360D02*
Y8610D01*
X-16733Y9027D01*
X-16400Y9277D01*
X-15900Y9360D01*
X-15400Y9193D01*
X-15150Y8777D01*
G01X-16150Y7360D02*
X-17817D01*
G01X-10800Y4360D02*
X-11300Y4443D01*
X-11800Y4777D01*
X-12133Y5360D01*
X-12300Y6027D01*
X-12133Y6693D01*
X-11800Y7277D01*
X-11300Y7610D01*
X-10800Y7693D01*
X-10300Y7610D01*
X-9800Y7277D01*
X-9467Y6693D01*
X-9383Y6027D01*
X-9467Y5360D01*
X-9800Y4777D01*
X-10300Y4443D01*
X-10800Y4360D01*
G01X-6367D02*
Y7693D01*
G01Y7027D02*
X-5950Y7360D01*
X-5533Y7610D01*
X-4950Y7693D01*
X-4533Y7610D01*
X-4033Y7360D01*
G01X6000Y4360D02*
X5500Y4443D01*
X5000Y4777D01*
X4667Y5360D01*
X4500Y6027D01*
X4667Y6693D01*
X5000Y7277D01*
X5500Y7610D01*
X6000Y7693D01*
X6500Y7610D01*
X7000Y7277D01*
X7333Y6693D01*
X7417Y6027D01*
X7333Y5360D01*
X7000Y4777D01*
X6500Y4443D01*
X6000Y4360D01*
G01X10183Y7693D02*
Y5360D01*
X10517Y4777D01*
X11017Y4443D01*
X11600Y4360D01*
X12183Y4443D01*
X12683Y4777D01*
X13017Y5360D01*
G01Y4360D02*
Y7693D01*
G01X17200Y9360D02*
Y4360D01*
G01X16033Y7693D02*
X18367D01*
G01X21550Y6610D02*
X24217D01*
X23967Y7193D01*
X23550Y7527D01*
X22967Y7693D01*
X22383Y7610D01*
X21883Y7360D01*
X21550Y6777D01*
X21383Y6277D01*
Y5777D01*
X21550Y5277D01*
X21967Y4777D01*
X22467Y4443D01*
X23050Y4360D01*
X23633Y4527D01*
X24217Y5027D01*
G01X27233Y4360D02*
Y7693D01*
G01Y7027D02*
X27650Y7360D01*
X28067Y7610D01*
X28650Y7693D01*
X29067Y7610D01*
X29567Y7360D01*
G01X41100Y4360D02*
Y7693D01*
G01Y7110D02*
X40767Y7443D01*
X40267Y7610D01*
X39683Y7693D01*
X39100Y7527D01*
X38600Y7193D01*
X38267Y6693D01*
X38100Y6027D01*
X38267Y5360D01*
X38600Y4860D01*
X39100Y4527D01*
X39683Y4360D01*
X40267Y4443D01*
X40767Y4693D01*
X41100Y5027D01*
G01X43783Y4360D02*
Y7693D01*
G01Y6860D02*
X44117Y7277D01*
X44617Y7610D01*
X45283Y7693D01*
X45867Y7610D01*
X46367Y7277D01*
X46617Y6693D01*
Y4360D01*
G01X52300Y9360D02*
Y4360D01*
G01Y5110D02*
X51967Y4693D01*
X51467Y4443D01*
X50883Y4360D01*
X50217Y4527D01*
X49717Y4943D01*
X49383Y5443D01*
X49300Y6027D01*
X49383Y6610D01*
X49717Y7110D01*
X50217Y7527D01*
X50883Y7693D01*
X51467Y7610D01*
X51883Y7443D01*
X52300Y7110D01*
G01X62000Y7693D02*
Y4360D01*
G01Y9027D02*
X61833Y9110D01*
Y9277D01*
X62000Y9360D01*
X62167Y9277D01*
Y9110D01*
X62000Y9027D01*
G01X66183Y4360D02*
Y7693D01*
G01Y6860D02*
X66517Y7277D01*
X67017Y7610D01*
X67683Y7693D01*
X68267Y7610D01*
X68767Y7277D01*
X69017Y6693D01*
Y4360D01*
G01X71783D02*
Y7693D01*
G01Y6860D02*
X72117Y7277D01*
X72617Y7610D01*
X73283Y7693D01*
X73867Y7610D01*
X74367Y7277D01*
X74617Y6693D01*
Y4360D01*
G01X77550Y6610D02*
X80217D01*
X79967Y7193D01*
X79550Y7527D01*
X78967Y7693D01*
X78383Y7610D01*
X77883Y7360D01*
X77550Y6777D01*
X77383Y6277D01*
Y5777D01*
X77550Y5277D01*
X77967Y4777D01*
X78467Y4443D01*
X79050Y4360D01*
X79633Y4527D01*
X80217Y5027D01*
G01X83233Y4360D02*
Y7693D01*
G01Y7027D02*
X83650Y7360D01*
X84067Y7610D01*
X84650Y7693D01*
X85067Y7610D01*
X85567Y7360D01*
G01X95600Y4360D02*
Y9360D01*
G01X102700Y4360D02*
Y7693D01*
G01Y7110D02*
X102367Y7443D01*
X101867Y7610D01*
X101283Y7693D01*
X100700Y7527D01*
X100200Y7193D01*
X99867Y6693D01*
X99700Y6027D01*
X99867Y5360D01*
X100200Y4860D01*
X100700Y4527D01*
X101283Y4360D01*
X101867Y4443D01*
X102367Y4693D01*
X102700Y5027D01*
G01X105550Y4943D02*
X105967Y4610D01*
X106550Y4360D01*
X107050D01*
X107550Y4527D01*
X107883Y4777D01*
X108050Y5110D01*
X107967Y5610D01*
X107633Y5860D01*
X106133Y6360D01*
X105800Y6943D01*
X105967Y7360D01*
X106300Y7610D01*
X106800Y7693D01*
X107300Y7610D01*
X107800Y7360D01*
G01X111150Y6610D02*
X113817D01*
X113567Y7193D01*
X113150Y7527D01*
X112567Y7693D01*
X111983Y7610D01*
X111483Y7360D01*
X111150Y6777D01*
X110983Y6277D01*
Y5777D01*
X111150Y5277D01*
X111567Y4777D01*
X112067Y4443D01*
X112650Y4360D01*
X113233Y4527D01*
X113817Y5027D01*
G01X116833Y4360D02*
Y7693D01*
G01Y7027D02*
X117250Y7360D01*
X117667Y7610D01*
X118250Y7693D01*
X118667Y7610D01*
X119167Y7360D01*
G01X-56673Y22540D02*
X-54590Y27540D01*
X-52507Y22540D01*
G01X-53257Y24290D02*
X-55923D01*
G01X-50407Y22540D02*
Y25873D01*
G01Y25040D02*
X-50073Y25457D01*
X-49573Y25790D01*
X-48907Y25873D01*
X-48323Y25790D01*
X-47823Y25457D01*
X-47573Y24873D01*
Y22540D01*
G01X-44557Y21290D02*
X-43973Y20957D01*
X-43307Y20873D01*
X-42723Y20957D01*
X-42223Y21373D01*
X-41890Y21957D01*
Y25873D01*
G01Y25207D02*
X-42223Y25540D01*
X-42723Y25790D01*
X-43307Y25873D01*
X-43973Y25707D01*
X-44390Y25373D01*
X-44723Y24790D01*
X-44890Y24207D01*
X-44807Y23707D01*
X-44473Y23123D01*
X-43973Y22707D01*
X-43307Y22540D01*
X-42807Y22623D01*
X-42223Y22957D01*
X-41890Y23290D01*
G01X-37790Y22540D02*
Y27540D01*
G01X-33440Y24790D02*
X-30773D01*
X-31023Y25373D01*
X-31440Y25707D01*
X-32023Y25873D01*
X-32607Y25790D01*
X-33107Y25540D01*
X-33440Y24957D01*
X-33607Y24457D01*
Y23957D01*
X-33440Y23457D01*
X-33023Y22957D01*
X-32523Y22623D01*
X-31940Y22540D01*
X-31357Y22707D01*
X-30773Y23207D01*
G01X-27007Y20873D02*
X-27840Y21707D01*
X-28257Y22540D01*
Y25873D01*
X-27840Y26707D01*
X-27007Y27540D01*
G01X-9373Y20873D02*
X-8540Y21707D01*
X-8123Y22540D01*
Y25873D01*
X-8540Y26707D01*
X-9373Y27540D01*
G01X-57867Y85960D02*
Y80960D01*
X-54533D01*
G01X-49100D02*
Y84293D01*
G01Y83710D02*
X-49433Y84043D01*
X-49933Y84210D01*
X-50517Y84293D01*
X-51100Y84127D01*
X-51600Y83793D01*
X-51933Y83293D01*
X-52100Y82627D01*
X-51933Y81960D01*
X-51600Y81460D01*
X-51100Y81127D01*
X-50517Y80960D01*
X-49933Y81043D01*
X-49433Y81293D01*
X-49100Y81627D01*
G01X-46250Y81543D02*
X-45833Y81210D01*
X-45250Y80960D01*
X-44750D01*
X-44250Y81127D01*
X-43917Y81377D01*
X-43750Y81710D01*
X-43833Y82210D01*
X-44167Y82460D01*
X-45667Y82960D01*
X-46000Y83543D01*
X-45833Y83960D01*
X-45500Y84210D01*
X-45000Y84293D01*
X-44500Y84210D01*
X-44000Y83960D01*
G01X-40650Y83210D02*
X-37983D01*
X-38233Y83793D01*
X-38650Y84127D01*
X-39233Y84293D01*
X-39817Y84210D01*
X-40317Y83960D01*
X-40650Y83377D01*
X-40817Y82877D01*
Y82377D01*
X-40650Y81877D01*
X-40233Y81377D01*
X-39733Y81043D01*
X-39150Y80960D01*
X-38567Y81127D01*
X-37983Y81627D01*
G01X-34967Y80960D02*
Y84293D01*
G01Y83627D02*
X-34550Y83960D01*
X-34133Y84210D01*
X-33550Y84293D01*
X-33133Y84210D01*
X-32633Y83960D01*
G01X-24100Y84293D02*
X-22600Y80960D01*
X-21100Y84293D01*
G01X-17000D02*
Y80960D01*
G01Y85627D02*
X-17167Y85710D01*
Y85877D01*
X-17000Y85960D01*
X-16833Y85877D01*
Y85710D01*
X-17000Y85627D01*
G01X-9900Y80960D02*
Y84293D01*
G01Y83710D02*
X-10233Y84043D01*
X-10733Y84210D01*
X-11317Y84293D01*
X-11900Y84127D01*
X-12400Y83793D01*
X-12733Y83293D01*
X-12900Y82627D01*
X-12733Y81960D01*
X-12400Y81460D01*
X-11900Y81127D01*
X-11317Y80960D01*
X-10733Y81043D01*
X-10233Y81293D01*
X-9900Y81627D01*
G01X-1450Y81543D02*
X-1033Y81210D01*
X-450Y80960D01*
X50D01*
X550Y81127D01*
X883Y81377D01*
X1050Y81710D01*
X967Y82210D01*
X633Y82460D01*
X-867Y82960D01*
X-1200Y83543D01*
X-1033Y83960D01*
X-700Y84210D01*
X-200Y84293D01*
X300Y84210D01*
X800Y83960D01*
G01X5400Y84293D02*
Y80960D01*
G01Y85627D02*
X5233Y85710D01*
Y85877D01*
X5400Y85960D01*
X5567Y85877D01*
Y85710D01*
X5400Y85627D01*
G01X9750Y84293D02*
X12250D01*
X9750Y80960D01*
X12250D01*
G01X15350Y83210D02*
X18017D01*
X17767Y83793D01*
X17350Y84127D01*
X16767Y84293D01*
X16183Y84210D01*
X15683Y83960D01*
X15350Y83377D01*
X15183Y82877D01*
Y82377D01*
X15350Y81877D01*
X15767Y81377D01*
X16267Y81043D01*
X16850Y80960D01*
X17433Y81127D01*
X18017Y81627D01*
G01X25717Y84293D02*
X26717Y80960D01*
X27800Y84293D01*
X28883Y80960D01*
X29883Y84293D01*
G01X33400D02*
Y80960D01*
G01Y85627D02*
X33233Y85710D01*
Y85877D01*
X33400Y85960D01*
X33567Y85877D01*
Y85710D01*
X33400Y85627D01*
G01X39000Y85960D02*
Y80960D01*
G01X37833Y84293D02*
X40167D01*
G01X43183Y80960D02*
Y85960D01*
G01Y83543D02*
X43600Y83960D01*
X44017Y84210D01*
X44683Y84293D01*
X45183Y84210D01*
X45767Y83877D01*
X46017Y83377D01*
Y80960D01*
G01X50200D02*
X49700Y81043D01*
X49200Y81377D01*
X48867Y81960D01*
X48700Y82627D01*
X48867Y83293D01*
X49200Y83877D01*
X49700Y84210D01*
X50200Y84293D01*
X50700Y84210D01*
X51200Y83877D01*
X51533Y83293D01*
X51617Y82627D01*
X51533Y81960D01*
X51200Y81377D01*
X50700Y81043D01*
X50200Y80960D01*
G01X54383Y84293D02*
Y81960D01*
X54717Y81377D01*
X55217Y81043D01*
X55800Y80960D01*
X56383Y81043D01*
X56883Y81377D01*
X57217Y81960D01*
G01Y80960D02*
Y84293D01*
G01X61400Y85960D02*
Y80960D01*
G01X60233Y84293D02*
X62567D01*
G01X71100Y79293D02*
Y84293D01*
G01Y83543D02*
X71517Y83960D01*
X71933Y84210D01*
X72600Y84293D01*
X73183Y84210D01*
X73767Y83793D01*
X74017Y83210D01*
X74100Y82627D01*
X74017Y82043D01*
X73767Y81460D01*
X73267Y81127D01*
X72600Y80960D01*
X72017Y81043D01*
X71433Y81293D01*
X71100Y81627D01*
G01X78200Y80960D02*
Y85960D01*
G01X85300Y80960D02*
Y84293D01*
G01Y83710D02*
X84967Y84043D01*
X84467Y84210D01*
X83883Y84293D01*
X83300Y84127D01*
X82800Y83793D01*
X82467Y83293D01*
X82300Y82627D01*
X82467Y81960D01*
X82800Y81460D01*
X83300Y81127D01*
X83883Y80960D01*
X84467Y81043D01*
X84967Y81293D01*
X85300Y81627D01*
G01X89400Y85960D02*
Y80960D01*
G01X88233Y84293D02*
X90567D01*
G01X95000D02*
Y80960D01*
G01Y85627D02*
X94833Y85710D01*
Y85877D01*
X95000Y85960D01*
X95167Y85877D01*
Y85710D01*
X95000Y85627D01*
G01X99183Y80960D02*
Y84293D01*
G01Y83460D02*
X99517Y83877D01*
X100017Y84210D01*
X100683Y84293D01*
X101267Y84210D01*
X101767Y83877D01*
X102017Y83293D01*
Y80960D01*
G01X105033Y79710D02*
X105617Y79377D01*
X106283Y79293D01*
X106867Y79377D01*
X107367Y79793D01*
X107700Y80377D01*
Y84293D01*
G01Y83627D02*
X107367Y83960D01*
X106867Y84210D01*
X106283Y84293D01*
X105617Y84127D01*
X105200Y83793D01*
X104867Y83210D01*
X104700Y82627D01*
X104783Y82127D01*
X105117Y81543D01*
X105617Y81127D01*
X106283Y80960D01*
X106783Y81043D01*
X107367Y81377D01*
X107700Y81710D01*
G01X116983Y79293D02*
X116150Y80127D01*
X115733Y80960D01*
Y84293D01*
X116150Y85127D01*
X116983Y85960D01*
G01X123667Y83627D02*
X124000Y83877D01*
X124250Y84293D01*
X124417Y84877D01*
X124250Y85377D01*
X123917Y85710D01*
X123333Y85960D01*
X121083D01*
Y80960D01*
X123833D01*
X124417Y81293D01*
X124750Y81793D01*
X124917Y82377D01*
X124750Y82960D01*
X124250Y83460D01*
X123667Y83627D01*
X121083D01*
G01X129017Y79293D02*
X129850Y80127D01*
X130267Y80960D01*
Y84293D01*
X129850Y85127D01*
X129017Y85960D01*
G01X-54000Y393833D02*
Y390500D01*
G01Y395167D02*
X-54167Y395250D01*
Y395417D01*
X-54000Y395500D01*
X-53833Y395417D01*
Y395250D01*
X-54000Y395167D01*
G01X-48400Y395500D02*
Y390500D01*
G01X-49567Y393833D02*
X-47233D01*
G01X-44050Y392750D02*
X-41383D01*
X-41633Y393333D01*
X-42050Y393667D01*
X-42633Y393833D01*
X-43217Y393750D01*
X-43717Y393500D01*
X-44050Y392917D01*
X-44217Y392417D01*
Y391917D01*
X-44050Y391417D01*
X-43633Y390917D01*
X-43133Y390583D01*
X-42550Y390500D01*
X-41967Y390667D01*
X-41383Y391167D01*
G01X-39700Y390500D02*
Y393833D01*
G01Y392917D02*
X-39450Y393333D01*
X-39033Y393667D01*
X-38450Y393833D01*
X-37867Y393667D01*
X-37450Y393333D01*
X-37200Y392917D01*
Y390500D01*
G01Y392917D02*
X-36950Y393333D01*
X-36533Y393667D01*
X-35950Y393833D01*
X-35367Y393667D01*
X-34950Y393333D01*
X-34700Y392833D01*
Y390500D01*
G01X-14303Y26927D02*
X-14703Y27127D01*
X-15170Y27260D01*
X-15703D01*
X-16303Y27060D01*
X-16770Y26727D01*
X-17103Y26327D01*
X-17370Y25660D01*
X-17437Y25060D01*
X-17303Y24460D01*
X-17103Y24060D01*
X-16703Y23660D01*
X-16237Y23393D01*
X-15770Y23260D01*
X-15303D01*
X-14837Y23393D01*
X-14437Y23593D01*
X-14103Y23860D01*
G01X137000Y-342500D02*
Y165000D01*
G01Y406000D02*
Y123000D01*
G01X131917Y587000D02*
X134000Y582000D01*
X136083Y587000D01*
G01X137767Y583000D02*
X138267Y582417D01*
X138933Y582083D01*
X139683Y582000D01*
X140350Y582083D01*
X141017Y582500D01*
X141433Y583000D01*
X141517Y583500D01*
X141350Y584083D01*
X140767Y584500D01*
X140183Y584667D01*
X139433D01*
G01X140183D02*
X140683Y584917D01*
X141100Y585333D01*
X141267Y585833D01*
X141100Y586333D01*
X140683Y586750D01*
X139933Y587000D01*
X139183Y586917D01*
X138433Y586583D01*
G01X145200Y581833D02*
X145033Y581917D01*
Y582083D01*
X145200Y582167D01*
X145367Y582083D01*
Y581917D01*
X145200Y581833D01*
G01X151800Y582000D02*
Y587000D01*
X148717Y583417D01*
X152883D01*
G01X156400Y581833D02*
X156233Y581917D01*
Y582083D01*
X156400Y582167D01*
X156567Y582083D01*
Y581917D01*
X156400Y581833D01*
G01X162000Y582000D02*
Y587000D01*
X161000Y586000D01*
G01Y582000D02*
X163000D01*
G01X182817Y586167D02*
X183317Y586667D01*
X183900Y586917D01*
X184567Y587000D01*
X185400Y586833D01*
X185983Y586417D01*
X186150Y585917D01*
X186067Y585417D01*
X185733Y585000D01*
X184067Y584167D01*
X183317Y583583D01*
X182817Y582750D01*
X182650Y582000D01*
X186150D01*
G01X190000Y587000D02*
X189333Y586833D01*
X188833Y586417D01*
X188500Y585917D01*
X188250Y585250D01*
X188167Y584500D01*
X188250Y583750D01*
X188500Y583083D01*
X188833Y582583D01*
X189333Y582167D01*
X190000Y582000D01*
X190667Y582167D01*
X191167Y582583D01*
X191500Y583083D01*
X191750Y583750D01*
X191833Y584500D01*
X191750Y585250D01*
X191500Y585917D01*
X191167Y586417D01*
X190667Y586833D01*
X190000Y587000D01*
G01X195600Y582000D02*
Y587000D01*
X194600Y586000D01*
G01Y582000D02*
X196600D01*
G01X199367Y582750D02*
X199867Y582333D01*
X200450Y582083D01*
X201200Y582000D01*
X201950Y582167D01*
X202533Y582500D01*
X202950Y583083D01*
X203033Y583750D01*
X202867Y584417D01*
X202450Y584833D01*
X201867Y585167D01*
X201283Y585250D01*
X200700Y585167D01*
X199950Y584833D01*
X200200Y587000D01*
X202450D01*
G01X205300Y581833D02*
X208300Y587000D01*
G01X212400D02*
X211733Y586833D01*
X211233Y586417D01*
X210900Y585917D01*
X210650Y585250D01*
X210567Y584500D01*
X210650Y583750D01*
X210900Y583083D01*
X211233Y582583D01*
X211733Y582167D01*
X212400Y582000D01*
X213067Y582167D01*
X213567Y582583D01*
X213900Y583083D01*
X214150Y583750D01*
X214233Y584500D01*
X214150Y585250D01*
X213900Y585917D01*
X213567Y586417D01*
X213067Y586833D01*
X212400Y587000D01*
G01X216417Y584083D02*
X217000Y584667D01*
X217500Y585000D01*
X218167Y585167D01*
X218750Y585000D01*
X219167Y584667D01*
X219500Y584167D01*
X219583Y583583D01*
X219500Y583083D01*
X219167Y582583D01*
X218667Y582167D01*
X218083Y582000D01*
X217417Y582167D01*
X216833Y582667D01*
X216500Y583417D01*
X216417Y584250D01*
X216583Y585333D01*
X216833Y585917D01*
X217250Y586500D01*
X217833Y586917D01*
X218417Y587000D01*
X219000Y586833D01*
X219417Y586417D01*
G01X146833Y-338000D02*
Y-333000D01*
X149000Y-337167D01*
X151167Y-333000D01*
Y-338000D01*
G01X153183Y-334667D02*
Y-337000D01*
X153517Y-337583D01*
X154017Y-337917D01*
X154600Y-338000D01*
X155183Y-337917D01*
X155683Y-337583D01*
X156017Y-337000D01*
G01Y-338000D02*
Y-334667D01*
G01X158950Y-337417D02*
X159367Y-337750D01*
X159950Y-338000D01*
X160450D01*
X160950Y-337833D01*
X161283Y-337583D01*
X161450Y-337250D01*
X161367Y-336750D01*
X161033Y-336500D01*
X159533Y-336000D01*
X159200Y-335417D01*
X159367Y-335000D01*
X159700Y-334750D01*
X160200Y-334667D01*
X160700Y-334750D01*
X161200Y-335000D01*
G01X165800Y-333000D02*
Y-338000D01*
G01X164633Y-334667D02*
X166967D01*
G01X176500Y-338000D02*
Y-333750D01*
X176667Y-333333D01*
X177000Y-333083D01*
X177500Y-333000D01*
X178000Y-333167D01*
X178250Y-333583D01*
G01X177250Y-335000D02*
X175583D01*
G01X182600Y-338000D02*
X182100Y-337917D01*
X181600Y-337583D01*
X181267Y-337000D01*
X181100Y-336333D01*
X181267Y-335667D01*
X181600Y-335083D01*
X182100Y-334750D01*
X182600Y-334667D01*
X183100Y-334750D01*
X183600Y-335083D01*
X183933Y-335667D01*
X184017Y-336333D01*
X183933Y-337000D01*
X183600Y-337583D01*
X183100Y-337917D01*
X182600Y-338000D01*
G01X188200D02*
Y-333000D01*
G01X193800Y-338000D02*
Y-333000D01*
G01X199400Y-338000D02*
X198900Y-337917D01*
X198400Y-337583D01*
X198067Y-337000D01*
X197900Y-336333D01*
X198067Y-335667D01*
X198400Y-335083D01*
X198900Y-334750D01*
X199400Y-334667D01*
X199900Y-334750D01*
X200400Y-335083D01*
X200733Y-335667D01*
X200817Y-336333D01*
X200733Y-337000D01*
X200400Y-337583D01*
X199900Y-337917D01*
X199400Y-338000D01*
G01X202917Y-334667D02*
X203917Y-338000D01*
X205000Y-334667D01*
X206083Y-338000D01*
X207083Y-334667D01*
G01X150667Y-321500D02*
X147333Y-319833D01*
X150667Y-318167D01*
G01X153517Y-320583D02*
X155683D01*
G01Y-319083D02*
X153517D01*
G01X160200Y-321500D02*
Y-316500D01*
X159200Y-317500D01*
G01Y-321500D02*
X161200D01*
G01X165800Y-321667D02*
X165633Y-321583D01*
Y-321417D01*
X165800Y-321333D01*
X165967Y-321417D01*
Y-321583D01*
X165800Y-321667D01*
G01X172400Y-321500D02*
Y-316500D01*
X169317Y-320083D01*
X173483D01*
G01X174500Y-321500D02*
Y-318167D01*
G01Y-319083D02*
X174750Y-318667D01*
X175167Y-318333D01*
X175750Y-318167D01*
X176333Y-318333D01*
X176750Y-318667D01*
X177000Y-319083D01*
Y-321500D01*
G01Y-319083D02*
X177250Y-318667D01*
X177667Y-318333D01*
X178250Y-318167D01*
X178833Y-318333D01*
X179250Y-318667D01*
X179500Y-319167D01*
Y-321500D01*
G01X182600Y-318167D02*
Y-321500D01*
G01Y-316833D02*
X182433Y-316750D01*
Y-316583D01*
X182600Y-316500D01*
X182767Y-316583D01*
Y-316750D01*
X182600Y-316833D01*
G01X188200Y-321500D02*
Y-316500D01*
G01X149000Y-301500D02*
X148333Y-301667D01*
X147833Y-302083D01*
X147500Y-302583D01*
X147250Y-303250D01*
X147167Y-304000D01*
X147250Y-304750D01*
X147500Y-305417D01*
X147833Y-305917D01*
X148333Y-306333D01*
X149000Y-306500D01*
X149667Y-306333D01*
X150167Y-305917D01*
X150500Y-305417D01*
X150750Y-304750D01*
X150833Y-304000D01*
X150750Y-303250D01*
X150500Y-302583D01*
X150167Y-302083D01*
X149667Y-301667D01*
X149000Y-301500D01*
G01X154600Y-306667D02*
X154433Y-306583D01*
Y-306417D01*
X154600Y-306333D01*
X154767Y-306417D01*
Y-306583D01*
X154600Y-306667D01*
G01X158367Y-305500D02*
X158867Y-306083D01*
X159533Y-306417D01*
X160283Y-306500D01*
X160950Y-306417D01*
X161617Y-306000D01*
X162033Y-305500D01*
X162117Y-305000D01*
X161950Y-304417D01*
X161367Y-304000D01*
X160783Y-303833D01*
X160033D01*
G01X160783D02*
X161283Y-303583D01*
X161700Y-303167D01*
X161867Y-302667D01*
X161700Y-302167D01*
X161283Y-301750D01*
X160533Y-301500D01*
X159783Y-301583D01*
X159033Y-301917D01*
G01X163300Y-304833D02*
X164133Y-303167D01*
X164967D01*
X166633Y-306500D01*
X167467D01*
X168300Y-304833D01*
G01X171400Y-301500D02*
X170733Y-301667D01*
X170233Y-302083D01*
X169900Y-302583D01*
X169650Y-303250D01*
X169567Y-304000D01*
X169650Y-304750D01*
X169900Y-305417D01*
X170233Y-305917D01*
X170733Y-306333D01*
X171400Y-306500D01*
X172067Y-306333D01*
X172567Y-305917D01*
X172900Y-305417D01*
X173150Y-304750D01*
X173233Y-304000D01*
X173150Y-303250D01*
X172900Y-302583D01*
X172567Y-302083D01*
X172067Y-301667D01*
X171400Y-301500D01*
G01X177000Y-306667D02*
X176833Y-306583D01*
Y-306417D01*
X177000Y-306333D01*
X177167Y-306417D01*
Y-306583D01*
X177000Y-306667D01*
G01X182433Y-306500D02*
X182600Y-305417D01*
X182850Y-304500D01*
X183183Y-303667D01*
X183600Y-302750D01*
X184267Y-301500D01*
X180933D01*
G01X185700Y-306500D02*
Y-303167D01*
G01Y-304083D02*
X185950Y-303667D01*
X186367Y-303333D01*
X186950Y-303167D01*
X187533Y-303333D01*
X187950Y-303667D01*
X188200Y-304083D01*
Y-306500D01*
G01Y-304083D02*
X188450Y-303667D01*
X188867Y-303333D01*
X189450Y-303167D01*
X190033Y-303333D01*
X190450Y-303667D01*
X190700Y-304167D01*
Y-306500D01*
G01X193800Y-303167D02*
Y-306500D01*
G01Y-301833D02*
X193633Y-301750D01*
Y-301583D01*
X193800Y-301500D01*
X193967Y-301583D01*
Y-301750D01*
X193800Y-301833D01*
G01X199400Y-306500D02*
Y-301500D01*
G01X149000Y-288000D02*
X148333Y-288167D01*
X147833Y-288583D01*
X147500Y-289083D01*
X147250Y-289750D01*
X147167Y-290500D01*
X147250Y-291250D01*
X147500Y-291917D01*
X147833Y-292417D01*
X148333Y-292833D01*
X149000Y-293000D01*
X149667Y-292833D01*
X150167Y-292417D01*
X150500Y-291917D01*
X150750Y-291250D01*
X150833Y-290500D01*
X150750Y-289750D01*
X150500Y-289083D01*
X150167Y-288583D01*
X149667Y-288167D01*
X149000Y-288000D01*
G01X154600Y-293167D02*
X154433Y-293083D01*
Y-292917D01*
X154600Y-292833D01*
X154767Y-292917D01*
Y-293083D01*
X154600Y-293167D01*
G01X158367Y-292000D02*
X158867Y-292583D01*
X159533Y-292917D01*
X160283Y-293000D01*
X160950Y-292917D01*
X161617Y-292500D01*
X162033Y-292000D01*
X162117Y-291500D01*
X161950Y-290917D01*
X161367Y-290500D01*
X160783Y-290333D01*
X160033D01*
G01X160783D02*
X161283Y-290083D01*
X161700Y-289667D01*
X161867Y-289167D01*
X161700Y-288667D01*
X161283Y-288250D01*
X160533Y-288000D01*
X159783Y-288083D01*
X159033Y-288417D01*
G01X163300Y-291333D02*
X164133Y-289667D01*
X164967D01*
X166633Y-293000D01*
X167467D01*
X168300Y-291333D01*
G01X171400Y-288000D02*
X170733Y-288167D01*
X170233Y-288583D01*
X169900Y-289083D01*
X169650Y-289750D01*
X169567Y-290500D01*
X169650Y-291250D01*
X169900Y-291917D01*
X170233Y-292417D01*
X170733Y-292833D01*
X171400Y-293000D01*
X172067Y-292833D01*
X172567Y-292417D01*
X172900Y-291917D01*
X173150Y-291250D01*
X173233Y-290500D01*
X173150Y-289750D01*
X172900Y-289083D01*
X172567Y-288583D01*
X172067Y-288167D01*
X171400Y-288000D01*
G01X177000Y-293167D02*
X176833Y-293083D01*
Y-292917D01*
X177000Y-292833D01*
X177167Y-292917D01*
Y-293083D01*
X177000Y-293167D01*
G01X182433Y-293000D02*
X182600Y-291917D01*
X182850Y-291000D01*
X183183Y-290167D01*
X183600Y-289250D01*
X184267Y-288000D01*
X180933D01*
G01X185700Y-293000D02*
Y-289667D01*
G01Y-290583D02*
X185950Y-290167D01*
X186367Y-289833D01*
X186950Y-289667D01*
X187533Y-289833D01*
X187950Y-290167D01*
X188200Y-290583D01*
Y-293000D01*
G01Y-290583D02*
X188450Y-290167D01*
X188867Y-289833D01*
X189450Y-289667D01*
X190033Y-289833D01*
X190450Y-290167D01*
X190700Y-290667D01*
Y-293000D01*
G01X193800Y-289667D02*
Y-293000D01*
G01Y-288333D02*
X193633Y-288250D01*
Y-288083D01*
X193800Y-288000D01*
X193967Y-288083D01*
Y-288250D01*
X193800Y-288333D01*
G01X199400Y-293000D02*
Y-288000D01*
G01X148083Y-274833D02*
X150083D01*
G01X149000Y-273750D02*
Y-275917D01*
G01X153100Y-276667D02*
X156100Y-271500D01*
G01X159117Y-274833D02*
X161283D01*
G01X165800Y-276500D02*
Y-271500D01*
X164800Y-272500D01*
G01Y-276500D02*
X166800D01*
G01X168900D02*
Y-273167D01*
G01Y-274083D02*
X169150Y-273667D01*
X169567Y-273333D01*
X170150Y-273167D01*
X170733Y-273333D01*
X171150Y-273667D01*
X171400Y-274083D01*
Y-276500D01*
G01Y-274083D02*
X171650Y-273667D01*
X172067Y-273333D01*
X172650Y-273167D01*
X173233Y-273333D01*
X173650Y-273667D01*
X173900Y-274167D01*
Y-276500D01*
G01X177000Y-273167D02*
Y-276500D01*
G01Y-271833D02*
X176833Y-271750D01*
Y-271583D01*
X177000Y-271500D01*
X177167Y-271583D01*
Y-271750D01*
X177000Y-271833D01*
G01X182600Y-276500D02*
Y-271500D01*
G01X148083Y-248333D02*
X150083D01*
G01X149000Y-247250D02*
Y-249417D01*
G01X153100Y-250167D02*
X156100Y-245000D01*
G01X159117Y-248333D02*
X161283D01*
G01X165800Y-250000D02*
Y-245000D01*
X164800Y-246000D01*
G01Y-250000D02*
X166800D01*
G01X168900D02*
Y-246667D01*
G01Y-247583D02*
X169150Y-247167D01*
X169567Y-246833D01*
X170150Y-246667D01*
X170733Y-246833D01*
X171150Y-247167D01*
X171400Y-247583D01*
Y-250000D01*
G01Y-247583D02*
X171650Y-247167D01*
X172067Y-246833D01*
X172650Y-246667D01*
X173233Y-246833D01*
X173650Y-247167D01*
X173900Y-247667D01*
Y-250000D01*
G01X177000Y-246667D02*
Y-250000D01*
G01Y-245333D02*
X176833Y-245250D01*
Y-245083D01*
X177000Y-245000D01*
X177167Y-245083D01*
Y-245250D01*
X177000Y-245333D01*
G01X182600Y-250000D02*
Y-245000D01*
G01X148083Y-259833D02*
X150083D01*
G01X149000Y-258750D02*
Y-260917D01*
G01X153100Y-261667D02*
X156100Y-256500D01*
G01X159117Y-259833D02*
X161283D01*
G01X164217Y-257333D02*
X164717Y-256833D01*
X165300Y-256583D01*
X165967Y-256500D01*
X166800Y-256667D01*
X167383Y-257083D01*
X167550Y-257583D01*
X167467Y-258083D01*
X167133Y-258500D01*
X165467Y-259333D01*
X164717Y-259917D01*
X164217Y-260750D01*
X164050Y-261500D01*
X167550D01*
G01X168900D02*
Y-258167D01*
G01Y-259083D02*
X169150Y-258667D01*
X169567Y-258333D01*
X170150Y-258167D01*
X170733Y-258333D01*
X171150Y-258667D01*
X171400Y-259083D01*
Y-261500D01*
G01Y-259083D02*
X171650Y-258667D01*
X172067Y-258333D01*
X172650Y-258167D01*
X173233Y-258333D01*
X173650Y-258667D01*
X173900Y-259167D01*
Y-261500D01*
G01X177000Y-258167D02*
Y-261500D01*
G01Y-256833D02*
X176833Y-256750D01*
Y-256583D01*
X177000Y-256500D01*
X177167Y-256583D01*
Y-256750D01*
X177000Y-256833D01*
G01X182600Y-261500D02*
Y-256500D01*
G01X148083Y-224333D02*
X150083D01*
G01X149000Y-223250D02*
Y-225417D01*
G01X153100Y-226167D02*
X156100Y-221000D01*
G01X159117Y-224333D02*
X161283D01*
G01X164217Y-221833D02*
X164717Y-221333D01*
X165300Y-221083D01*
X165967Y-221000D01*
X166800Y-221167D01*
X167383Y-221583D01*
X167550Y-222083D01*
X167467Y-222583D01*
X167133Y-223000D01*
X165467Y-223833D01*
X164717Y-224417D01*
X164217Y-225250D01*
X164050Y-226000D01*
X167550D01*
G01X168900D02*
Y-222667D01*
G01Y-223583D02*
X169150Y-223167D01*
X169567Y-222833D01*
X170150Y-222667D01*
X170733Y-222833D01*
X171150Y-223167D01*
X171400Y-223583D01*
Y-226000D01*
G01Y-223583D02*
X171650Y-223167D01*
X172067Y-222833D01*
X172650Y-222667D01*
X173233Y-222833D01*
X173650Y-223167D01*
X173900Y-223667D01*
Y-226000D01*
G01X177000Y-222667D02*
Y-226000D01*
G01Y-221333D02*
X176833Y-221250D01*
Y-221083D01*
X177000Y-221000D01*
X177167Y-221083D01*
Y-221250D01*
X177000Y-221333D01*
G01X182600Y-226000D02*
Y-221000D01*
G01X148083Y-204833D02*
X150083D01*
G01X149000Y-203750D02*
Y-205917D01*
G01X153100Y-206667D02*
X156100Y-201500D01*
G01X159117Y-204833D02*
X161283D01*
G01X165800Y-206500D02*
Y-201500D01*
X164800Y-202500D01*
G01Y-206500D02*
X166800D01*
G01X169567Y-205750D02*
X170067Y-206167D01*
X170650Y-206417D01*
X171400Y-206500D01*
X172150Y-206333D01*
X172733Y-206000D01*
X173150Y-205417D01*
X173233Y-204750D01*
X173067Y-204083D01*
X172650Y-203667D01*
X172067Y-203333D01*
X171483Y-203250D01*
X170900Y-203333D01*
X170150Y-203667D01*
X170400Y-201500D01*
X172650D01*
G01X175500Y-206667D02*
X178500Y-201500D01*
G01X175500D02*
X175000Y-201667D01*
X174750Y-201917D01*
X174583Y-202417D01*
X174750Y-202917D01*
X175000Y-203167D01*
X175500Y-203333D01*
X176000Y-203167D01*
X176250Y-202917D01*
X176417Y-202417D01*
X176250Y-201917D01*
X176000Y-201667D01*
X175500Y-201500D01*
G01X178500Y-204833D02*
X178000Y-205000D01*
X177750Y-205250D01*
X177583Y-205750D01*
X177750Y-206250D01*
X178000Y-206500D01*
X178500Y-206667D01*
X179000Y-206500D01*
X179250Y-206250D01*
X179417Y-205750D01*
X179250Y-205250D01*
X179000Y-205000D01*
X178500Y-204833D01*
G01X148083Y-189833D02*
X150083D01*
G01X149000Y-188750D02*
Y-190917D01*
G01X153100Y-191667D02*
X156100Y-186500D01*
G01X159117Y-189833D02*
X161283D01*
G01X165800Y-191500D02*
Y-186500D01*
X164800Y-187500D01*
G01Y-191500D02*
X166800D01*
G01X168900D02*
Y-188167D01*
G01Y-189083D02*
X169150Y-188667D01*
X169567Y-188333D01*
X170150Y-188167D01*
X170733Y-188333D01*
X171150Y-188667D01*
X171400Y-189083D01*
Y-191500D01*
G01Y-189083D02*
X171650Y-188667D01*
X172067Y-188333D01*
X172650Y-188167D01*
X173233Y-188333D01*
X173650Y-188667D01*
X173900Y-189167D01*
Y-191500D01*
G01X177000Y-188167D02*
Y-191500D01*
G01Y-186833D02*
X176833Y-186750D01*
Y-186583D01*
X177000Y-186500D01*
X177167Y-186583D01*
Y-186750D01*
X177000Y-186833D01*
G01X182600Y-191500D02*
Y-186500D01*
G01X148083Y-174833D02*
X150083D01*
G01X149000Y-173750D02*
Y-175917D01*
G01X153100Y-176667D02*
X156100Y-171500D01*
G01X159117Y-174833D02*
X161283D01*
G01X164217Y-172333D02*
X164717Y-171833D01*
X165300Y-171583D01*
X165967Y-171500D01*
X166800Y-171667D01*
X167383Y-172083D01*
X167550Y-172583D01*
X167467Y-173083D01*
X167133Y-173500D01*
X165467Y-174333D01*
X164717Y-174917D01*
X164217Y-175750D01*
X164050Y-176500D01*
X167550D01*
G01X171400Y-171500D02*
X170733Y-171667D01*
X170233Y-172083D01*
X169900Y-172583D01*
X169650Y-173250D01*
X169567Y-174000D01*
X169650Y-174750D01*
X169900Y-175417D01*
X170233Y-175917D01*
X170733Y-176333D01*
X171400Y-176500D01*
X172067Y-176333D01*
X172567Y-175917D01*
X172900Y-175417D01*
X173150Y-174750D01*
X173233Y-174000D01*
X173150Y-173250D01*
X172900Y-172583D01*
X172567Y-172083D01*
X172067Y-171667D01*
X171400Y-171500D01*
G01X175500Y-176667D02*
X178500Y-171500D01*
G01X175500D02*
X175000Y-171667D01*
X174750Y-171917D01*
X174583Y-172417D01*
X174750Y-172917D01*
X175000Y-173167D01*
X175500Y-173333D01*
X176000Y-173167D01*
X176250Y-172917D01*
X176417Y-172417D01*
X176250Y-171917D01*
X176000Y-171667D01*
X175500Y-171500D01*
G01X178500Y-174833D02*
X178000Y-175000D01*
X177750Y-175250D01*
X177583Y-175750D01*
X177750Y-176250D01*
X178000Y-176500D01*
X178500Y-176667D01*
X179000Y-176500D01*
X179250Y-176250D01*
X179417Y-175750D01*
X179250Y-175250D01*
X179000Y-175000D01*
X178500Y-174833D01*
G01X148083Y-159833D02*
X150083D01*
G01X149000Y-158750D02*
Y-160917D01*
G01X153100Y-161667D02*
X156100Y-156500D01*
G01X159117Y-159833D02*
X161283D01*
G01X163967Y-160500D02*
X164467Y-161083D01*
X165133Y-161417D01*
X165883Y-161500D01*
X166550Y-161417D01*
X167217Y-161000D01*
X167633Y-160500D01*
X167717Y-160000D01*
X167550Y-159417D01*
X166967Y-159000D01*
X166383Y-158833D01*
X165633D01*
G01X166383D02*
X166883Y-158583D01*
X167300Y-158167D01*
X167467Y-157667D01*
X167300Y-157167D01*
X166883Y-156750D01*
X166133Y-156500D01*
X165383Y-156583D01*
X164633Y-156917D01*
G01X168900Y-161500D02*
Y-158167D01*
G01Y-159083D02*
X169150Y-158667D01*
X169567Y-158333D01*
X170150Y-158167D01*
X170733Y-158333D01*
X171150Y-158667D01*
X171400Y-159083D01*
Y-161500D01*
G01Y-159083D02*
X171650Y-158667D01*
X172067Y-158333D01*
X172650Y-158167D01*
X173233Y-158333D01*
X173650Y-158667D01*
X173900Y-159167D01*
Y-161500D01*
G01X177000Y-158167D02*
Y-161500D01*
G01Y-156833D02*
X176833Y-156750D01*
Y-156583D01*
X177000Y-156500D01*
X177167Y-156583D01*
Y-156750D01*
X177000Y-156833D01*
G01X182600Y-161500D02*
Y-156500D01*
G01X147333Y-146500D02*
X150667Y-144833D01*
X147333Y-143167D01*
G01X153517Y-145583D02*
X155683D01*
G01Y-144083D02*
X153517D01*
G01X160200Y-146500D02*
Y-141500D01*
X159200Y-142500D01*
G01Y-146500D02*
X161200D01*
G01X165800Y-146667D02*
X165633Y-146583D01*
Y-146417D01*
X165800Y-146333D01*
X165967Y-146417D01*
Y-146583D01*
X165800Y-146667D01*
G01X171400Y-141500D02*
X170733Y-141667D01*
X170233Y-142083D01*
X169900Y-142583D01*
X169650Y-143250D01*
X169567Y-144000D01*
X169650Y-144750D01*
X169900Y-145417D01*
X170233Y-145917D01*
X170733Y-146333D01*
X171400Y-146500D01*
X172067Y-146333D01*
X172567Y-145917D01*
X172900Y-145417D01*
X173150Y-144750D01*
X173233Y-144000D01*
X173150Y-143250D01*
X172900Y-142583D01*
X172567Y-142083D01*
X172067Y-141667D01*
X171400Y-141500D01*
G01X174500Y-146500D02*
Y-143167D01*
G01Y-144083D02*
X174750Y-143667D01*
X175167Y-143333D01*
X175750Y-143167D01*
X176333Y-143333D01*
X176750Y-143667D01*
X177000Y-144083D01*
Y-146500D01*
G01Y-144083D02*
X177250Y-143667D01*
X177667Y-143333D01*
X178250Y-143167D01*
X178833Y-143333D01*
X179250Y-143667D01*
X179500Y-144167D01*
Y-146500D01*
G01X182600Y-143167D02*
Y-146500D01*
G01Y-141833D02*
X182433Y-141750D01*
Y-141583D01*
X182600Y-141500D01*
X182767Y-141583D01*
Y-141750D01*
X182600Y-141833D01*
G01X188200Y-146500D02*
Y-141500D01*
G01X147333Y-129000D02*
X150667Y-127333D01*
X147333Y-125667D01*
G01X153517Y-128083D02*
X155683D01*
G01Y-126583D02*
X153517D01*
G01X160200Y-129000D02*
Y-124000D01*
X159200Y-125000D01*
G01Y-129000D02*
X161200D01*
G01X165800Y-129167D02*
X165633Y-129083D01*
Y-128917D01*
X165800Y-128833D01*
X165967Y-128917D01*
Y-129083D01*
X165800Y-129167D01*
G01X169567Y-128250D02*
X170067Y-128667D01*
X170650Y-128917D01*
X171400Y-129000D01*
X172150Y-128833D01*
X172733Y-128500D01*
X173150Y-127917D01*
X173233Y-127250D01*
X173067Y-126583D01*
X172650Y-126167D01*
X172067Y-125833D01*
X171483Y-125750D01*
X170900Y-125833D01*
X170150Y-126167D01*
X170400Y-124000D01*
X172650D01*
G01X174500Y-129000D02*
Y-125667D01*
G01Y-126583D02*
X174750Y-126167D01*
X175167Y-125833D01*
X175750Y-125667D01*
X176333Y-125833D01*
X176750Y-126167D01*
X177000Y-126583D01*
Y-129000D01*
G01Y-126583D02*
X177250Y-126167D01*
X177667Y-125833D01*
X178250Y-125667D01*
X178833Y-125833D01*
X179250Y-126167D01*
X179500Y-126667D01*
Y-129000D01*
G01X182600Y-125667D02*
Y-129000D01*
G01Y-124333D02*
X182433Y-124250D01*
Y-124083D01*
X182600Y-124000D01*
X182767Y-124083D01*
Y-124250D01*
X182600Y-124333D01*
G01X188200Y-129000D02*
Y-124000D01*
G01X147333Y-106500D02*
X150667Y-104833D01*
X147333Y-103167D01*
G01X153517Y-105583D02*
X155683D01*
G01Y-104083D02*
X153517D01*
G01X160200Y-106500D02*
Y-101500D01*
X159200Y-102500D01*
G01Y-106500D02*
X161200D01*
G01X165800Y-106667D02*
X165633Y-106583D01*
Y-106417D01*
X165800Y-106333D01*
X165967Y-106417D01*
Y-106583D01*
X165800Y-106667D01*
G01X169567Y-105500D02*
X170067Y-106083D01*
X170733Y-106417D01*
X171483Y-106500D01*
X172150Y-106417D01*
X172817Y-106000D01*
X173233Y-105500D01*
X173317Y-105000D01*
X173150Y-104417D01*
X172567Y-104000D01*
X171983Y-103833D01*
X171233D01*
G01X171983D02*
X172483Y-103583D01*
X172900Y-103167D01*
X173067Y-102667D01*
X172900Y-102167D01*
X172483Y-101750D01*
X171733Y-101500D01*
X170983Y-101583D01*
X170233Y-101917D01*
G01X174500Y-106500D02*
Y-103167D01*
G01Y-104083D02*
X174750Y-103667D01*
X175167Y-103333D01*
X175750Y-103167D01*
X176333Y-103333D01*
X176750Y-103667D01*
X177000Y-104083D01*
Y-106500D01*
G01Y-104083D02*
X177250Y-103667D01*
X177667Y-103333D01*
X178250Y-103167D01*
X178833Y-103333D01*
X179250Y-103667D01*
X179500Y-104167D01*
Y-106500D01*
G01X182600Y-103167D02*
Y-106500D01*
G01Y-101833D02*
X182433Y-101750D01*
Y-101583D01*
X182600Y-101500D01*
X182767Y-101583D01*
Y-101750D01*
X182600Y-101833D01*
G01X188200Y-106500D02*
Y-101500D01*
G01X154477Y-72510D02*
X151143Y-70843D01*
X154477Y-69177D01*
G01X158410Y-67510D02*
X157743Y-67677D01*
X157243Y-68093D01*
X156910Y-68593D01*
X156660Y-69260D01*
X156577Y-70010D01*
X156660Y-70760D01*
X156910Y-71427D01*
X157243Y-71927D01*
X157743Y-72343D01*
X158410Y-72510D01*
X159077Y-72343D01*
X159577Y-71927D01*
X159910Y-71427D01*
X160160Y-70760D01*
X160243Y-70010D01*
X160160Y-69260D01*
X159910Y-68593D01*
X159577Y-68093D01*
X159077Y-67677D01*
X158410Y-67510D01*
G01X164010Y-72677D02*
X163843Y-72593D01*
Y-72427D01*
X164010Y-72343D01*
X164177Y-72427D01*
Y-72593D01*
X164010Y-72677D01*
G01X167777Y-71510D02*
X168277Y-72093D01*
X168943Y-72427D01*
X169693Y-72510D01*
X170360Y-72427D01*
X171027Y-72010D01*
X171443Y-71510D01*
X171527Y-71010D01*
X171360Y-70427D01*
X170777Y-70010D01*
X170193Y-69843D01*
X169443D01*
G01X170193D02*
X170693Y-69593D01*
X171110Y-69177D01*
X171277Y-68677D01*
X171110Y-68177D01*
X170693Y-67760D01*
X169943Y-67510D01*
X169193Y-67593D01*
X168443Y-67927D01*
G01X172710Y-72510D02*
Y-69177D01*
G01Y-70093D02*
X172960Y-69677D01*
X173377Y-69343D01*
X173960Y-69177D01*
X174543Y-69343D01*
X174960Y-69677D01*
X175210Y-70093D01*
Y-72510D01*
G01Y-70093D02*
X175460Y-69677D01*
X175877Y-69343D01*
X176460Y-69177D01*
X177043Y-69343D01*
X177460Y-69677D01*
X177710Y-70177D01*
Y-72510D01*
G01X180810Y-69177D02*
Y-72510D01*
G01Y-67843D02*
X180643Y-67760D01*
Y-67593D01*
X180810Y-67510D01*
X180977Y-67593D01*
Y-67760D01*
X180810Y-67843D01*
G01X186410Y-72510D02*
Y-67510D01*
G01X153877Y-17320D02*
X150543Y-15653D01*
X153877Y-13987D01*
G01X157810Y-17320D02*
Y-12320D01*
X156810Y-13320D01*
G01Y-17320D02*
X158810D01*
G01X160910D02*
Y-13987D01*
G01Y-14903D02*
X161160Y-14487D01*
X161577Y-14153D01*
X162160Y-13987D01*
X162743Y-14153D01*
X163160Y-14487D01*
X163410Y-14903D01*
Y-17320D01*
G01Y-14903D02*
X163660Y-14487D01*
X164077Y-14153D01*
X164660Y-13987D01*
X165243Y-14153D01*
X165660Y-14487D01*
X165910Y-14987D01*
Y-17320D01*
G01X169010Y-13987D02*
Y-17320D01*
G01Y-12653D02*
X168843Y-12570D01*
Y-12403D01*
X169010Y-12320D01*
X169177Y-12403D01*
Y-12570D01*
X169010Y-12653D01*
G01X174610Y-17320D02*
Y-12320D01*
G01X149897Y22230D02*
X146563Y23897D01*
X149897Y25563D01*
G01X152413Y22813D02*
X152997Y22397D01*
X153663Y22230D01*
X154330Y22397D01*
X154913Y22897D01*
X155330Y23647D01*
X155497Y24397D01*
Y25313D01*
X155330Y26063D01*
X154913Y26730D01*
X154413Y27063D01*
X153830Y27230D01*
X153163Y27063D01*
X152663Y26730D01*
X152330Y26230D01*
X152163Y25563D01*
X152330Y24980D01*
X152747Y24397D01*
X153247Y24063D01*
X153830Y23980D01*
X154497Y24147D01*
X154997Y24563D01*
X155497Y25313D01*
G01X159430Y27230D02*
X158763Y27063D01*
X158263Y26647D01*
X157930Y26147D01*
X157680Y25480D01*
X157597Y24730D01*
X157680Y23980D01*
X157930Y23313D01*
X158263Y22813D01*
X158763Y22397D01*
X159430Y22230D01*
X160097Y22397D01*
X160597Y22813D01*
X160930Y23313D01*
X161180Y23980D01*
X161263Y24730D01*
X161180Y25480D01*
X160930Y26147D01*
X160597Y26647D01*
X160097Y27063D01*
X159430Y27230D01*
G01X172130D02*
Y22230D01*
G01Y22980D02*
X171797Y22563D01*
X171297Y22313D01*
X170713Y22230D01*
X170047Y22397D01*
X169547Y22813D01*
X169213Y23313D01*
X169130Y23897D01*
X169213Y24480D01*
X169547Y24980D01*
X170047Y25397D01*
X170713Y25563D01*
X171297Y25480D01*
X171713Y25313D01*
X172130Y24980D01*
G01X174980Y24480D02*
X177647D01*
X177397Y25063D01*
X176980Y25397D01*
X176397Y25563D01*
X175813Y25480D01*
X175313Y25230D01*
X174980Y24647D01*
X174813Y24147D01*
Y23647D01*
X174980Y23147D01*
X175397Y22647D01*
X175897Y22313D01*
X176480Y22230D01*
X177063Y22397D01*
X177647Y22897D01*
G01X180663Y20980D02*
X181247Y20647D01*
X181913Y20563D01*
X182497Y20647D01*
X182997Y21063D01*
X183330Y21647D01*
Y25563D01*
G01Y24897D02*
X182997Y25230D01*
X182497Y25480D01*
X181913Y25563D01*
X181247Y25397D01*
X180830Y25063D01*
X180497Y24480D01*
X180330Y23897D01*
X180413Y23397D01*
X180747Y22813D01*
X181247Y22397D01*
X181913Y22230D01*
X182413Y22313D01*
X182997Y22647D01*
X183330Y22980D01*
G01X186263Y22230D02*
Y25563D01*
G01Y24897D02*
X186680Y25230D01*
X187097Y25480D01*
X187680Y25563D01*
X188097Y25480D01*
X188597Y25230D01*
G01X191780Y24480D02*
X194447D01*
X194197Y25063D01*
X193780Y25397D01*
X193197Y25563D01*
X192613Y25480D01*
X192113Y25230D01*
X191780Y24647D01*
X191613Y24147D01*
Y23647D01*
X191780Y23147D01*
X192197Y22647D01*
X192697Y22313D01*
X193280Y22230D01*
X193863Y22397D01*
X194447Y22897D01*
G01X197380Y24480D02*
X200047D01*
X199797Y25063D01*
X199380Y25397D01*
X198797Y25563D01*
X198213Y25480D01*
X197713Y25230D01*
X197380Y24647D01*
X197213Y24147D01*
Y23647D01*
X197380Y23147D01*
X197797Y22647D01*
X198297Y22313D01*
X198880Y22230D01*
X199463Y22397D01*
X200047Y22897D01*
G01X143620Y37470D02*
Y40803D01*
G01Y39887D02*
X143870Y40303D01*
X144287Y40637D01*
X144870Y40803D01*
X145453Y40637D01*
X145870Y40303D01*
X146120Y39887D01*
Y37470D01*
G01Y39887D02*
X146370Y40303D01*
X146787Y40637D01*
X147370Y40803D01*
X147953Y40637D01*
X148370Y40303D01*
X148620Y39803D01*
Y37470D01*
G01X150303Y40803D02*
Y38470D01*
X150637Y37887D01*
X151137Y37553D01*
X151720Y37470D01*
X152303Y37553D01*
X152803Y37887D01*
X153137Y38470D01*
G01Y37470D02*
Y40803D01*
G01X156070Y38053D02*
X156487Y37720D01*
X157070Y37470D01*
X157570D01*
X158070Y37637D01*
X158403Y37887D01*
X158570Y38220D01*
X158487Y38720D01*
X158153Y38970D01*
X156653Y39470D01*
X156320Y40053D01*
X156487Y40470D01*
X156820Y40720D01*
X157320Y40803D01*
X157820Y40720D01*
X158320Y40470D01*
G01X162920Y42470D02*
Y37470D01*
G01X161753Y40803D02*
X164087D01*
G01X170187Y37470D02*
X166853Y39137D01*
X170187Y40803D01*
G01X172037Y37470D02*
X174120Y42470D01*
X176203Y37470D01*
G01X175453Y39220D02*
X172787D01*
G01X186820Y42470D02*
Y37470D01*
G01Y38220D02*
X186487Y37803D01*
X185987Y37553D01*
X185403Y37470D01*
X184737Y37637D01*
X184237Y38053D01*
X183903Y38553D01*
X183820Y39137D01*
X183903Y39720D01*
X184237Y40220D01*
X184737Y40637D01*
X185403Y40803D01*
X185987Y40720D01*
X186403Y40553D01*
X186820Y40220D01*
G01X190920Y40803D02*
Y37470D01*
G01Y42137D02*
X190753Y42220D01*
Y42387D01*
X190920Y42470D01*
X191087Y42387D01*
Y42220D01*
X190920Y42137D01*
G01X198020Y37470D02*
Y40803D01*
G01Y40220D02*
X197687Y40553D01*
X197187Y40720D01*
X196603Y40803D01*
X196020Y40637D01*
X195520Y40303D01*
X195187Y39803D01*
X195020Y39137D01*
X195187Y38470D01*
X195520Y37970D01*
X196020Y37637D01*
X196603Y37470D01*
X197187Y37553D01*
X197687Y37803D01*
X198020Y38137D01*
G01X199620Y37470D02*
Y40803D01*
G01Y39887D02*
X199870Y40303D01*
X200287Y40637D01*
X200870Y40803D01*
X201453Y40637D01*
X201870Y40303D01*
X202120Y39887D01*
Y37470D01*
G01Y39887D02*
X202370Y40303D01*
X202787Y40637D01*
X203370Y40803D01*
X203953Y40637D01*
X204370Y40303D01*
X204620Y39803D01*
Y37470D01*
G01X206470Y39720D02*
X209137D01*
X208887Y40303D01*
X208470Y40637D01*
X207887Y40803D01*
X207303Y40720D01*
X206803Y40470D01*
X206470Y39887D01*
X206303Y39387D01*
Y38887D01*
X206470Y38387D01*
X206887Y37887D01*
X207387Y37553D01*
X207970Y37470D01*
X208553Y37637D01*
X209137Y38137D01*
G01X213320Y42470D02*
Y37470D01*
G01X212153Y40803D02*
X214487D01*
G01X217670Y39720D02*
X220337D01*
X220087Y40303D01*
X219670Y40637D01*
X219087Y40803D01*
X218503Y40720D01*
X218003Y40470D01*
X217670Y39887D01*
X217503Y39387D01*
Y38887D01*
X217670Y38387D01*
X218087Y37887D01*
X218587Y37553D01*
X219170Y37470D01*
X219753Y37637D01*
X220337Y38137D01*
G01X223353Y37470D02*
Y40803D01*
G01Y40137D02*
X223770Y40470D01*
X224187Y40720D01*
X224770Y40803D01*
X225187Y40720D01*
X225687Y40470D01*
G01X144200Y46240D02*
Y51240D01*
G01Y48740D02*
X144617Y49240D01*
X145117Y49490D01*
X145617Y49573D01*
X146367Y49407D01*
X146867Y49073D01*
X147200Y48490D01*
Y47823D01*
X147033Y47157D01*
X146700Y46657D01*
X146117Y46323D01*
X145617Y46240D01*
X145117Y46323D01*
X144617Y46573D01*
X144200Y46990D01*
G01X149883Y49573D02*
Y47240D01*
X150217Y46657D01*
X150717Y46323D01*
X151300Y46240D01*
X151883Y46323D01*
X152383Y46657D01*
X152717Y47240D01*
G01Y46240D02*
Y49573D01*
G01X156900Y51240D02*
Y46240D01*
G01X155733Y49573D02*
X158067D01*
G01X168767Y48907D02*
X169100Y49157D01*
X169350Y49573D01*
X169517Y50157D01*
X169350Y50657D01*
X169017Y50990D01*
X168433Y51240D01*
X166183D01*
Y46240D01*
X168933D01*
X169517Y46573D01*
X169850Y47073D01*
X170017Y47657D01*
X169850Y48240D01*
X169350Y48740D01*
X168767Y48907D01*
X166183D01*
G01X180800Y51240D02*
Y46240D01*
G01Y46990D02*
X180467Y46573D01*
X179967Y46323D01*
X179383Y46240D01*
X178717Y46407D01*
X178217Y46823D01*
X177883Y47323D01*
X177800Y47907D01*
X177883Y48490D01*
X178217Y48990D01*
X178717Y49407D01*
X179383Y49573D01*
X179967Y49490D01*
X180383Y49323D01*
X180800Y48990D01*
G01X184900Y49573D02*
Y46240D01*
G01Y50907D02*
X184733Y50990D01*
Y51157D01*
X184900Y51240D01*
X185067Y51157D01*
Y50990D01*
X184900Y50907D01*
G01X192000Y46240D02*
Y49573D01*
G01Y48990D02*
X191667Y49323D01*
X191167Y49490D01*
X190583Y49573D01*
X190000Y49407D01*
X189500Y49073D01*
X189167Y48573D01*
X189000Y47907D01*
X189167Y47240D01*
X189500Y46740D01*
X190000Y46407D01*
X190583Y46240D01*
X191167Y46323D01*
X191667Y46573D01*
X192000Y46907D01*
G01X193600Y46240D02*
Y49573D01*
G01Y48657D02*
X193850Y49073D01*
X194267Y49407D01*
X194850Y49573D01*
X195433Y49407D01*
X195850Y49073D01*
X196100Y48657D01*
Y46240D01*
G01Y48657D02*
X196350Y49073D01*
X196767Y49407D01*
X197350Y49573D01*
X197933Y49407D01*
X198350Y49073D01*
X198600Y48573D01*
Y46240D01*
G01X200450Y48490D02*
X203117D01*
X202867Y49073D01*
X202450Y49407D01*
X201867Y49573D01*
X201283Y49490D01*
X200783Y49240D01*
X200450Y48657D01*
X200283Y48157D01*
Y47657D01*
X200450Y47157D01*
X200867Y46657D01*
X201367Y46323D01*
X201950Y46240D01*
X202533Y46407D01*
X203117Y46907D01*
G01X207300Y51240D02*
Y46240D01*
G01X206133Y49573D02*
X208467D01*
G01X211650Y48490D02*
X214317D01*
X214067Y49073D01*
X213650Y49407D01*
X213067Y49573D01*
X212483Y49490D01*
X211983Y49240D01*
X211650Y48657D01*
X211483Y48157D01*
Y47657D01*
X211650Y47157D01*
X212067Y46657D01*
X212567Y46323D01*
X213150Y46240D01*
X213733Y46407D01*
X214317Y46907D01*
G01X217333Y46240D02*
Y49573D01*
G01Y48907D02*
X217750Y49240D01*
X218167Y49490D01*
X218750Y49573D01*
X219167Y49490D01*
X219667Y49240D01*
G01X145283Y56260D02*
X148617Y57927D01*
X145283Y59593D01*
G01X151467Y57177D02*
X153633D01*
G01Y58677D02*
X151467D01*
G01X157983Y56260D02*
X158150Y57343D01*
X158400Y58260D01*
X158733Y59093D01*
X159150Y60010D01*
X159817Y61260D01*
X156483D01*
G01X163750D02*
X163083Y61093D01*
X162583Y60677D01*
X162250Y60177D01*
X162000Y59510D01*
X161917Y58760D01*
X162000Y58010D01*
X162250Y57343D01*
X162583Y56843D01*
X163083Y56427D01*
X163750Y56260D01*
X164417Y56427D01*
X164917Y56843D01*
X165250Y57343D01*
X165500Y58010D01*
X165583Y58760D01*
X165500Y59510D01*
X165250Y60177D01*
X164917Y60677D01*
X164417Y61093D01*
X163750Y61260D01*
G01X167850Y56093D02*
X170850Y61260D01*
G01X167850D02*
X167350Y61093D01*
X167100Y60843D01*
X166933Y60343D01*
X167100Y59843D01*
X167350Y59593D01*
X167850Y59427D01*
X168350Y59593D01*
X168600Y59843D01*
X168767Y60343D01*
X168600Y60843D01*
X168350Y61093D01*
X167850Y61260D01*
G01X170850Y57927D02*
X170350Y57760D01*
X170100Y57510D01*
X169933Y57010D01*
X170100Y56510D01*
X170350Y56260D01*
X170850Y56093D01*
X171350Y56260D01*
X171600Y56510D01*
X171767Y57010D01*
X171600Y57510D01*
X171350Y57760D01*
X170850Y57927D01*
G01X174783Y55343D02*
X175117Y56427D01*
G01X147263Y76687D02*
X149263D01*
G01X148180Y77770D02*
Y75603D01*
G01X152280Y74853D02*
X155280Y80020D01*
G01X158297Y76687D02*
X160463D01*
G01X164980Y75020D02*
Y80020D01*
X163980Y79020D01*
G01Y75020D02*
X165980D01*
G01X168080D02*
Y78353D01*
G01Y77437D02*
X168330Y77853D01*
X168747Y78187D01*
X169330Y78353D01*
X169913Y78187D01*
X170330Y77853D01*
X170580Y77437D01*
Y75020D01*
G01Y77437D02*
X170830Y77853D01*
X171247Y78187D01*
X171830Y78353D01*
X172413Y78187D01*
X172830Y77853D01*
X173080Y77353D01*
Y75020D01*
G01X176180Y78353D02*
Y75020D01*
G01Y79687D02*
X176013Y79770D01*
Y79937D01*
X176180Y80020D01*
X176347Y79937D01*
Y79770D01*
X176180Y79687D01*
G01X181780Y75020D02*
Y80020D01*
G01X149833Y120000D02*
Y125000D01*
X152000Y120833D01*
X154167Y125000D01*
Y120000D01*
G01X156183Y123333D02*
Y121000D01*
X156517Y120417D01*
X157017Y120083D01*
X157600Y120000D01*
X158183Y120083D01*
X158683Y120417D01*
X159017Y121000D01*
G01Y120000D02*
Y123333D01*
G01X161950Y120583D02*
X162367Y120250D01*
X162950Y120000D01*
X163450D01*
X163950Y120167D01*
X164283Y120417D01*
X164450Y120750D01*
X164367Y121250D01*
X164033Y121500D01*
X162533Y122000D01*
X162200Y122583D01*
X162367Y123000D01*
X162700Y123250D01*
X163200Y123333D01*
X163700Y123250D01*
X164200Y123000D01*
G01X168800Y125000D02*
Y120000D01*
G01X167633Y123333D02*
X169967D01*
G01X179500Y120000D02*
Y124250D01*
X179667Y124667D01*
X180000Y124917D01*
X180500Y125000D01*
X181000Y124833D01*
X181250Y124417D01*
G01X180250Y123000D02*
X178583D01*
G01X185600Y120000D02*
X185100Y120083D01*
X184600Y120417D01*
X184267Y121000D01*
X184100Y121667D01*
X184267Y122333D01*
X184600Y122917D01*
X185100Y123250D01*
X185600Y123333D01*
X186100Y123250D01*
X186600Y122917D01*
X186933Y122333D01*
X187017Y121667D01*
X186933Y121000D01*
X186600Y120417D01*
X186100Y120083D01*
X185600Y120000D01*
G01X191200D02*
Y125000D01*
G01X196800Y120000D02*
Y125000D01*
G01X202400Y120000D02*
X201900Y120083D01*
X201400Y120417D01*
X201067Y121000D01*
X200900Y121667D01*
X201067Y122333D01*
X201400Y122917D01*
X201900Y123250D01*
X202400Y123333D01*
X202900Y123250D01*
X203400Y122917D01*
X203733Y122333D01*
X203817Y121667D01*
X203733Y121000D01*
X203400Y120417D01*
X202900Y120083D01*
X202400Y120000D01*
G01X205917Y123333D02*
X206917Y120000D01*
X208000Y123333D01*
X209083Y120000D01*
X210083Y123333D01*
G01X147310Y156990D02*
Y161240D01*
X147477Y161657D01*
X147810Y161907D01*
X148310Y161990D01*
X148810Y161823D01*
X149060Y161407D01*
G01X148060Y159990D02*
X146393D01*
G01X153410Y156990D02*
X152910Y157073D01*
X152410Y157407D01*
X152077Y157990D01*
X151910Y158657D01*
X152077Y159323D01*
X152410Y159907D01*
X152910Y160240D01*
X153410Y160323D01*
X153910Y160240D01*
X154410Y159907D01*
X154743Y159323D01*
X154827Y158657D01*
X154743Y157990D01*
X154410Y157407D01*
X153910Y157073D01*
X153410Y156990D01*
G01X159010D02*
Y161990D01*
G01X164610Y156990D02*
Y161990D01*
G01X170210Y156990D02*
X169710Y157073D01*
X169210Y157407D01*
X168877Y157990D01*
X168710Y158657D01*
X168877Y159323D01*
X169210Y159907D01*
X169710Y160240D01*
X170210Y160323D01*
X170710Y160240D01*
X171210Y159907D01*
X171543Y159323D01*
X171627Y158657D01*
X171543Y157990D01*
X171210Y157407D01*
X170710Y157073D01*
X170210Y156990D01*
G01X173727Y160323D02*
X174727Y156990D01*
X175810Y160323D01*
X176893Y156990D01*
X177893Y160323D01*
G01X188510Y161990D02*
Y156990D01*
G01Y157740D02*
X188177Y157323D01*
X187677Y157073D01*
X187093Y156990D01*
X186427Y157157D01*
X185927Y157573D01*
X185593Y158073D01*
X185510Y158657D01*
X185593Y159240D01*
X185927Y159740D01*
X186427Y160157D01*
X187093Y160323D01*
X187677Y160240D01*
X188093Y160073D01*
X188510Y159740D01*
G01X191443Y156990D02*
Y160323D01*
G01Y159657D02*
X191860Y159990D01*
X192277Y160240D01*
X192860Y160323D01*
X193277Y160240D01*
X193777Y159990D01*
G01X199710Y156990D02*
Y160323D01*
G01Y159740D02*
X199377Y160073D01*
X198877Y160240D01*
X198293Y160323D01*
X197710Y160157D01*
X197210Y159823D01*
X196877Y159323D01*
X196710Y158657D01*
X196877Y157990D01*
X197210Y157490D01*
X197710Y157157D01*
X198293Y156990D01*
X198877Y157073D01*
X199377Y157323D01*
X199710Y157657D01*
G01X201727Y160323D02*
X202727Y156990D01*
X203810Y160323D01*
X204893Y156990D01*
X205893Y160323D01*
G01X209410D02*
Y156990D01*
G01Y161657D02*
X209243Y161740D01*
Y161907D01*
X209410Y161990D01*
X209577Y161907D01*
Y161740D01*
X209410Y161657D01*
G01X213593Y156990D02*
Y160323D01*
G01Y159490D02*
X213927Y159907D01*
X214427Y160240D01*
X215093Y160323D01*
X215677Y160240D01*
X216177Y159907D01*
X216427Y159323D01*
Y156990D01*
G01X219443Y155740D02*
X220027Y155407D01*
X220693Y155323D01*
X221277Y155407D01*
X221777Y155823D01*
X222110Y156407D01*
Y160323D01*
G01Y159657D02*
X221777Y159990D01*
X221277Y160240D01*
X220693Y160323D01*
X220027Y160157D01*
X219610Y159823D01*
X219277Y159240D01*
X219110Y158657D01*
X219193Y158157D01*
X219527Y157573D01*
X220027Y157157D01*
X220693Y156990D01*
X221193Y157073D01*
X221777Y157407D01*
X222110Y157740D01*
G01X226627Y155323D02*
X227460Y156157D01*
X227877Y156990D01*
Y160323D01*
X227460Y161157D01*
X226627Y161990D01*
G01X148403Y167587D02*
X150403D01*
G01X149320Y168670D02*
Y166503D01*
G01X153420Y165753D02*
X156420Y170920D01*
G01X159437Y167587D02*
X161603D01*
G01X164287Y166670D02*
X164787Y166253D01*
X165370Y166003D01*
X166120Y165920D01*
X166870Y166087D01*
X167453Y166420D01*
X167870Y167003D01*
X167953Y167670D01*
X167787Y168337D01*
X167370Y168753D01*
X166787Y169087D01*
X166203Y169170D01*
X165620Y169087D01*
X164870Y168753D01*
X165120Y170920D01*
X167370D01*
G01X169220Y165920D02*
Y169253D01*
G01Y168337D02*
X169470Y168753D01*
X169887Y169087D01*
X170470Y169253D01*
X171053Y169087D01*
X171470Y168753D01*
X171720Y168337D01*
Y165920D01*
G01Y168337D02*
X171970Y168753D01*
X172387Y169087D01*
X172970Y169253D01*
X173553Y169087D01*
X173970Y168753D01*
X174220Y168253D01*
Y165920D01*
G01X177320Y169253D02*
Y165920D01*
G01Y170587D02*
X177153Y170670D01*
Y170837D01*
X177320Y170920D01*
X177487Y170837D01*
Y170670D01*
X177320Y170587D01*
G01X182920Y165920D02*
Y170920D01*
G01X149000Y179000D02*
Y184000D01*
X148000Y183000D01*
G01Y179000D02*
X150000D01*
G01X154600Y178833D02*
X154433Y178917D01*
Y179083D01*
X154600Y179167D01*
X154767Y179083D01*
Y178917D01*
X154600Y178833D01*
G01X160200Y184000D02*
X159533Y183833D01*
X159033Y183417D01*
X158700Y182917D01*
X158450Y182250D01*
X158367Y181500D01*
X158450Y180750D01*
X158700Y180083D01*
X159033Y179583D01*
X159533Y179167D01*
X160200Y179000D01*
X160867Y179167D01*
X161367Y179583D01*
X161700Y180083D01*
X161950Y180750D01*
X162033Y181500D01*
X161950Y182250D01*
X161700Y182917D01*
X161367Y183417D01*
X160867Y183833D01*
X160200Y184000D01*
G01X163300Y179000D02*
Y182333D01*
G01Y181417D02*
X163550Y181833D01*
X163967Y182167D01*
X164550Y182333D01*
X165133Y182167D01*
X165550Y181833D01*
X165800Y181417D01*
Y179000D01*
G01Y181417D02*
X166050Y181833D01*
X166467Y182167D01*
X167050Y182333D01*
X167633Y182167D01*
X168050Y181833D01*
X168300Y181333D01*
Y179000D01*
G01X171400Y182333D02*
Y179000D01*
G01Y183667D02*
X171233Y183750D01*
Y183917D01*
X171400Y184000D01*
X171567Y183917D01*
Y183750D01*
X171400Y183667D01*
G01X177000Y179000D02*
Y184000D01*
G01X185700Y179000D02*
Y182333D01*
G01Y181417D02*
X185950Y181833D01*
X186367Y182167D01*
X186950Y182333D01*
X187533Y182167D01*
X187950Y181833D01*
X188200Y181417D01*
Y179000D01*
G01Y181417D02*
X188450Y181833D01*
X188867Y182167D01*
X189450Y182333D01*
X190033Y182167D01*
X190450Y181833D01*
X190700Y181333D01*
Y179000D01*
G01X195300D02*
Y182333D01*
G01Y181750D02*
X194967Y182083D01*
X194467Y182250D01*
X193883Y182333D01*
X193300Y182167D01*
X192800Y181833D01*
X192467Y181333D01*
X192300Y180667D01*
X192467Y180000D01*
X192800Y179500D01*
X193300Y179167D01*
X193883Y179000D01*
X194467Y179083D01*
X194967Y179333D01*
X195300Y179667D01*
G01X198150Y182333D02*
X200650Y179000D01*
G01Y182333D02*
X198150Y179000D01*
G01X148083Y198667D02*
X150083D01*
G01X149000Y199750D02*
Y197583D01*
G01X153100Y196833D02*
X156100Y202000D01*
G01X159117Y198667D02*
X161283D01*
G01X163967Y197750D02*
X164467Y197333D01*
X165050Y197083D01*
X165800Y197000D01*
X166550Y197167D01*
X167133Y197500D01*
X167550Y198083D01*
X167633Y198750D01*
X167467Y199417D01*
X167050Y199833D01*
X166467Y200167D01*
X165883Y200250D01*
X165300Y200167D01*
X164550Y199833D01*
X164800Y202000D01*
X167050D01*
G01X168900Y197000D02*
Y200333D01*
G01Y199417D02*
X169150Y199833D01*
X169567Y200167D01*
X170150Y200333D01*
X170733Y200167D01*
X171150Y199833D01*
X171400Y199417D01*
Y197000D01*
G01Y199417D02*
X171650Y199833D01*
X172067Y200167D01*
X172650Y200333D01*
X173233Y200167D01*
X173650Y199833D01*
X173900Y199333D01*
Y197000D01*
G01X177000Y200333D02*
Y197000D01*
G01Y201667D02*
X176833Y201750D01*
Y201917D01*
X177000Y202000D01*
X177167Y201917D01*
Y201750D01*
X177000Y201667D01*
G01X182600Y197000D02*
Y202000D01*
G01X148083Y213667D02*
X150083D01*
G01X149000Y214750D02*
Y212583D01*
G01X153100Y211833D02*
X156100Y217000D01*
G01X159117Y213667D02*
X161283D01*
G01X163967Y212750D02*
X164467Y212333D01*
X165050Y212083D01*
X165800Y212000D01*
X166550Y212167D01*
X167133Y212500D01*
X167550Y213083D01*
X167633Y213750D01*
X167467Y214417D01*
X167050Y214833D01*
X166467Y215167D01*
X165883Y215250D01*
X165300Y215167D01*
X164550Y214833D01*
X164800Y217000D01*
X167050D01*
G01X168900Y212000D02*
Y215333D01*
G01Y214417D02*
X169150Y214833D01*
X169567Y215167D01*
X170150Y215333D01*
X170733Y215167D01*
X171150Y214833D01*
X171400Y214417D01*
Y212000D01*
G01Y214417D02*
X171650Y214833D01*
X172067Y215167D01*
X172650Y215333D01*
X173233Y215167D01*
X173650Y214833D01*
X173900Y214333D01*
Y212000D01*
G01X177000Y215333D02*
Y212000D01*
G01Y216667D02*
X176833Y216750D01*
Y216917D01*
X177000Y217000D01*
X177167Y216917D01*
Y216750D01*
X177000Y216667D01*
G01X182600Y212000D02*
Y217000D01*
G01X148083Y228667D02*
X150083D01*
G01X149000Y229750D02*
Y227583D01*
G01X152767Y228000D02*
X153267Y227417D01*
X153933Y227083D01*
X154683Y227000D01*
X155350Y227083D01*
X156017Y227500D01*
X156433Y228000D01*
X156517Y228500D01*
X156350Y229083D01*
X155767Y229500D01*
X155183Y229667D01*
X154433D01*
G01X155183D02*
X155683Y229917D01*
X156100Y230333D01*
X156267Y230833D01*
X156100Y231333D01*
X155683Y231750D01*
X154933Y232000D01*
X154183Y231917D01*
X153433Y231583D01*
G01X158700Y226833D02*
X161700Y232000D01*
G01X164717Y228667D02*
X166883D01*
G01X171400Y232000D02*
X170733Y231833D01*
X170233Y231417D01*
X169900Y230917D01*
X169650Y230250D01*
X169567Y229500D01*
X169650Y228750D01*
X169900Y228083D01*
X170233Y227583D01*
X170733Y227167D01*
X171400Y227000D01*
X172067Y227167D01*
X172567Y227583D01*
X172900Y228083D01*
X173150Y228750D01*
X173233Y229500D01*
X173150Y230250D01*
X172900Y230917D01*
X172567Y231417D01*
X172067Y231833D01*
X171400Y232000D01*
G01X174500Y227000D02*
Y230333D01*
G01Y229417D02*
X174750Y229833D01*
X175167Y230167D01*
X175750Y230333D01*
X176333Y230167D01*
X176750Y229833D01*
X177000Y229417D01*
Y227000D01*
G01Y229417D02*
X177250Y229833D01*
X177667Y230167D01*
X178250Y230333D01*
X178833Y230167D01*
X179250Y229833D01*
X179500Y229333D01*
Y227000D01*
G01X182600Y230333D02*
Y227000D01*
G01Y231667D02*
X182433Y231750D01*
Y231917D01*
X182600Y232000D01*
X182767Y231917D01*
Y231750D01*
X182600Y231667D01*
G01X188200Y227000D02*
Y232000D01*
G01X148083Y243667D02*
X150083D01*
G01X149000Y244750D02*
Y242583D01*
G01X153100Y241833D02*
X156100Y247000D01*
G01X159117Y243667D02*
X161283D01*
G01X164217Y246167D02*
X164717Y246667D01*
X165300Y246917D01*
X165967Y247000D01*
X166800Y246833D01*
X167383Y246417D01*
X167550Y245917D01*
X167467Y245417D01*
X167133Y245000D01*
X165467Y244167D01*
X164717Y243583D01*
X164217Y242750D01*
X164050Y242000D01*
X167550D01*
G01X168900D02*
Y245333D01*
G01Y244417D02*
X169150Y244833D01*
X169567Y245167D01*
X170150Y245333D01*
X170733Y245167D01*
X171150Y244833D01*
X171400Y244417D01*
Y242000D01*
G01Y244417D02*
X171650Y244833D01*
X172067Y245167D01*
X172650Y245333D01*
X173233Y245167D01*
X173650Y244833D01*
X173900Y244333D01*
Y242000D01*
G01X177000Y245333D02*
Y242000D01*
G01Y246667D02*
X176833Y246750D01*
Y246917D01*
X177000Y247000D01*
X177167Y246917D01*
Y246750D01*
X177000Y246667D01*
G01X182600Y242000D02*
Y247000D01*
G01X148083Y257167D02*
X150083D01*
G01X149000Y258250D02*
Y256083D01*
G01X153100Y255333D02*
X156100Y260500D01*
G01X159117Y257167D02*
X161283D01*
G01X163967Y256500D02*
X164467Y255917D01*
X165133Y255583D01*
X165883Y255500D01*
X166550Y255583D01*
X167217Y256000D01*
X167633Y256500D01*
X167717Y257000D01*
X167550Y257583D01*
X166967Y258000D01*
X166383Y258167D01*
X165633D01*
G01X166383D02*
X166883Y258417D01*
X167300Y258833D01*
X167467Y259333D01*
X167300Y259833D01*
X166883Y260250D01*
X166133Y260500D01*
X165383Y260417D01*
X164633Y260083D01*
G01X168900Y255500D02*
Y258833D01*
G01Y257917D02*
X169150Y258333D01*
X169567Y258667D01*
X170150Y258833D01*
X170733Y258667D01*
X171150Y258333D01*
X171400Y257917D01*
Y255500D01*
G01Y257917D02*
X171650Y258333D01*
X172067Y258667D01*
X172650Y258833D01*
X173233Y258667D01*
X173650Y258333D01*
X173900Y257833D01*
Y255500D01*
G01X177000Y258833D02*
Y255500D01*
G01Y260167D02*
X176833Y260250D01*
Y260417D01*
X177000Y260500D01*
X177167Y260417D01*
Y260250D01*
X177000Y260167D01*
G01X182600Y255500D02*
Y260500D01*
G01X148083Y273667D02*
X150083D01*
G01X149000Y274750D02*
Y272583D01*
G01X153100Y271833D02*
X156100Y277000D01*
G01X159117Y273667D02*
X161283D01*
G01X164217Y276167D02*
X164717Y276667D01*
X165300Y276917D01*
X165967Y277000D01*
X166800Y276833D01*
X167383Y276417D01*
X167550Y275917D01*
X167467Y275417D01*
X167133Y275000D01*
X165467Y274167D01*
X164717Y273583D01*
X164217Y272750D01*
X164050Y272000D01*
X167550D01*
G01X168900D02*
Y275333D01*
G01Y274417D02*
X169150Y274833D01*
X169567Y275167D01*
X170150Y275333D01*
X170733Y275167D01*
X171150Y274833D01*
X171400Y274417D01*
Y272000D01*
G01Y274417D02*
X171650Y274833D01*
X172067Y275167D01*
X172650Y275333D01*
X173233Y275167D01*
X173650Y274833D01*
X173900Y274333D01*
Y272000D01*
G01X177000Y275333D02*
Y272000D01*
G01Y276667D02*
X176833Y276750D01*
Y276917D01*
X177000Y277000D01*
X177167Y276917D01*
Y276750D01*
X177000Y276667D01*
G01X182600Y272000D02*
Y277000D01*
G01X148083Y288667D02*
X150083D01*
G01X149000Y289750D02*
Y287583D01*
G01X153100Y286833D02*
X156100Y292000D01*
G01X159117Y288667D02*
X161283D01*
G01X164217Y291167D02*
X164717Y291667D01*
X165300Y291917D01*
X165967Y292000D01*
X166800Y291833D01*
X167383Y291417D01*
X167550Y290917D01*
X167467Y290417D01*
X167133Y290000D01*
X165467Y289167D01*
X164717Y288583D01*
X164217Y287750D01*
X164050Y287000D01*
X167550D01*
G01X168900D02*
Y290333D01*
G01Y289417D02*
X169150Y289833D01*
X169567Y290167D01*
X170150Y290333D01*
X170733Y290167D01*
X171150Y289833D01*
X171400Y289417D01*
Y287000D01*
G01Y289417D02*
X171650Y289833D01*
X172067Y290167D01*
X172650Y290333D01*
X173233Y290167D01*
X173650Y289833D01*
X173900Y289333D01*
Y287000D01*
G01X177000Y290333D02*
Y287000D01*
G01Y291667D02*
X176833Y291750D01*
Y291917D01*
X177000Y292000D01*
X177167Y291917D01*
Y291750D01*
X177000Y291667D01*
G01X182600Y287000D02*
Y292000D01*
G01X148083Y302167D02*
X150083D01*
G01X149000Y303250D02*
Y301083D01*
G01X153017Y304667D02*
X153517Y305167D01*
X154100Y305417D01*
X154767Y305500D01*
X155600Y305333D01*
X156183Y304917D01*
X156350Y304417D01*
X156267Y303917D01*
X155933Y303500D01*
X154267Y302667D01*
X153517Y302083D01*
X153017Y301250D01*
X152850Y300500D01*
X156350D01*
G01X158700Y300333D02*
X161700Y305500D01*
G01X164717Y302167D02*
X166883D01*
G01X172400Y300500D02*
Y305500D01*
X169317Y301917D01*
X173483D01*
G01X174500Y300500D02*
Y303833D01*
G01Y302917D02*
X174750Y303333D01*
X175167Y303667D01*
X175750Y303833D01*
X176333Y303667D01*
X176750Y303333D01*
X177000Y302917D01*
Y300500D01*
G01Y302917D02*
X177250Y303333D01*
X177667Y303667D01*
X178250Y303833D01*
X178833Y303667D01*
X179250Y303333D01*
X179500Y302833D01*
Y300500D01*
G01X182600Y303833D02*
Y300500D01*
G01Y305167D02*
X182433Y305250D01*
Y305417D01*
X182600Y305500D01*
X182767Y305417D01*
Y305250D01*
X182600Y305167D01*
G01X188200Y300500D02*
Y305500D01*
G01X148083Y318667D02*
X150083D01*
G01X149000Y319750D02*
Y317583D01*
G01X153100Y316833D02*
X156100Y322000D01*
G01X159117Y318667D02*
X161283D01*
G01X163967Y318000D02*
X164467Y317417D01*
X165133Y317083D01*
X165883Y317000D01*
X166550Y317083D01*
X167217Y317500D01*
X167633Y318000D01*
X167717Y318500D01*
X167550Y319083D01*
X166967Y319500D01*
X166383Y319667D01*
X165633D01*
G01X166383D02*
X166883Y319917D01*
X167300Y320333D01*
X167467Y320833D01*
X167300Y321333D01*
X166883Y321750D01*
X166133Y322000D01*
X165383Y321917D01*
X164633Y321583D01*
G01X168900Y317000D02*
Y320333D01*
G01Y319417D02*
X169150Y319833D01*
X169567Y320167D01*
X170150Y320333D01*
X170733Y320167D01*
X171150Y319833D01*
X171400Y319417D01*
Y317000D01*
G01Y319417D02*
X171650Y319833D01*
X172067Y320167D01*
X172650Y320333D01*
X173233Y320167D01*
X173650Y319833D01*
X173900Y319333D01*
Y317000D01*
G01X177000Y320333D02*
Y317000D01*
G01Y321667D02*
X176833Y321750D01*
Y321917D01*
X177000Y322000D01*
X177167Y321917D01*
Y321750D01*
X177000Y321667D01*
G01X182600Y317000D02*
Y322000D01*
G01X146917Y330500D02*
X149000Y335500D01*
X151083Y330500D01*
G01X150333Y332250D02*
X147667D01*
G01X154600Y330500D02*
Y335500D01*
G01X160200Y330500D02*
Y335500D01*
G01X165800Y330500D02*
X165300Y330583D01*
X164800Y330917D01*
X164467Y331500D01*
X164300Y332167D01*
X164467Y332833D01*
X164800Y333417D01*
X165300Y333750D01*
X165800Y333833D01*
X166300Y333750D01*
X166800Y333417D01*
X167133Y332833D01*
X167217Y332167D01*
X167133Y331500D01*
X166800Y330917D01*
X166300Y330583D01*
X165800Y330500D01*
G01X169317Y333833D02*
X170317Y330500D01*
X171400Y333833D01*
X172483Y330500D01*
X173483Y333833D01*
G01X148083Y347167D02*
X150083D01*
G01X149000Y348250D02*
Y346083D01*
G01X153100Y345333D02*
X156100Y350500D01*
G01X159117Y347167D02*
X161283D01*
G01X164217Y349667D02*
X164717Y350167D01*
X165300Y350417D01*
X165967Y350500D01*
X166800Y350333D01*
X167383Y349917D01*
X167550Y349417D01*
X167467Y348917D01*
X167133Y348500D01*
X165467Y347667D01*
X164717Y347083D01*
X164217Y346250D01*
X164050Y345500D01*
X167550D01*
G01X168900D02*
Y348833D01*
G01Y347917D02*
X169150Y348333D01*
X169567Y348667D01*
X170150Y348833D01*
X170733Y348667D01*
X171150Y348333D01*
X171400Y347917D01*
Y345500D01*
G01Y347917D02*
X171650Y348333D01*
X172067Y348667D01*
X172650Y348833D01*
X173233Y348667D01*
X173650Y348333D01*
X173900Y347833D01*
Y345500D01*
G01X177000Y348833D02*
Y345500D01*
G01Y350167D02*
X176833Y350250D01*
Y350417D01*
X177000Y350500D01*
X177167Y350417D01*
Y350250D01*
X177000Y350167D01*
G01X182600Y345500D02*
Y350500D01*
G01X146853Y365700D02*
Y370700D01*
X149020Y366533D01*
X151187Y370700D01*
Y365700D01*
G01X153203Y369033D02*
Y366700D01*
X153537Y366117D01*
X154037Y365783D01*
X154620Y365700D01*
X155203Y365783D01*
X155703Y366117D01*
X156037Y366700D01*
G01Y365700D02*
Y369033D01*
G01X158970Y366283D02*
X159387Y365950D01*
X159970Y365700D01*
X160470D01*
X160970Y365867D01*
X161303Y366117D01*
X161470Y366450D01*
X161387Y366950D01*
X161053Y367200D01*
X159553Y367700D01*
X159220Y368283D01*
X159387Y368700D01*
X159720Y368950D01*
X160220Y369033D01*
X160720Y368950D01*
X161220Y368700D01*
G01X165820Y370700D02*
Y365700D01*
G01X164653Y369033D02*
X166987D01*
G01X176520Y365700D02*
Y369950D01*
X176687Y370367D01*
X177020Y370617D01*
X177520Y370700D01*
X178020Y370533D01*
X178270Y370117D01*
G01X177270Y368700D02*
X175603D01*
G01X182620Y365700D02*
X182120Y365783D01*
X181620Y366117D01*
X181287Y366700D01*
X181120Y367367D01*
X181287Y368033D01*
X181620Y368617D01*
X182120Y368950D01*
X182620Y369033D01*
X183120Y368950D01*
X183620Y368617D01*
X183953Y368033D01*
X184037Y367367D01*
X183953Y366700D01*
X183620Y366117D01*
X183120Y365783D01*
X182620Y365700D01*
G01X188220D02*
Y370700D01*
G01X193820Y365700D02*
Y370700D01*
G01X199420Y365700D02*
X198920Y365783D01*
X198420Y366117D01*
X198087Y366700D01*
X197920Y367367D01*
X198087Y368033D01*
X198420Y368617D01*
X198920Y368950D01*
X199420Y369033D01*
X199920Y368950D01*
X200420Y368617D01*
X200753Y368033D01*
X200837Y367367D01*
X200753Y366700D01*
X200420Y366117D01*
X199920Y365783D01*
X199420Y365700D01*
G01X202937Y369033D02*
X203937Y365700D01*
X205020Y369033D01*
X206103Y365700D01*
X207103Y369033D01*
G01X159000Y395500D02*
Y390500D01*
G01X157083Y395500D02*
X160917D01*
G01X164600Y390500D02*
X164100Y390583D01*
X163600Y390917D01*
X163267Y391500D01*
X163100Y392167D01*
X163267Y392833D01*
X163600Y393417D01*
X164100Y393750D01*
X164600Y393833D01*
X165100Y393750D01*
X165600Y393417D01*
X165933Y392833D01*
X166017Y392167D01*
X165933Y391500D01*
X165600Y390917D01*
X165100Y390583D01*
X164600Y390500D01*
G01X170200D02*
Y395500D01*
G01X174550Y392750D02*
X177217D01*
X176967Y393333D01*
X176550Y393667D01*
X175967Y393833D01*
X175383Y393750D01*
X174883Y393500D01*
X174550Y392917D01*
X174383Y392417D01*
Y391917D01*
X174550Y391417D01*
X174967Y390917D01*
X175467Y390583D01*
X176050Y390500D01*
X176633Y390667D01*
X177217Y391167D01*
G01X180233Y390500D02*
Y393833D01*
G01Y393167D02*
X180650Y393500D01*
X181067Y393750D01*
X181650Y393833D01*
X182067Y393750D01*
X182567Y393500D01*
G01X188500Y390500D02*
Y393833D01*
G01Y393250D02*
X188167Y393583D01*
X187667Y393750D01*
X187083Y393833D01*
X186500Y393667D01*
X186000Y393333D01*
X185667Y392833D01*
X185500Y392167D01*
X185667Y391500D01*
X186000Y391000D01*
X186500Y390667D01*
X187083Y390500D01*
X187667Y390583D01*
X188167Y390833D01*
X188500Y391167D01*
G01X191183Y390500D02*
Y393833D01*
G01Y393000D02*
X191517Y393417D01*
X192017Y393750D01*
X192683Y393833D01*
X193267Y393750D01*
X193767Y393417D01*
X194017Y392833D01*
Y390500D01*
G01X199533Y393417D02*
X198950Y393750D01*
X198450Y393833D01*
X197783Y393667D01*
X197283Y393333D01*
X196950Y392750D01*
X196867Y392167D01*
X196950Y391583D01*
X197283Y391083D01*
X197783Y390667D01*
X198450Y390500D01*
X199033Y390667D01*
X199533Y391000D01*
G01X202550Y392750D02*
X205217D01*
X204967Y393333D01*
X204550Y393667D01*
X203967Y393833D01*
X203383Y393750D01*
X202883Y393500D01*
X202550Y392917D01*
X202383Y392417D01*
Y391917D01*
X202550Y391417D01*
X202967Y390917D01*
X203467Y390583D01*
X204050Y390500D01*
X204633Y390667D01*
X205217Y391167D01*
G01X192353Y165153D02*
X191520Y165987D01*
X191103Y166820D01*
Y170153D01*
X191520Y170987D01*
X192353Y171820D01*
G01X198370Y166820D02*
X197870Y166903D01*
X197370Y167237D01*
X197037Y167820D01*
X196870Y168487D01*
X197037Y169153D01*
X197370Y169737D01*
X197870Y170070D01*
X198370Y170153D01*
X198870Y170070D01*
X199370Y169737D01*
X199703Y169153D01*
X199787Y168487D01*
X199703Y167820D01*
X199370Y167237D01*
X198870Y166903D01*
X198370Y166820D01*
G01X202803D02*
Y170153D01*
G01Y169487D02*
X203220Y169820D01*
X203637Y170070D01*
X204220Y170153D01*
X204637Y170070D01*
X205137Y169820D01*
G01X236000Y443000D02*
Y-342500D01*
G01X254500Y577500D02*
Y-346000D01*
X884500D01*
Y509000D01*
X254500D01*
G01Y-326000D02*
X884500D01*
G01X264167Y-311250D02*
X264667Y-311667D01*
X265250Y-311917D01*
X266000Y-312000D01*
X266750Y-311833D01*
X267333Y-311500D01*
X267750Y-310917D01*
X267833Y-310250D01*
X267667Y-309583D01*
X267250Y-309167D01*
X266667Y-308833D01*
X266083Y-308750D01*
X265500Y-308833D01*
X264750Y-309167D01*
X265000Y-307000D01*
X267250D01*
G01X271600Y-312167D02*
X271433Y-312083D01*
Y-311917D01*
X271600Y-311833D01*
X271767Y-311917D01*
Y-312083D01*
X271600Y-312167D01*
G01X281133Y-312000D02*
Y-307000D01*
X283217D01*
X283883Y-307250D01*
X284300Y-307583D01*
X284467Y-308250D01*
X284300Y-308917D01*
X283800Y-309333D01*
X283217Y-309583D01*
X281133D01*
G01X283217D02*
X284467Y-312000D01*
G01X287150Y-309750D02*
X289817D01*
X289567Y-309167D01*
X289150Y-308833D01*
X288567Y-308667D01*
X287983Y-308750D01*
X287483Y-309000D01*
X287150Y-309583D01*
X286983Y-310083D01*
Y-310583D01*
X287150Y-311083D01*
X287567Y-311583D01*
X288067Y-311917D01*
X288650Y-312000D01*
X289233Y-311833D01*
X289817Y-311333D01*
G01X291500Y-312000D02*
Y-308667D01*
G01Y-309583D02*
X291750Y-309167D01*
X292167Y-308833D01*
X292750Y-308667D01*
X293333Y-308833D01*
X293750Y-309167D01*
X294000Y-309583D01*
Y-312000D01*
G01Y-309583D02*
X294250Y-309167D01*
X294667Y-308833D01*
X295250Y-308667D01*
X295833Y-308833D01*
X296250Y-309167D01*
X296500Y-309667D01*
Y-312000D01*
G01X301100D02*
Y-308667D01*
G01Y-309250D02*
X300767Y-308917D01*
X300267Y-308750D01*
X299683Y-308667D01*
X299100Y-308833D01*
X298600Y-309167D01*
X298267Y-309667D01*
X298100Y-310333D01*
X298267Y-311000D01*
X298600Y-311500D01*
X299100Y-311833D01*
X299683Y-312000D01*
X300267Y-311917D01*
X300767Y-311667D01*
X301100Y-311333D01*
G01X304033Y-312000D02*
Y-308667D01*
G01Y-309333D02*
X304450Y-309000D01*
X304867Y-308750D01*
X305450Y-308667D01*
X305867Y-308750D01*
X306367Y-309000D01*
G01X309383Y-312000D02*
Y-307000D01*
G01X312050Y-308667D02*
X309383Y-310583D01*
G01X310467Y-309833D02*
X312217Y-312000D01*
G01X314567Y-312167D02*
X318233Y-308500D01*
G01X316400Y-307833D02*
Y-312833D01*
G01X318233Y-312167D02*
X314567Y-308500D01*
G01X313900Y-310333D02*
X318900D01*
G01X254500Y-296000D02*
X884500D01*
G01X254500Y-187500D02*
X884500D01*
G01X254500Y62500D02*
X884500D01*
G01X267000Y76500D02*
Y81500D01*
X263917Y77917D01*
X268083D01*
G01X271600Y76333D02*
X271433Y76417D01*
Y76583D01*
X271600Y76667D01*
X271767Y76583D01*
Y76417D01*
X271600Y76333D01*
G01X281300Y76500D02*
Y81500D01*
G01Y79000D02*
X281717Y79500D01*
X282217Y79750D01*
X282717Y79833D01*
X283467Y79667D01*
X283967Y79333D01*
X284300Y78750D01*
Y78083D01*
X284133Y77417D01*
X283800Y76917D01*
X283217Y76583D01*
X282717Y76500D01*
X282217Y76583D01*
X281717Y76833D01*
X281300Y77250D01*
G01X289900Y76500D02*
Y79833D01*
G01Y79250D02*
X289567Y79583D01*
X289067Y79750D01*
X288483Y79833D01*
X287900Y79667D01*
X287400Y79333D01*
X287067Y78833D01*
X286900Y78167D01*
X287067Y77500D01*
X287400Y77000D01*
X287900Y76667D01*
X288483Y76500D01*
X289067Y76583D01*
X289567Y76833D01*
X289900Y77167D01*
G01X295333Y79417D02*
X294750Y79750D01*
X294250Y79833D01*
X293583Y79667D01*
X293083Y79333D01*
X292750Y78750D01*
X292667Y78167D01*
X292750Y77583D01*
X293083Y77083D01*
X293583Y76667D01*
X294250Y76500D01*
X294833Y76667D01*
X295333Y77000D01*
G01X298183Y76500D02*
Y81500D01*
G01X300850Y79833D02*
X298183Y77917D01*
G01X299267Y78667D02*
X301017Y76500D01*
G01X306700Y81500D02*
Y76500D01*
G01Y77250D02*
X306367Y76833D01*
X305867Y76583D01*
X305283Y76500D01*
X304617Y76667D01*
X304117Y77083D01*
X303783Y77583D01*
X303700Y78167D01*
X303783Y78750D01*
X304117Y79250D01*
X304617Y79667D01*
X305283Y79833D01*
X305867Y79750D01*
X306283Y79583D01*
X306700Y79250D01*
G01X309633Y76500D02*
Y79833D01*
G01Y79167D02*
X310050Y79500D01*
X310467Y79750D01*
X311050Y79833D01*
X311467Y79750D01*
X311967Y79500D01*
G01X316400Y79833D02*
Y76500D01*
G01Y81167D02*
X316233Y81250D01*
Y81417D01*
X316400Y81500D01*
X316567Y81417D01*
Y81250D01*
X316400Y81167D01*
G01X322000Y76500D02*
Y81500D01*
G01X327600Y76500D02*
Y81500D01*
G01X340300Y76500D02*
Y79833D01*
G01Y79250D02*
X339967Y79583D01*
X339467Y79750D01*
X338883Y79833D01*
X338300Y79667D01*
X337800Y79333D01*
X337467Y78833D01*
X337300Y78167D01*
X337467Y77500D01*
X337800Y77000D01*
X338300Y76667D01*
X338883Y76500D01*
X339467Y76583D01*
X339967Y76833D01*
X340300Y77167D01*
G01X342983Y76500D02*
Y79833D01*
G01Y79000D02*
X343317Y79417D01*
X343817Y79750D01*
X344483Y79833D01*
X345067Y79750D01*
X345567Y79417D01*
X345817Y78833D01*
Y76500D01*
G01X351500Y81500D02*
Y76500D01*
G01Y77250D02*
X351167Y76833D01*
X350667Y76583D01*
X350083Y76500D01*
X349417Y76667D01*
X348917Y77083D01*
X348583Y77583D01*
X348500Y78167D01*
X348583Y78750D01*
X348917Y79250D01*
X349417Y79667D01*
X350083Y79833D01*
X350667Y79750D01*
X351083Y79583D01*
X351500Y79250D01*
G01X359950Y77083D02*
X360367Y76750D01*
X360950Y76500D01*
X361450D01*
X361950Y76667D01*
X362283Y76917D01*
X362450Y77250D01*
X362367Y77750D01*
X362033Y78000D01*
X360533Y78500D01*
X360200Y79083D01*
X360367Y79500D01*
X360700Y79750D01*
X361200Y79833D01*
X361700Y79750D01*
X362200Y79500D01*
G01X368300Y74833D02*
Y79833D01*
G01Y79083D02*
X367883Y79500D01*
X367383Y79750D01*
X366800Y79833D01*
X366300Y79750D01*
X365717Y79333D01*
X365383Y78750D01*
X365300Y78167D01*
X365383Y77583D01*
X365717Y77000D01*
X366300Y76583D01*
X366800Y76500D01*
X367383Y76583D01*
X367883Y76833D01*
X368300Y77250D01*
G01X370983Y79833D02*
Y77500D01*
X371317Y76917D01*
X371817Y76583D01*
X372400Y76500D01*
X372983Y76583D01*
X373483Y76917D01*
X373817Y77500D01*
G01Y76500D02*
Y79833D01*
G01X379500Y76500D02*
Y79833D01*
G01Y79250D02*
X379167Y79583D01*
X378667Y79750D01*
X378083Y79833D01*
X377500Y79667D01*
X377000Y79333D01*
X376667Y78833D01*
X376500Y78167D01*
X376667Y77500D01*
X377000Y77000D01*
X377500Y76667D01*
X378083Y76500D01*
X378667Y76583D01*
X379167Y76833D01*
X379500Y77167D01*
G01X382433Y76500D02*
Y79833D01*
G01Y79167D02*
X382850Y79500D01*
X383267Y79750D01*
X383850Y79833D01*
X384267Y79750D01*
X384767Y79500D01*
G01X387950Y78750D02*
X390617D01*
X390367Y79333D01*
X389950Y79667D01*
X389367Y79833D01*
X388783Y79750D01*
X388283Y79500D01*
X387950Y78917D01*
X387783Y78417D01*
Y77917D01*
X387950Y77417D01*
X388367Y76917D01*
X388867Y76583D01*
X389450Y76500D01*
X390033Y76667D01*
X390617Y77167D01*
G01X398983Y76500D02*
Y81500D01*
G01Y79083D02*
X399400Y79500D01*
X399817Y79750D01*
X400483Y79833D01*
X400983Y79750D01*
X401567Y79417D01*
X401817Y78917D01*
Y76500D01*
G01X406000D02*
X405500Y76583D01*
X405000Y76917D01*
X404667Y77500D01*
X404500Y78167D01*
X404667Y78833D01*
X405000Y79417D01*
X405500Y79750D01*
X406000Y79833D01*
X406500Y79750D01*
X407000Y79417D01*
X407333Y78833D01*
X407417Y78167D01*
X407333Y77500D01*
X407000Y76917D01*
X406500Y76583D01*
X406000Y76500D01*
G01X411600D02*
Y81500D01*
G01X415950Y78750D02*
X418617D01*
X418367Y79333D01*
X417950Y79667D01*
X417367Y79833D01*
X416783Y79750D01*
X416283Y79500D01*
X415950Y78917D01*
X415783Y78417D01*
Y77917D01*
X415950Y77417D01*
X416367Y76917D01*
X416867Y76583D01*
X417450Y76500D01*
X418033Y76667D01*
X418617Y77167D01*
G01X422800Y76333D02*
X422633Y76417D01*
Y76583D01*
X422800Y76667D01*
X422967Y76583D01*
Y76417D01*
X422800Y76333D01*
G01Y78583D02*
X422633Y78667D01*
Y78833D01*
X422800Y78917D01*
X422967Y78833D01*
Y78667D01*
X422800Y78583D01*
G01X254500Y92500D02*
X884500D01*
G01X262907Y101673D02*
X266573Y105340D01*
G01X264740Y106007D02*
Y101007D01*
G01X266573Y101673D02*
X262907Y105340D01*
G01X262240Y103507D02*
X267240D01*
G01X269923Y100173D02*
X269090Y101007D01*
X268673Y101840D01*
Y105173D01*
X269090Y106007D01*
X269923Y106840D01*
G01X274107Y102590D02*
X274607Y102173D01*
X275190Y101923D01*
X275940Y101840D01*
X276690Y102007D01*
X277273Y102340D01*
X277690Y102923D01*
X277773Y103590D01*
X277607Y104257D01*
X277190Y104673D01*
X276607Y105007D01*
X276023Y105090D01*
X275440Y105007D01*
X274690Y104673D01*
X274940Y106840D01*
X277190D01*
G01X281540Y101673D02*
X281373Y101757D01*
Y101923D01*
X281540Y102007D01*
X281707Y101923D01*
Y101757D01*
X281540Y101673D01*
G01X287140Y101840D02*
Y106840D01*
X286140Y105840D01*
G01Y101840D02*
X288140D01*
G01X293157Y100173D02*
X293990Y101007D01*
X294407Y101840D01*
Y105173D01*
X293990Y106007D01*
X293157Y106840D01*
G01X262717Y118740D02*
X264800Y113740D01*
X266883Y118740D01*
G01X270400Y117073D02*
Y113740D01*
G01Y118407D02*
X270233Y118490D01*
Y118657D01*
X270400Y118740D01*
X270567Y118657D01*
Y118490D01*
X270400Y118407D01*
G01X277500Y113740D02*
Y117073D01*
G01Y116490D02*
X277167Y116823D01*
X276667Y116990D01*
X276083Y117073D01*
X275500Y116907D01*
X275000Y116573D01*
X274667Y116073D01*
X274500Y115407D01*
X274667Y114740D01*
X275000Y114240D01*
X275500Y113907D01*
X276083Y113740D01*
X276667Y113823D01*
X277167Y114073D01*
X277500Y114407D01*
G01X286200Y118740D02*
X288200D01*
G01X287200D02*
Y113740D01*
G01X286200D02*
X288200D01*
G01X291383D02*
Y117073D01*
G01Y116240D02*
X291717Y116657D01*
X292217Y116990D01*
X292883Y117073D01*
X293467Y116990D01*
X293967Y116657D01*
X294217Y116073D01*
Y113740D01*
G01X302333D02*
Y118740D01*
X304333D01*
X305000Y118490D01*
X305500Y117907D01*
X305667Y117240D01*
X305500Y116573D01*
X305083Y116073D01*
X304333Y115823D01*
X302333D01*
G01X311100Y113740D02*
Y117073D01*
G01Y116490D02*
X310767Y116823D01*
X310267Y116990D01*
X309683Y117073D01*
X309100Y116907D01*
X308600Y116573D01*
X308267Y116073D01*
X308100Y115407D01*
X308267Y114740D01*
X308600Y114240D01*
X309100Y113907D01*
X309683Y113740D01*
X310267Y113823D01*
X310767Y114073D01*
X311100Y114407D01*
G01X316700Y118740D02*
Y113740D01*
G01Y114490D02*
X316367Y114073D01*
X315867Y113823D01*
X315283Y113740D01*
X314617Y113907D01*
X314117Y114323D01*
X313783Y114823D01*
X313700Y115407D01*
X313783Y115990D01*
X314117Y116490D01*
X314617Y116907D01*
X315283Y117073D01*
X315867Y116990D01*
X316283Y116823D01*
X316700Y116490D01*
G01X320383Y112073D02*
X319550Y112907D01*
X319133Y113740D01*
Y117073D01*
X319550Y117907D01*
X320383Y118740D01*
G01X324317D02*
X326400Y113740D01*
X328483Y118740D01*
G01X331000D02*
X333000D01*
G01X332000D02*
Y113740D01*
G01X331000D02*
X333000D01*
G01X335933D02*
Y118740D01*
X337933D01*
X338600Y118490D01*
X339100Y117907D01*
X339267Y117240D01*
X339100Y116573D01*
X338683Y116073D01*
X337933Y115823D01*
X335933D01*
G01X343617Y112073D02*
X344450Y112907D01*
X344867Y113740D01*
Y117073D01*
X344450Y117907D01*
X343617Y118740D01*
G01X254500Y127500D02*
X884500D01*
G01X262607Y135303D02*
X266273Y138970D01*
G01X264440Y139637D02*
Y134637D01*
G01X266273Y135303D02*
X262607Y138970D01*
G01X261940Y137137D02*
X266940D01*
G01X269623Y133803D02*
X268790Y134637D01*
X268373Y135470D01*
Y138803D01*
X268790Y139637D01*
X269623Y140470D01*
G01X273807Y136220D02*
X274307Y135803D01*
X274890Y135553D01*
X275640Y135470D01*
X276390Y135637D01*
X276973Y135970D01*
X277390Y136553D01*
X277473Y137220D01*
X277307Y137887D01*
X276890Y138303D01*
X276307Y138637D01*
X275723Y138720D01*
X275140Y138637D01*
X274390Y138303D01*
X274640Y140470D01*
X276890D01*
G01X281240Y135303D02*
X281073Y135387D01*
Y135553D01*
X281240Y135637D01*
X281407Y135553D01*
Y135387D01*
X281240Y135303D01*
G01X286840Y135470D02*
Y140470D01*
X285840Y139470D01*
G01Y135470D02*
X287840D01*
G01X292857Y133803D02*
X293690Y134637D01*
X294107Y135470D01*
Y138803D01*
X293690Y139637D01*
X292857Y140470D01*
G01X262417Y151500D02*
X264500Y146500D01*
X266583Y151500D01*
G01X270100Y149833D02*
Y146500D01*
G01Y151167D02*
X269933Y151250D01*
Y151417D01*
X270100Y151500D01*
X270267Y151417D01*
Y151250D01*
X270100Y151167D01*
G01X277200Y146500D02*
Y149833D01*
G01Y149250D02*
X276867Y149583D01*
X276367Y149750D01*
X275783Y149833D01*
X275200Y149667D01*
X274700Y149333D01*
X274367Y148833D01*
X274200Y148167D01*
X274367Y147500D01*
X274700Y147000D01*
X275200Y146667D01*
X275783Y146500D01*
X276367Y146583D01*
X276867Y146833D01*
X277200Y147167D01*
G01X286900Y146500D02*
X286233Y146583D01*
X285650Y146917D01*
X285150Y147417D01*
X284817Y148000D01*
X284650Y148667D01*
Y149333D01*
X284817Y150000D01*
X285150Y150583D01*
X285650Y151083D01*
X286233Y151417D01*
X286900Y151500D01*
X287567Y151417D01*
X288150Y151083D01*
X288650Y150583D01*
X288983Y150000D01*
X289150Y149333D01*
Y148667D01*
X288983Y148000D01*
X288650Y147417D01*
X288150Y146917D01*
X287567Y146583D01*
X286900Y146500D01*
G01X291083D02*
Y149833D01*
G01Y149000D02*
X291417Y149417D01*
X291917Y149750D01*
X292583Y149833D01*
X293167Y149750D01*
X293667Y149417D01*
X293917Y148833D01*
Y146500D01*
G01X302033D02*
Y151500D01*
X304033D01*
X304700Y151250D01*
X305200Y150667D01*
X305367Y150000D01*
X305200Y149333D01*
X304783Y148833D01*
X304033Y148583D01*
X302033D01*
G01X310800Y146500D02*
Y149833D01*
G01Y149250D02*
X310467Y149583D01*
X309967Y149750D01*
X309383Y149833D01*
X308800Y149667D01*
X308300Y149333D01*
X307967Y148833D01*
X307800Y148167D01*
X307967Y147500D01*
X308300Y147000D01*
X308800Y146667D01*
X309383Y146500D01*
X309967Y146583D01*
X310467Y146833D01*
X310800Y147167D01*
G01X316400Y151500D02*
Y146500D01*
G01Y147250D02*
X316067Y146833D01*
X315567Y146583D01*
X314983Y146500D01*
X314317Y146667D01*
X313817Y147083D01*
X313483Y147583D01*
X313400Y148167D01*
X313483Y148750D01*
X313817Y149250D01*
X314317Y149667D01*
X314983Y149833D01*
X315567Y149750D01*
X315983Y149583D01*
X316400Y149250D01*
G01X320083Y144833D02*
X319250Y145667D01*
X318833Y146500D01*
Y149833D01*
X319250Y150667D01*
X320083Y151500D01*
G01X324017D02*
X326100Y146500D01*
X328183Y151500D01*
G01X331700Y146500D02*
X331033Y146583D01*
X330450Y146917D01*
X329950Y147417D01*
X329617Y148000D01*
X329450Y148667D01*
Y149333D01*
X329617Y150000D01*
X329950Y150583D01*
X330450Y151083D01*
X331033Y151417D01*
X331700Y151500D01*
X332367Y151417D01*
X332950Y151083D01*
X333450Y150583D01*
X333783Y150000D01*
X333950Y149333D01*
Y148667D01*
X333783Y148000D01*
X333450Y147417D01*
X332950Y146917D01*
X332367Y146583D01*
X331700Y146500D01*
G01X335633D02*
Y151500D01*
X337633D01*
X338300Y151250D01*
X338800Y150667D01*
X338967Y150000D01*
X338800Y149333D01*
X338383Y148833D01*
X337633Y148583D01*
X335633D01*
G01X343317Y144833D02*
X344150Y145667D01*
X344567Y146500D01*
Y149833D01*
X344150Y150667D01*
X343317Y151500D01*
G01X265167Y170167D02*
X265500Y170417D01*
X265750Y170833D01*
X265917Y171417D01*
X265750Y171917D01*
X265417Y172250D01*
X264833Y172500D01*
X262583D01*
Y167500D01*
X265333D01*
X265917Y167833D01*
X266250Y168333D01*
X266417Y168917D01*
X266250Y169500D01*
X265750Y170000D01*
X265167Y170167D01*
X262583D01*
G01X268683Y170833D02*
Y168500D01*
X269017Y167917D01*
X269517Y167583D01*
X270100Y167500D01*
X270683Y167583D01*
X271183Y167917D01*
X271517Y168500D01*
G01Y167500D02*
Y170833D01*
G01X274533Y167500D02*
Y170833D01*
G01Y170167D02*
X274950Y170500D01*
X275367Y170750D01*
X275950Y170833D01*
X276367Y170750D01*
X276867Y170500D01*
G01X281300Y170833D02*
Y167500D01*
G01Y172167D02*
X281133Y172250D01*
Y172417D01*
X281300Y172500D01*
X281467Y172417D01*
Y172250D01*
X281300Y172167D01*
G01X285650Y169750D02*
X288317D01*
X288067Y170333D01*
X287650Y170667D01*
X287067Y170833D01*
X286483Y170750D01*
X285983Y170500D01*
X285650Y169917D01*
X285483Y169417D01*
Y168917D01*
X285650Y168417D01*
X286067Y167917D01*
X286567Y167583D01*
X287150Y167500D01*
X287733Y167667D01*
X288317Y168167D01*
G01X294000Y172500D02*
Y167500D01*
G01Y168250D02*
X293667Y167833D01*
X293167Y167583D01*
X292583Y167500D01*
X291917Y167667D01*
X291417Y168083D01*
X291083Y168583D01*
X291000Y169167D01*
X291083Y169750D01*
X291417Y170250D01*
X291917Y170667D01*
X292583Y170833D01*
X293167Y170750D01*
X293583Y170583D01*
X294000Y170250D01*
G01X302283Y167500D02*
Y172500D01*
G01Y170083D02*
X302700Y170500D01*
X303117Y170750D01*
X303783Y170833D01*
X304283Y170750D01*
X304867Y170417D01*
X305117Y169917D01*
Y167500D01*
G01X309300D02*
X308800Y167583D01*
X308300Y167917D01*
X307967Y168500D01*
X307800Y169167D01*
X307967Y169833D01*
X308300Y170417D01*
X308800Y170750D01*
X309300Y170833D01*
X309800Y170750D01*
X310300Y170417D01*
X310633Y169833D01*
X310717Y169167D01*
X310633Y168500D01*
X310300Y167917D01*
X309800Y167583D01*
X309300Y167500D01*
G01X314900D02*
Y172500D01*
G01X319250Y169750D02*
X321917D01*
X321667Y170333D01*
X321250Y170667D01*
X320667Y170833D01*
X320083Y170750D01*
X319583Y170500D01*
X319250Y169917D01*
X319083Y169417D01*
Y168917D01*
X319250Y168417D01*
X319667Y167917D01*
X320167Y167583D01*
X320750Y167500D01*
X321333Y167667D01*
X321917Y168167D01*
G01X254500Y162500D02*
X884500D01*
G01X254500Y177500D02*
X884500D01*
G01X262917Y188500D02*
Y193500D01*
X266083D01*
G01X264917Y191083D02*
X262917D01*
G01X268683Y191833D02*
Y189500D01*
X269017Y188917D01*
X269517Y188583D01*
X270100Y188500D01*
X270683Y188583D01*
X271183Y188917D01*
X271517Y189500D01*
G01Y188500D02*
Y191833D01*
G01X275700Y188500D02*
Y193500D01*
G01X281300Y188500D02*
Y193500D01*
G01X291000Y186833D02*
Y191833D01*
G01Y191083D02*
X291417Y191500D01*
X291833Y191750D01*
X292500Y191833D01*
X293083Y191750D01*
X293667Y191333D01*
X293917Y190750D01*
X294000Y190167D01*
X293917Y189583D01*
X293667Y189000D01*
X293167Y188667D01*
X292500Y188500D01*
X291917Y188583D01*
X291333Y188833D01*
X291000Y189167D01*
G01X298100Y188500D02*
Y193500D01*
G01X302283Y191833D02*
Y189500D01*
X302617Y188917D01*
X303117Y188583D01*
X303700Y188500D01*
X304283Y188583D01*
X304783Y188917D01*
X305117Y189500D01*
G01Y188500D02*
Y191833D01*
G01X308133Y187250D02*
X308717Y186917D01*
X309383Y186833D01*
X309967Y186917D01*
X310467Y187333D01*
X310800Y187917D01*
Y191833D01*
G01Y191167D02*
X310467Y191500D01*
X309967Y191750D01*
X309383Y191833D01*
X308717Y191667D01*
X308300Y191333D01*
X307967Y190750D01*
X307800Y190167D01*
X307883Y189667D01*
X308217Y189083D01*
X308717Y188667D01*
X309383Y188500D01*
X309883Y188583D01*
X310467Y188917D01*
X310800Y189250D01*
G01X313733Y187250D02*
X314317Y186917D01*
X314983Y186833D01*
X315567Y186917D01*
X316067Y187333D01*
X316400Y187917D01*
Y191833D01*
G01Y191167D02*
X316067Y191500D01*
X315567Y191750D01*
X314983Y191833D01*
X314317Y191667D01*
X313900Y191333D01*
X313567Y190750D01*
X313400Y190167D01*
X313483Y189667D01*
X313817Y189083D01*
X314317Y188667D01*
X314983Y188500D01*
X315483Y188583D01*
X316067Y188917D01*
X316400Y189250D01*
G01X320500Y191833D02*
Y188500D01*
G01Y193167D02*
X320333Y193250D01*
Y193417D01*
X320500Y193500D01*
X320667Y193417D01*
Y193250D01*
X320500Y193167D01*
G01X324683Y188500D02*
Y191833D01*
G01Y191000D02*
X325017Y191417D01*
X325517Y191750D01*
X326183Y191833D01*
X326767Y191750D01*
X327267Y191417D01*
X327517Y190833D01*
Y188500D01*
G01X330533Y187250D02*
X331117Y186917D01*
X331783Y186833D01*
X332367Y186917D01*
X332867Y187333D01*
X333200Y187917D01*
Y191833D01*
G01Y191167D02*
X332867Y191500D01*
X332367Y191750D01*
X331783Y191833D01*
X331117Y191667D01*
X330700Y191333D01*
X330367Y190750D01*
X330200Y190167D01*
X330283Y189667D01*
X330617Y189083D01*
X331117Y188667D01*
X331783Y188500D01*
X332283Y188583D01*
X332867Y188917D01*
X333200Y189250D01*
G01X254500Y204500D02*
X884500D01*
G01X262750Y257000D02*
Y262000D01*
G01X266250D02*
Y257000D01*
G01Y259500D02*
X262750D01*
G01X271600Y257000D02*
Y260333D01*
G01Y259750D02*
X271267Y260083D01*
X270767Y260250D01*
X270183Y260333D01*
X269600Y260167D01*
X269100Y259833D01*
X268767Y259333D01*
X268600Y258667D01*
X268767Y258000D01*
X269100Y257500D01*
X269600Y257167D01*
X270183Y257000D01*
X270767Y257083D01*
X271267Y257333D01*
X271600Y257667D01*
G01X275700Y257000D02*
Y262000D01*
G01X280800Y257000D02*
Y261250D01*
X280967Y261667D01*
X281300Y261917D01*
X281800Y262000D01*
X282300Y261833D01*
X282550Y261417D01*
G01X281550Y260000D02*
X279883D01*
G01X290833Y257000D02*
Y262000D01*
X292833D01*
X293500Y261750D01*
X294000Y261167D01*
X294167Y260500D01*
X294000Y259833D01*
X293583Y259333D01*
X292833Y259083D01*
X290833D01*
G01X298100Y257000D02*
Y262000D01*
G01X302283Y260333D02*
Y258000D01*
X302617Y257417D01*
X303117Y257083D01*
X303700Y257000D01*
X304283Y257083D01*
X304783Y257417D01*
X305117Y258000D01*
G01Y257000D02*
Y260333D01*
G01X308133Y255750D02*
X308717Y255417D01*
X309383Y255333D01*
X309967Y255417D01*
X310467Y255833D01*
X310800Y256417D01*
Y260333D01*
G01Y259667D02*
X310467Y260000D01*
X309967Y260250D01*
X309383Y260333D01*
X308717Y260167D01*
X308300Y259833D01*
X307967Y259250D01*
X307800Y258667D01*
X307883Y258167D01*
X308217Y257583D01*
X308717Y257167D01*
X309383Y257000D01*
X309883Y257083D01*
X310467Y257417D01*
X310800Y257750D01*
G01X313733Y255750D02*
X314317Y255417D01*
X314983Y255333D01*
X315567Y255417D01*
X316067Y255833D01*
X316400Y256417D01*
Y260333D01*
G01Y259667D02*
X316067Y260000D01*
X315567Y260250D01*
X314983Y260333D01*
X314317Y260167D01*
X313900Y259833D01*
X313567Y259250D01*
X313400Y258667D01*
X313483Y258167D01*
X313817Y257583D01*
X314317Y257167D01*
X314983Y257000D01*
X315483Y257083D01*
X316067Y257417D01*
X316400Y257750D01*
G01X320500Y260333D02*
Y257000D01*
G01Y261667D02*
X320333Y261750D01*
Y261917D01*
X320500Y262000D01*
X320667Y261917D01*
Y261750D01*
X320500Y261667D01*
G01X324683Y257000D02*
Y260333D01*
G01Y259500D02*
X325017Y259917D01*
X325517Y260250D01*
X326183Y260333D01*
X326767Y260250D01*
X327267Y259917D01*
X327517Y259333D01*
Y257000D01*
G01X330533Y255750D02*
X331117Y255417D01*
X331783Y255333D01*
X332367Y255417D01*
X332867Y255833D01*
X333200Y256417D01*
Y260333D01*
G01Y259667D02*
X332867Y260000D01*
X332367Y260250D01*
X331783Y260333D01*
X331117Y260167D01*
X330700Y259833D01*
X330367Y259250D01*
X330200Y258667D01*
X330283Y258167D01*
X330617Y257583D01*
X331117Y257167D01*
X331783Y257000D01*
X332283Y257083D01*
X332867Y257417D01*
X333200Y257750D01*
G01X254500Y306500D02*
X884500D01*
G01X264333Y316000D02*
Y321000D01*
X266333D01*
X267000Y320750D01*
X267500Y320167D01*
X267667Y319500D01*
X267500Y318833D01*
X267083Y318333D01*
X266333Y318083D01*
X264333D01*
G01X271600Y316000D02*
Y321000D01*
G01X275783Y319333D02*
Y317000D01*
X276117Y316417D01*
X276617Y316083D01*
X277200Y316000D01*
X277783Y316083D01*
X278283Y316417D01*
X278617Y317000D01*
G01Y316000D02*
Y319333D01*
G01X281633Y314750D02*
X282217Y314417D01*
X282883Y314333D01*
X283467Y314417D01*
X283967Y314833D01*
X284300Y315417D01*
Y319333D01*
G01Y318667D02*
X283967Y319000D01*
X283467Y319250D01*
X282883Y319333D01*
X282217Y319167D01*
X281800Y318833D01*
X281467Y318250D01*
X281300Y317667D01*
X281383Y317167D01*
X281717Y316583D01*
X282217Y316167D01*
X282883Y316000D01*
X283383Y316083D01*
X283967Y316417D01*
X284300Y316750D01*
G01X287233Y314750D02*
X287817Y314417D01*
X288483Y314333D01*
X289067Y314417D01*
X289567Y314833D01*
X289900Y315417D01*
Y319333D01*
G01Y318667D02*
X289567Y319000D01*
X289067Y319250D01*
X288483Y319333D01*
X287817Y319167D01*
X287400Y318833D01*
X287067Y318250D01*
X286900Y317667D01*
X286983Y317167D01*
X287317Y316583D01*
X287817Y316167D01*
X288483Y316000D01*
X288983Y316083D01*
X289567Y316417D01*
X289900Y316750D01*
G01X294000Y319333D02*
Y316000D01*
G01Y320667D02*
X293833Y320750D01*
Y320917D01*
X294000Y321000D01*
X294167Y320917D01*
Y320750D01*
X294000Y320667D01*
G01X298183Y316000D02*
Y319333D01*
G01Y318500D02*
X298517Y318917D01*
X299017Y319250D01*
X299683Y319333D01*
X300267Y319250D01*
X300767Y318917D01*
X301017Y318333D01*
Y316000D01*
G01X304033Y314750D02*
X304617Y314417D01*
X305283Y314333D01*
X305867Y314417D01*
X306367Y314833D01*
X306700Y315417D01*
Y319333D01*
G01Y318667D02*
X306367Y319000D01*
X305867Y319250D01*
X305283Y319333D01*
X304617Y319167D01*
X304200Y318833D01*
X303867Y318250D01*
X303700Y317667D01*
X303783Y317167D01*
X304117Y316583D01*
X304617Y316167D01*
X305283Y316000D01*
X305783Y316083D01*
X306367Y316417D01*
X306700Y316750D01*
G01X317900Y321000D02*
Y316000D01*
G01Y316750D02*
X317567Y316333D01*
X317067Y316083D01*
X316483Y316000D01*
X315817Y316167D01*
X315317Y316583D01*
X314983Y317083D01*
X314900Y317667D01*
X314983Y318250D01*
X315317Y318750D01*
X315817Y319167D01*
X316483Y319333D01*
X317067Y319250D01*
X317483Y319083D01*
X317900Y318750D01*
G01X320750Y318250D02*
X323417D01*
X323167Y318833D01*
X322750Y319167D01*
X322167Y319333D01*
X321583Y319250D01*
X321083Y319000D01*
X320750Y318417D01*
X320583Y317917D01*
Y317417D01*
X320750Y316917D01*
X321167Y316417D01*
X321667Y316083D01*
X322250Y316000D01*
X322833Y316167D01*
X323417Y316667D01*
G01X327100Y316000D02*
Y320250D01*
X327267Y320667D01*
X327600Y320917D01*
X328100Y321000D01*
X328600Y320833D01*
X328850Y320417D01*
G01X327850Y319000D02*
X326183D01*
G01X333200Y319333D02*
Y316000D01*
G01Y320667D02*
X333033Y320750D01*
Y320917D01*
X333200Y321000D01*
X333367Y320917D01*
Y320750D01*
X333200Y320667D01*
G01X337383Y316000D02*
Y319333D01*
G01Y318500D02*
X337717Y318917D01*
X338217Y319250D01*
X338883Y319333D01*
X339467Y319250D01*
X339967Y318917D01*
X340217Y318333D01*
Y316000D01*
G01X343150Y318250D02*
X345817D01*
X345567Y318833D01*
X345150Y319167D01*
X344567Y319333D01*
X343983Y319250D01*
X343483Y319000D01*
X343150Y318417D01*
X342983Y317917D01*
Y317417D01*
X343150Y316917D01*
X343567Y316417D01*
X344067Y316083D01*
X344650Y316000D01*
X345233Y316167D01*
X345817Y316667D01*
G01X254500Y331500D02*
X884500D01*
G01X264167Y492000D02*
X264667Y491417D01*
X265333Y491083D01*
X266083Y491000D01*
X266750Y491083D01*
X267417Y491500D01*
X267833Y492000D01*
X267917Y492500D01*
X267750Y493083D01*
X267167Y493500D01*
X266583Y493667D01*
X265833D01*
G01X266583D02*
X267083Y493917D01*
X267500Y494333D01*
X267667Y494833D01*
X267500Y495333D01*
X267083Y495750D01*
X266333Y496000D01*
X265583Y495917D01*
X264833Y495583D01*
G01X271600Y490833D02*
X271433Y490917D01*
Y491083D01*
X271600Y491167D01*
X271767Y491083D01*
Y490917D01*
X271600Y490833D01*
G01X281133Y491000D02*
Y496000D01*
X283133D01*
X283800Y495750D01*
X284300Y495167D01*
X284467Y494500D01*
X284300Y493833D01*
X283883Y493333D01*
X283133Y493083D01*
X281133D01*
G01X288400Y491000D02*
Y496000D01*
G01X292583Y494333D02*
Y492000D01*
X292917Y491417D01*
X293417Y491083D01*
X294000Y491000D01*
X294583Y491083D01*
X295083Y491417D01*
X295417Y492000D01*
G01Y491000D02*
Y494333D01*
G01X298433Y489750D02*
X299017Y489417D01*
X299683Y489333D01*
X300267Y489417D01*
X300767Y489833D01*
X301100Y490417D01*
Y494333D01*
G01Y493667D02*
X300767Y494000D01*
X300267Y494250D01*
X299683Y494333D01*
X299017Y494167D01*
X298600Y493833D01*
X298267Y493250D01*
X298100Y492667D01*
X298183Y492167D01*
X298517Y491583D01*
X299017Y491167D01*
X299683Y491000D01*
X300183Y491083D01*
X300767Y491417D01*
X301100Y491750D01*
G01X309300Y494333D02*
X310800Y491000D01*
X312300Y494333D01*
G01X316400D02*
Y491000D01*
G01Y495667D02*
X316233Y495750D01*
Y495917D01*
X316400Y496000D01*
X316567Y495917D01*
Y495750D01*
X316400Y495667D01*
G01X323500Y491000D02*
Y494333D01*
G01Y493750D02*
X323167Y494083D01*
X322667Y494250D01*
X322083Y494333D01*
X321500Y494167D01*
X321000Y493833D01*
X320667Y493333D01*
X320500Y492667D01*
X320667Y492000D01*
X321000Y491500D01*
X321500Y491167D01*
X322083Y491000D01*
X322667Y491083D01*
X323167Y491333D01*
X323500Y491667D01*
G01X331700Y490833D02*
X334700Y496000D01*
G01X336717D02*
X338800Y491000D01*
X340883Y496000D01*
G01X344400Y491000D02*
X343733Y491083D01*
X343150Y491417D01*
X342650Y491917D01*
X342317Y492500D01*
X342150Y493167D01*
Y493833D01*
X342317Y494500D01*
X342650Y495083D01*
X343150Y495583D01*
X343733Y495917D01*
X344400Y496000D01*
X345067Y495917D01*
X345650Y495583D01*
X346150Y495083D01*
X346483Y494500D01*
X346650Y493833D01*
Y493167D01*
X346483Y492500D01*
X346150Y491917D01*
X345650Y491417D01*
X345067Y491083D01*
X344400Y491000D01*
G01X348333D02*
Y496000D01*
X350333D01*
X351000Y495750D01*
X351500Y495167D01*
X351667Y494500D01*
X351500Y493833D01*
X351083Y493333D01*
X350333Y493083D01*
X348333D01*
G01X354100Y490833D02*
X357100Y496000D01*
G01X359117D02*
X361200Y491000D01*
X363283Y496000D01*
G01X365800D02*
X367800D01*
G01X366800D02*
Y491000D01*
G01X365800D02*
X367800D01*
G01X370733D02*
Y496000D01*
X372733D01*
X373400Y495750D01*
X373900Y495167D01*
X374067Y494500D01*
X373900Y493833D01*
X373483Y493333D01*
X372733Y493083D01*
X370733D01*
G01X378000Y490833D02*
X377833Y490917D01*
Y491083D01*
X378000Y491167D01*
X378167Y491083D01*
Y490917D01*
X378000Y490833D01*
G01Y493083D02*
X377833Y493167D01*
Y493333D01*
X378000Y493417D01*
X378167Y493333D01*
Y493167D01*
X378000Y493083D01*
G01X254500Y479000D02*
X886000D01*
G01X266313Y540000D02*
Y545000D01*
X268397D01*
X269063Y544750D01*
X269480Y544417D01*
X269647Y543750D01*
X269480Y543083D01*
X268980Y542667D01*
X268397Y542417D01*
X266313D01*
G01X268397D02*
X269647Y540000D01*
G01X273580D02*
X273080Y540083D01*
X272580Y540417D01*
X272247Y541000D01*
X272080Y541667D01*
X272247Y542333D01*
X272580Y542917D01*
X273080Y543250D01*
X273580Y543333D01*
X274080Y543250D01*
X274580Y542917D01*
X274913Y542333D01*
X274997Y541667D01*
X274913Y541000D01*
X274580Y540417D01*
X274080Y540083D01*
X273580Y540000D01*
G01X277763Y543333D02*
Y541000D01*
X278097Y540417D01*
X278597Y540083D01*
X279180Y540000D01*
X279763Y540083D01*
X280263Y540417D01*
X280597Y541000D01*
G01Y540000D02*
Y543333D01*
G01X284780Y545000D02*
Y540000D01*
G01X283613Y543333D02*
X285947D01*
G01X290380D02*
Y540000D01*
G01Y544667D02*
X290213Y544750D01*
Y544917D01*
X290380Y545000D01*
X290547Y544917D01*
Y544750D01*
X290380Y544667D01*
G01X294563Y540000D02*
Y543333D01*
G01Y542500D02*
X294897Y542917D01*
X295397Y543250D01*
X296063Y543333D01*
X296647Y543250D01*
X297147Y542917D01*
X297397Y542333D01*
Y540000D01*
G01X300413Y538750D02*
X300997Y538417D01*
X301663Y538333D01*
X302247Y538417D01*
X302747Y538833D01*
X303080Y539417D01*
Y543333D01*
G01Y542667D02*
X302747Y543000D01*
X302247Y543250D01*
X301663Y543333D01*
X300997Y543167D01*
X300580Y542833D01*
X300247Y542250D01*
X300080Y541667D01*
X300163Y541167D01*
X300497Y540583D01*
X300997Y540167D01*
X301663Y540000D01*
X302163Y540083D01*
X302747Y540417D01*
X303080Y540750D01*
G01X254480Y577500D02*
X884500D01*
G01X278437Y-338320D02*
X278937Y-338737D01*
X279520Y-338987D01*
X280270Y-339070D01*
X281020Y-338903D01*
X281603Y-338570D01*
X282020Y-337987D01*
X282103Y-337320D01*
X281937Y-336653D01*
X281520Y-336237D01*
X280937Y-335903D01*
X280353Y-335820D01*
X279770Y-335903D01*
X279020Y-336237D01*
X279270Y-334070D01*
X281520D01*
G01X285870Y-339237D02*
X285703Y-339153D01*
Y-338987D01*
X285870Y-338903D01*
X286037Y-338987D01*
Y-339153D01*
X285870Y-339237D01*
G01X291470Y-339070D02*
Y-334070D01*
X290470Y-335070D01*
G01Y-339070D02*
X292470D01*
G01X301670Y-334070D02*
X303670D01*
G01X302670D02*
Y-339070D01*
G01X301670D02*
X303670D01*
G01X307770D02*
Y-334820D01*
X307937Y-334403D01*
X308270Y-334153D01*
X308770Y-334070D01*
X309270Y-334237D01*
X309520Y-334653D01*
G01X308520Y-336070D02*
X306853D01*
G01X319970Y-336570D02*
X321637D01*
Y-338070D01*
X321137Y-338570D01*
X320553Y-338903D01*
X319720Y-339070D01*
X318887Y-338903D01*
X318303Y-338570D01*
X317803Y-338070D01*
X317470Y-337487D01*
X317303Y-336820D01*
Y-336237D01*
X317470Y-335737D01*
X317803Y-335153D01*
X318303Y-334653D01*
X318803Y-334320D01*
X319470Y-334070D01*
X320053D01*
X320720Y-334237D01*
X321220Y-334570D01*
G01X323820Y-336820D02*
X326487D01*
X326237Y-336237D01*
X325820Y-335903D01*
X325237Y-335737D01*
X324653Y-335820D01*
X324153Y-336070D01*
X323820Y-336653D01*
X323653Y-337153D01*
Y-337653D01*
X323820Y-338153D01*
X324237Y-338653D01*
X324737Y-338987D01*
X325320Y-339070D01*
X325903Y-338903D01*
X326487Y-338403D01*
G01X329503Y-339070D02*
Y-335737D01*
G01Y-336403D02*
X329920Y-336070D01*
X330337Y-335820D01*
X330920Y-335737D01*
X331337Y-335820D01*
X331837Y-336070D01*
G01X334770Y-339070D02*
Y-334070D01*
G01Y-336570D02*
X335187Y-336070D01*
X335687Y-335820D01*
X336187Y-335737D01*
X336937Y-335903D01*
X337437Y-336237D01*
X337770Y-336820D01*
Y-337487D01*
X337603Y-338153D01*
X337270Y-338653D01*
X336687Y-338987D01*
X336187Y-339070D01*
X335687Y-338987D01*
X335187Y-338737D01*
X334770Y-338320D01*
G01X340620Y-336820D02*
X343287D01*
X343037Y-336237D01*
X342620Y-335903D01*
X342037Y-335737D01*
X341453Y-335820D01*
X340953Y-336070D01*
X340620Y-336653D01*
X340453Y-337153D01*
Y-337653D01*
X340620Y-338153D01*
X341037Y-338653D01*
X341537Y-338987D01*
X342120Y-339070D01*
X342703Y-338903D01*
X343287Y-338403D01*
G01X346303Y-339070D02*
Y-335737D01*
G01Y-336403D02*
X346720Y-336070D01*
X347137Y-335820D01*
X347720Y-335737D01*
X348137Y-335820D01*
X348637Y-336070D01*
G01X357253Y-339070D02*
Y-334070D01*
G01Y-336487D02*
X357670Y-336070D01*
X358087Y-335820D01*
X358753Y-335737D01*
X359253Y-335820D01*
X359837Y-336153D01*
X360087Y-336653D01*
Y-339070D01*
G01X365770D02*
Y-335737D01*
G01Y-336320D02*
X365437Y-335987D01*
X364937Y-335820D01*
X364353Y-335737D01*
X363770Y-335903D01*
X363270Y-336237D01*
X362937Y-336737D01*
X362770Y-337403D01*
X362937Y-338070D01*
X363270Y-338570D01*
X363770Y-338903D01*
X364353Y-339070D01*
X364937Y-338987D01*
X365437Y-338737D01*
X365770Y-338403D01*
G01X368620Y-338487D02*
X369037Y-338820D01*
X369620Y-339070D01*
X370120D01*
X370620Y-338903D01*
X370953Y-338653D01*
X371120Y-338320D01*
X371037Y-337820D01*
X370703Y-337570D01*
X369203Y-337070D01*
X368870Y-336487D01*
X369037Y-336070D01*
X369370Y-335820D01*
X369870Y-335737D01*
X370370Y-335820D01*
X370870Y-336070D01*
G01X381070Y-334070D02*
Y-339070D01*
G01X379903Y-335737D02*
X382237D01*
G01X385253Y-339070D02*
Y-334070D01*
G01Y-336487D02*
X385670Y-336070D01*
X386087Y-335820D01*
X386753Y-335737D01*
X387253Y-335820D01*
X387837Y-336153D01*
X388087Y-336653D01*
Y-339070D01*
G01X392270Y-335737D02*
Y-339070D01*
G01Y-334403D02*
X392103Y-334320D01*
Y-334153D01*
X392270Y-334070D01*
X392437Y-334153D01*
Y-334320D01*
X392270Y-334403D01*
G01X396620Y-338487D02*
X397037Y-338820D01*
X397620Y-339070D01*
X398120D01*
X398620Y-338903D01*
X398953Y-338653D01*
X399120Y-338320D01*
X399037Y-337820D01*
X398703Y-337570D01*
X397203Y-337070D01*
X396870Y-336487D01*
X397037Y-336070D01*
X397370Y-335820D01*
X397870Y-335737D01*
X398370Y-335820D01*
X398870Y-336070D01*
G01X407653Y-339070D02*
Y-334070D01*
G01X410320Y-335737D02*
X407653Y-337653D01*
G01X408737Y-336903D02*
X410487Y-339070D01*
G01X414670Y-335737D02*
Y-339070D01*
G01Y-334403D02*
X414503Y-334320D01*
Y-334153D01*
X414670Y-334070D01*
X414837Y-334153D01*
Y-334320D01*
X414670Y-334403D01*
G01X418853Y-339070D02*
Y-335737D01*
G01Y-336570D02*
X419187Y-336153D01*
X419687Y-335820D01*
X420353Y-335737D01*
X420937Y-335820D01*
X421437Y-336153D01*
X421687Y-336737D01*
Y-339070D01*
G01X427370Y-334070D02*
Y-339070D01*
G01Y-338320D02*
X427037Y-338737D01*
X426537Y-338987D01*
X425953Y-339070D01*
X425287Y-338903D01*
X424787Y-338487D01*
X424453Y-337987D01*
X424370Y-337403D01*
X424453Y-336820D01*
X424787Y-336320D01*
X425287Y-335903D01*
X425953Y-335737D01*
X426537Y-335820D01*
X426953Y-335987D01*
X427370Y-336320D01*
G01X437070Y-339070D02*
X436570Y-338987D01*
X436070Y-338653D01*
X435737Y-338070D01*
X435570Y-337403D01*
X435737Y-336737D01*
X436070Y-336153D01*
X436570Y-335820D01*
X437070Y-335737D01*
X437570Y-335820D01*
X438070Y-336153D01*
X438403Y-336737D01*
X438487Y-337403D01*
X438403Y-338070D01*
X438070Y-338653D01*
X437570Y-338987D01*
X437070Y-339070D01*
G01X442170D02*
Y-334820D01*
X442337Y-334403D01*
X442670Y-334153D01*
X443170Y-334070D01*
X443670Y-334237D01*
X443920Y-334653D01*
G01X442920Y-336070D02*
X441253D01*
G01X455370Y-334070D02*
Y-339070D01*
G01Y-338320D02*
X455037Y-338737D01*
X454537Y-338987D01*
X453953Y-339070D01*
X453287Y-338903D01*
X452787Y-338487D01*
X452453Y-337987D01*
X452370Y-337403D01*
X452453Y-336820D01*
X452787Y-336320D01*
X453287Y-335903D01*
X453953Y-335737D01*
X454537Y-335820D01*
X454953Y-335987D01*
X455370Y-336320D01*
G01X458220Y-336820D02*
X460887D01*
X460637Y-336237D01*
X460220Y-335903D01*
X459637Y-335737D01*
X459053Y-335820D01*
X458553Y-336070D01*
X458220Y-336653D01*
X458053Y-337153D01*
Y-337653D01*
X458220Y-338153D01*
X458637Y-338653D01*
X459137Y-338987D01*
X459720Y-339070D01*
X460303Y-338903D01*
X460887Y-338403D01*
G01X463820Y-338487D02*
X464237Y-338820D01*
X464820Y-339070D01*
X465320D01*
X465820Y-338903D01*
X466153Y-338653D01*
X466320Y-338320D01*
X466237Y-337820D01*
X465903Y-337570D01*
X464403Y-337070D01*
X464070Y-336487D01*
X464237Y-336070D01*
X464570Y-335820D01*
X465070Y-335737D01*
X465570Y-335820D01*
X466070Y-336070D01*
G01X470670Y-335737D02*
Y-339070D01*
G01Y-334403D02*
X470503Y-334320D01*
Y-334153D01*
X470670Y-334070D01*
X470837Y-334153D01*
Y-334320D01*
X470670Y-334403D01*
G01X475103Y-340320D02*
X475687Y-340653D01*
X476353Y-340737D01*
X476937Y-340653D01*
X477437Y-340237D01*
X477770Y-339653D01*
Y-335737D01*
G01Y-336403D02*
X477437Y-336070D01*
X476937Y-335820D01*
X476353Y-335737D01*
X475687Y-335903D01*
X475270Y-336237D01*
X474937Y-336820D01*
X474770Y-337403D01*
X474853Y-337903D01*
X475187Y-338487D01*
X475687Y-338903D01*
X476353Y-339070D01*
X476853Y-338987D01*
X477437Y-338653D01*
X477770Y-338320D01*
G01X480453Y-339070D02*
Y-335737D01*
G01Y-336570D02*
X480787Y-336153D01*
X481287Y-335820D01*
X481953Y-335737D01*
X482537Y-335820D01*
X483037Y-336153D01*
X483287Y-336737D01*
Y-339070D01*
G01X487303Y-339987D02*
X487637Y-338903D01*
G01X497170Y-340737D02*
Y-335737D01*
G01Y-336487D02*
X497587Y-336070D01*
X498003Y-335820D01*
X498670Y-335737D01*
X499253Y-335820D01*
X499837Y-336237D01*
X500087Y-336820D01*
X500170Y-337403D01*
X500087Y-337987D01*
X499837Y-338570D01*
X499337Y-338903D01*
X498670Y-339070D01*
X498087Y-338987D01*
X497503Y-338737D01*
X497170Y-338403D01*
G01X504270Y-339070D02*
Y-334070D01*
G01X508620Y-336820D02*
X511287D01*
X511037Y-336237D01*
X510620Y-335903D01*
X510037Y-335737D01*
X509453Y-335820D01*
X508953Y-336070D01*
X508620Y-336653D01*
X508453Y-337153D01*
Y-337653D01*
X508620Y-338153D01*
X509037Y-338653D01*
X509537Y-338987D01*
X510120Y-339070D01*
X510703Y-338903D01*
X511287Y-338403D01*
G01X516970Y-339070D02*
Y-335737D01*
G01Y-336320D02*
X516637Y-335987D01*
X516137Y-335820D01*
X515553Y-335737D01*
X514970Y-335903D01*
X514470Y-336237D01*
X514137Y-336737D01*
X513970Y-337403D01*
X514137Y-338070D01*
X514470Y-338570D01*
X514970Y-338903D01*
X515553Y-339070D01*
X516137Y-338987D01*
X516637Y-338737D01*
X516970Y-338403D01*
G01X519820Y-338487D02*
X520237Y-338820D01*
X520820Y-339070D01*
X521320D01*
X521820Y-338903D01*
X522153Y-338653D01*
X522320Y-338320D01*
X522237Y-337820D01*
X521903Y-337570D01*
X520403Y-337070D01*
X520070Y-336487D01*
X520237Y-336070D01*
X520570Y-335820D01*
X521070Y-335737D01*
X521570Y-335820D01*
X522070Y-336070D01*
G01X525420Y-336820D02*
X528087D01*
X527837Y-336237D01*
X527420Y-335903D01*
X526837Y-335737D01*
X526253Y-335820D01*
X525753Y-336070D01*
X525420Y-336653D01*
X525253Y-337153D01*
Y-337653D01*
X525420Y-338153D01*
X525837Y-338653D01*
X526337Y-338987D01*
X526920Y-339070D01*
X527503Y-338903D01*
X528087Y-338403D01*
G01X537370Y-339070D02*
Y-334820D01*
X537537Y-334403D01*
X537870Y-334153D01*
X538370Y-334070D01*
X538870Y-334237D01*
X539120Y-334653D01*
G01X538120Y-336070D02*
X536453D01*
G01X543470Y-339070D02*
X542970Y-338987D01*
X542470Y-338653D01*
X542137Y-338070D01*
X541970Y-337403D01*
X542137Y-336737D01*
X542470Y-336153D01*
X542970Y-335820D01*
X543470Y-335737D01*
X543970Y-335820D01*
X544470Y-336153D01*
X544803Y-336737D01*
X544887Y-337403D01*
X544803Y-338070D01*
X544470Y-338653D01*
X543970Y-338987D01*
X543470Y-339070D01*
G01X549070D02*
Y-334070D01*
G01X554670Y-339070D02*
Y-334070D01*
G01X560270Y-339070D02*
X559770Y-338987D01*
X559270Y-338653D01*
X558937Y-338070D01*
X558770Y-337403D01*
X558937Y-336737D01*
X559270Y-336153D01*
X559770Y-335820D01*
X560270Y-335737D01*
X560770Y-335820D01*
X561270Y-336153D01*
X561603Y-336737D01*
X561687Y-337403D01*
X561603Y-338070D01*
X561270Y-338653D01*
X560770Y-338987D01*
X560270Y-339070D01*
G01X563787Y-335737D02*
X564787Y-339070D01*
X565870Y-335737D01*
X566953Y-339070D01*
X567953Y-335737D01*
G01X571470Y-339237D02*
X571303Y-339153D01*
Y-338987D01*
X571470Y-338903D01*
X571637Y-338987D01*
Y-339153D01*
X571470Y-339237D01*
G01X581670Y-334070D02*
X583670D01*
G01X582670D02*
Y-339070D01*
G01X581670D02*
X583670D01*
G01X587770D02*
Y-334820D01*
X587937Y-334403D01*
X588270Y-334153D01*
X588770Y-334070D01*
X589270Y-334237D01*
X589520Y-334653D01*
G01X588520Y-336070D02*
X586853D01*
G01X598053Y-339070D02*
Y-335737D01*
G01Y-336570D02*
X598387Y-336153D01*
X598887Y-335820D01*
X599553Y-335737D01*
X600137Y-335820D01*
X600637Y-336153D01*
X600887Y-336737D01*
Y-339070D01*
G01X605070D02*
X604570Y-338987D01*
X604070Y-338653D01*
X603737Y-338070D01*
X603570Y-337403D01*
X603737Y-336737D01*
X604070Y-336153D01*
X604570Y-335820D01*
X605070Y-335737D01*
X605570Y-335820D01*
X606070Y-336153D01*
X606403Y-336737D01*
X606487Y-337403D01*
X606403Y-338070D01*
X606070Y-338653D01*
X605570Y-338987D01*
X605070Y-339070D01*
G01X610670Y-334070D02*
Y-339070D01*
G01X609503Y-335737D02*
X611837D01*
G01X616103Y-339987D02*
X616437Y-338903D01*
G01X625970Y-340737D02*
Y-335737D01*
G01Y-336487D02*
X626387Y-336070D01*
X626803Y-335820D01*
X627470Y-335737D01*
X628053Y-335820D01*
X628637Y-336237D01*
X628887Y-336820D01*
X628970Y-337403D01*
X628887Y-337987D01*
X628637Y-338570D01*
X628137Y-338903D01*
X627470Y-339070D01*
X626887Y-338987D01*
X626303Y-338737D01*
X625970Y-338403D01*
G01X633070Y-339070D02*
Y-334070D01*
G01X637420Y-336820D02*
X640087D01*
X639837Y-336237D01*
X639420Y-335903D01*
X638837Y-335737D01*
X638253Y-335820D01*
X637753Y-336070D01*
X637420Y-336653D01*
X637253Y-337153D01*
Y-337653D01*
X637420Y-338153D01*
X637837Y-338653D01*
X638337Y-338987D01*
X638920Y-339070D01*
X639503Y-338903D01*
X640087Y-338403D01*
G01X645770Y-339070D02*
Y-335737D01*
G01Y-336320D02*
X645437Y-335987D01*
X644937Y-335820D01*
X644353Y-335737D01*
X643770Y-335903D01*
X643270Y-336237D01*
X642937Y-336737D01*
X642770Y-337403D01*
X642937Y-338070D01*
X643270Y-338570D01*
X643770Y-338903D01*
X644353Y-339070D01*
X644937Y-338987D01*
X645437Y-338737D01*
X645770Y-338403D01*
G01X648620Y-338487D02*
X649037Y-338820D01*
X649620Y-339070D01*
X650120D01*
X650620Y-338903D01*
X650953Y-338653D01*
X651120Y-338320D01*
X651037Y-337820D01*
X650703Y-337570D01*
X649203Y-337070D01*
X648870Y-336487D01*
X649037Y-336070D01*
X649370Y-335820D01*
X649870Y-335737D01*
X650370Y-335820D01*
X650870Y-336070D01*
G01X654220Y-336820D02*
X656887D01*
X656637Y-336237D01*
X656220Y-335903D01*
X655637Y-335737D01*
X655053Y-335820D01*
X654553Y-336070D01*
X654220Y-336653D01*
X654053Y-337153D01*
Y-337653D01*
X654220Y-338153D01*
X654637Y-338653D01*
X655137Y-338987D01*
X655720Y-339070D01*
X656303Y-338903D01*
X656887Y-338403D01*
G01X666670Y-335737D02*
Y-339070D01*
G01Y-334403D02*
X666503Y-334320D01*
Y-334153D01*
X666670Y-334070D01*
X666837Y-334153D01*
Y-334320D01*
X666670Y-334403D01*
G01X673770Y-340737D02*
Y-335737D01*
G01Y-336487D02*
X673353Y-336070D01*
X672853Y-335820D01*
X672270Y-335737D01*
X671770Y-335820D01*
X671187Y-336237D01*
X670853Y-336820D01*
X670770Y-337403D01*
X670853Y-337987D01*
X671187Y-338570D01*
X671770Y-338987D01*
X672270Y-339070D01*
X672853Y-338987D01*
X673353Y-338737D01*
X673770Y-338320D01*
G01X676453Y-339070D02*
Y-335737D01*
G01Y-336570D02*
X676787Y-336153D01*
X677287Y-335820D01*
X677953Y-335737D01*
X678537Y-335820D01*
X679037Y-336153D01*
X679287Y-336737D01*
Y-339070D01*
G01X683470D02*
X682970Y-338987D01*
X682470Y-338653D01*
X682137Y-338070D01*
X681970Y-337403D01*
X682137Y-336737D01*
X682470Y-336153D01*
X682970Y-335820D01*
X683470Y-335737D01*
X683970Y-335820D01*
X684470Y-336153D01*
X684803Y-336737D01*
X684887Y-337403D01*
X684803Y-338070D01*
X684470Y-338653D01*
X683970Y-338987D01*
X683470Y-339070D01*
G01X687903D02*
Y-335737D01*
G01Y-336403D02*
X688320Y-336070D01*
X688737Y-335820D01*
X689320Y-335737D01*
X689737Y-335820D01*
X690237Y-336070D01*
G01X693420Y-336820D02*
X696087D01*
X695837Y-336237D01*
X695420Y-335903D01*
X694837Y-335737D01*
X694253Y-335820D01*
X693753Y-336070D01*
X693420Y-336653D01*
X693253Y-337153D01*
Y-337653D01*
X693420Y-338153D01*
X693837Y-338653D01*
X694337Y-338987D01*
X694920Y-339070D01*
X695503Y-338903D01*
X696087Y-338403D01*
G01X705870Y-334070D02*
Y-339070D01*
G01X704703Y-335737D02*
X707037D01*
G01X710053Y-339070D02*
Y-334070D01*
G01Y-336487D02*
X710470Y-336070D01*
X710887Y-335820D01*
X711553Y-335737D01*
X712053Y-335820D01*
X712637Y-336153D01*
X712887Y-336653D01*
Y-339070D01*
G01X717070Y-335737D02*
Y-339070D01*
G01Y-334403D02*
X716903Y-334320D01*
Y-334153D01*
X717070Y-334070D01*
X717237Y-334153D01*
Y-334320D01*
X717070Y-334403D01*
G01X721420Y-338487D02*
X721837Y-338820D01*
X722420Y-339070D01*
X722920D01*
X723420Y-338903D01*
X723753Y-338653D01*
X723920Y-338320D01*
X723837Y-337820D01*
X723503Y-337570D01*
X722003Y-337070D01*
X721670Y-336487D01*
X721837Y-336070D01*
X722170Y-335820D01*
X722670Y-335737D01*
X723170Y-335820D01*
X723670Y-336070D01*
G01X732703Y-339070D02*
Y-335737D01*
G01Y-336403D02*
X733120Y-336070D01*
X733537Y-335820D01*
X734120Y-335737D01*
X734537Y-335820D01*
X735037Y-336070D01*
G01X738220Y-336820D02*
X740887D01*
X740637Y-336237D01*
X740220Y-335903D01*
X739637Y-335737D01*
X739053Y-335820D01*
X738553Y-336070D01*
X738220Y-336653D01*
X738053Y-337153D01*
Y-337653D01*
X738220Y-338153D01*
X738637Y-338653D01*
X739137Y-338987D01*
X739720Y-339070D01*
X740303Y-338903D01*
X740887Y-338403D01*
G01X746570Y-340737D02*
Y-335737D01*
G01Y-336487D02*
X746153Y-336070D01*
X745653Y-335820D01*
X745070Y-335737D01*
X744570Y-335820D01*
X743987Y-336237D01*
X743653Y-336820D01*
X743570Y-337403D01*
X743653Y-337987D01*
X743987Y-338570D01*
X744570Y-338987D01*
X745070Y-339070D01*
X745653Y-338987D01*
X746153Y-338737D01*
X746570Y-338320D01*
G01X749253Y-335737D02*
Y-338070D01*
X749587Y-338653D01*
X750087Y-338987D01*
X750670Y-339070D01*
X751253Y-338987D01*
X751753Y-338653D01*
X752087Y-338070D01*
G01Y-339070D02*
Y-335737D01*
G01X755020Y-336820D02*
X757687D01*
X757437Y-336237D01*
X757020Y-335903D01*
X756437Y-335737D01*
X755853Y-335820D01*
X755353Y-336070D01*
X755020Y-336653D01*
X754853Y-337153D01*
Y-337653D01*
X755020Y-338153D01*
X755437Y-338653D01*
X755937Y-338987D01*
X756520Y-339070D01*
X757103Y-338903D01*
X757687Y-338403D01*
G01X760620Y-338487D02*
X761037Y-338820D01*
X761620Y-339070D01*
X762120D01*
X762620Y-338903D01*
X762953Y-338653D01*
X763120Y-338320D01*
X763037Y-337820D01*
X762703Y-337570D01*
X761203Y-337070D01*
X760870Y-336487D01*
X761037Y-336070D01*
X761370Y-335820D01*
X761870Y-335737D01*
X762370Y-335820D01*
X762870Y-336070D01*
G01X767470Y-334070D02*
Y-339070D01*
G01X766303Y-335737D02*
X768637D01*
G01X773070Y-339237D02*
X772903Y-339153D01*
Y-338987D01*
X773070Y-338903D01*
X773237Y-338987D01*
Y-339153D01*
X773070Y-339237D01*
G01X319083Y-168300D02*
Y-173300D01*
X322417D01*
G01X325100Y-169967D02*
X327600Y-173300D01*
G01Y-169967D02*
X325100Y-173300D01*
G01X331950Y-173467D02*
X331783Y-173383D01*
Y-173217D01*
X331950Y-173133D01*
X332117Y-173217D01*
Y-173383D01*
X331950Y-173467D01*
G01Y-171217D02*
X331783Y-171133D01*
Y-170967D01*
X331950Y-170883D01*
X332117Y-170967D01*
Y-171133D01*
X331950Y-171217D01*
G01X340650Y-173300D02*
Y-169967D01*
G01Y-170883D02*
X340900Y-170467D01*
X341317Y-170133D01*
X341900Y-169967D01*
X342483Y-170133D01*
X342900Y-170467D01*
X343150Y-170883D01*
Y-173300D01*
G01Y-170883D02*
X343400Y-170467D01*
X343817Y-170133D01*
X344400Y-169967D01*
X344983Y-170133D01*
X345400Y-170467D01*
X345650Y-170967D01*
Y-173300D01*
G01X347333Y-169967D02*
Y-172300D01*
X347667Y-172883D01*
X348167Y-173217D01*
X348750Y-173300D01*
X349333Y-173217D01*
X349833Y-172883D01*
X350167Y-172300D01*
G01Y-173300D02*
Y-169967D01*
G01X353100Y-172717D02*
X353517Y-173050D01*
X354100Y-173300D01*
X354600D01*
X355100Y-173133D01*
X355433Y-172883D01*
X355600Y-172550D01*
X355517Y-172050D01*
X355183Y-171800D01*
X353683Y-171300D01*
X353350Y-170717D01*
X353517Y-170300D01*
X353850Y-170050D01*
X354350Y-169967D01*
X354850Y-170050D01*
X355350Y-170300D01*
G01X359950Y-168300D02*
Y-173300D01*
G01X358783Y-169967D02*
X361117D01*
G01X369650Y-173300D02*
Y-168300D01*
G01Y-170800D02*
X370067Y-170300D01*
X370567Y-170050D01*
X371067Y-169967D01*
X371817Y-170133D01*
X372317Y-170467D01*
X372650Y-171050D01*
Y-171717D01*
X372483Y-172383D01*
X372150Y-172883D01*
X371567Y-173217D01*
X371067Y-173300D01*
X370567Y-173217D01*
X370067Y-172967D01*
X369650Y-172550D01*
G01X375500Y-171050D02*
X378167D01*
X377917Y-170467D01*
X377500Y-170133D01*
X376917Y-169967D01*
X376333Y-170050D01*
X375833Y-170300D01*
X375500Y-170883D01*
X375333Y-171383D01*
Y-171883D01*
X375500Y-172383D01*
X375917Y-172883D01*
X376417Y-173217D01*
X377000Y-173300D01*
X377583Y-173133D01*
X378167Y-172633D01*
G01X386450Y-173300D02*
Y-168300D01*
G01Y-170800D02*
X386867Y-170300D01*
X387367Y-170050D01*
X387867Y-169967D01*
X388617Y-170133D01*
X389117Y-170467D01*
X389450Y-171050D01*
Y-171717D01*
X389283Y-172383D01*
X388950Y-172883D01*
X388367Y-173217D01*
X387867Y-173300D01*
X387367Y-173217D01*
X386867Y-172967D01*
X386450Y-172550D01*
G01X392383Y-173300D02*
Y-169967D01*
G01Y-170633D02*
X392800Y-170300D01*
X393217Y-170050D01*
X393800Y-169967D01*
X394217Y-170050D01*
X394717Y-170300D01*
G01X399150Y-173300D02*
X398650Y-173217D01*
X398150Y-172883D01*
X397817Y-172300D01*
X397650Y-171633D01*
X397817Y-170967D01*
X398150Y-170383D01*
X398650Y-170050D01*
X399150Y-169967D01*
X399650Y-170050D01*
X400150Y-170383D01*
X400483Y-170967D01*
X400567Y-171633D01*
X400483Y-172300D01*
X400150Y-172883D01*
X399650Y-173217D01*
X399150Y-173300D01*
G01X403333D02*
Y-168300D01*
G01X406000Y-169967D02*
X403333Y-171883D01*
G01X404417Y-171133D02*
X406167Y-173300D01*
G01X409100Y-171050D02*
X411767D01*
X411517Y-170467D01*
X411100Y-170133D01*
X410517Y-169967D01*
X409933Y-170050D01*
X409433Y-170300D01*
X409100Y-170883D01*
X408933Y-171383D01*
Y-171883D01*
X409100Y-172383D01*
X409517Y-172883D01*
X410017Y-173217D01*
X410600Y-173300D01*
X411183Y-173133D01*
X411767Y-172633D01*
G01X414533Y-173300D02*
Y-169967D01*
G01Y-170800D02*
X414867Y-170383D01*
X415367Y-170050D01*
X416033Y-169967D01*
X416617Y-170050D01*
X417117Y-170383D01*
X417367Y-170967D01*
Y-173300D01*
G01X427150D02*
Y-168300D01*
G01X434250Y-173300D02*
Y-169967D01*
G01Y-170550D02*
X433917Y-170217D01*
X433417Y-170050D01*
X432833Y-169967D01*
X432250Y-170133D01*
X431750Y-170467D01*
X431417Y-170967D01*
X431250Y-171633D01*
X431417Y-172300D01*
X431750Y-172800D01*
X432250Y-173133D01*
X432833Y-173300D01*
X433417Y-173217D01*
X433917Y-172967D01*
X434250Y-172633D01*
G01X436600Y-174800D02*
X437100Y-174967D01*
X437767Y-174800D01*
X438183Y-174467D01*
X438517Y-174050D01*
X439017Y-172717D01*
X440100Y-169967D01*
G01X437433D02*
X439017Y-172717D01*
G01X442700Y-171050D02*
X445367D01*
X445117Y-170467D01*
X444700Y-170133D01*
X444117Y-169967D01*
X443533Y-170050D01*
X443033Y-170300D01*
X442700Y-170883D01*
X442533Y-171383D01*
Y-171883D01*
X442700Y-172383D01*
X443117Y-172883D01*
X443617Y-173217D01*
X444200Y-173300D01*
X444783Y-173133D01*
X445367Y-172633D01*
G01X448383Y-173300D02*
Y-169967D01*
G01Y-170633D02*
X448800Y-170300D01*
X449217Y-170050D01*
X449800Y-169967D01*
X450217Y-170050D01*
X450717Y-170300D01*
G01X318667Y-150000D02*
Y-145000D01*
X320333D01*
X321000Y-145250D01*
X321500Y-145583D01*
X321917Y-146083D01*
X322250Y-146667D01*
X322333Y-147500D01*
X322250Y-148333D01*
X321917Y-148917D01*
X321500Y-149417D01*
X321000Y-149750D01*
X320333Y-150000D01*
X318667D01*
G01X324933D02*
Y-146667D01*
G01Y-147333D02*
X325350Y-147000D01*
X325767Y-146750D01*
X326350Y-146667D01*
X326767Y-146750D01*
X327267Y-147000D01*
G01X331700Y-146667D02*
Y-150000D01*
G01Y-145333D02*
X331533Y-145250D01*
Y-145083D01*
X331700Y-145000D01*
X331867Y-145083D01*
Y-145250D01*
X331700Y-145333D01*
G01X337300Y-150000D02*
Y-145000D01*
G01X342900Y-150000D02*
Y-145000D01*
G01X352517Y-150000D02*
Y-145000D01*
X355683D01*
G01X354517Y-147417D02*
X352517D01*
G01X358533Y-150000D02*
Y-146667D01*
G01Y-147333D02*
X358950Y-147000D01*
X359367Y-146750D01*
X359950Y-146667D01*
X360367Y-146750D01*
X360867Y-147000D01*
G01X365300Y-150000D02*
X364800Y-149917D01*
X364300Y-149583D01*
X363967Y-149000D01*
X363800Y-148333D01*
X363967Y-147667D01*
X364300Y-147083D01*
X364800Y-146750D01*
X365300Y-146667D01*
X365800Y-146750D01*
X366300Y-147083D01*
X366633Y-147667D01*
X366717Y-148333D01*
X366633Y-149000D01*
X366300Y-149583D01*
X365800Y-149917D01*
X365300Y-150000D01*
G01X368400D02*
Y-146667D01*
G01Y-147583D02*
X368650Y-147167D01*
X369067Y-146833D01*
X369650Y-146667D01*
X370233Y-146833D01*
X370650Y-147167D01*
X370900Y-147583D01*
Y-150000D01*
G01Y-147583D02*
X371150Y-147167D01*
X371567Y-146833D01*
X372150Y-146667D01*
X372733Y-146833D01*
X373150Y-147167D01*
X373400Y-147667D01*
Y-150000D01*
G01X380433Y-145000D02*
Y-150000D01*
X383767D01*
G01X387700D02*
Y-145000D01*
X386700Y-146000D01*
G01Y-150000D02*
X388700D01*
G01X398483Y-151667D02*
X397650Y-150833D01*
X397233Y-150000D01*
Y-146667D01*
X397650Y-145833D01*
X398483Y-145000D01*
G01X404500D02*
Y-150000D01*
G01X402583Y-145000D02*
X406417D01*
G01X410100Y-150000D02*
X409433Y-149917D01*
X408850Y-149583D01*
X408350Y-149083D01*
X408017Y-148500D01*
X407850Y-147833D01*
Y-147167D01*
X408017Y-146500D01*
X408350Y-145917D01*
X408850Y-145417D01*
X409433Y-145083D01*
X410100Y-145000D01*
X410767Y-145083D01*
X411350Y-145417D01*
X411850Y-145917D01*
X412183Y-146500D01*
X412350Y-147167D01*
Y-147833D01*
X412183Y-148500D01*
X411850Y-149083D01*
X411350Y-149583D01*
X410767Y-149917D01*
X410100Y-150000D01*
G01X414033D02*
Y-145000D01*
X416033D01*
X416700Y-145250D01*
X417200Y-145833D01*
X417367Y-146500D01*
X417200Y-147167D01*
X416783Y-147667D01*
X416033Y-147917D01*
X414033D01*
G01X421717Y-151667D02*
X422550Y-150833D01*
X422967Y-150000D01*
Y-146667D01*
X422550Y-145833D01*
X421717Y-145000D01*
G01X432500D02*
Y-150000D01*
G01X431333Y-146667D02*
X433667D01*
G01X438100Y-150000D02*
X437600Y-149917D01*
X437100Y-149583D01*
X436767Y-149000D01*
X436600Y-148333D01*
X436767Y-147667D01*
X437100Y-147083D01*
X437600Y-146750D01*
X438100Y-146667D01*
X438600Y-146750D01*
X439100Y-147083D01*
X439433Y-147667D01*
X439517Y-148333D01*
X439433Y-149000D01*
X439100Y-149583D01*
X438600Y-149917D01*
X438100Y-150000D01*
G01X447633Y-145000D02*
Y-150000D01*
X450967D01*
G01X453650Y-146667D02*
X456150Y-150000D01*
G01Y-146667D02*
X453650Y-150000D01*
G01X318483Y-156690D02*
Y-161690D01*
X321817D01*
G01X324333D02*
Y-158357D01*
G01Y-159190D02*
X324667Y-158773D01*
X325167Y-158440D01*
X325833Y-158357D01*
X326417Y-158440D01*
X326917Y-158773D01*
X327167Y-159357D01*
Y-161690D01*
G01X331350Y-161857D02*
X331183Y-161773D01*
Y-161607D01*
X331350Y-161523D01*
X331517Y-161607D01*
Y-161773D01*
X331350Y-161857D01*
G01Y-159607D02*
X331183Y-159523D01*
Y-159357D01*
X331350Y-159273D01*
X331517Y-159357D01*
Y-159523D01*
X331350Y-159607D01*
G01X343883Y-158773D02*
X343300Y-158440D01*
X342800Y-158357D01*
X342133Y-158523D01*
X341633Y-158857D01*
X341300Y-159440D01*
X341217Y-160023D01*
X341300Y-160607D01*
X341633Y-161107D01*
X342133Y-161523D01*
X342800Y-161690D01*
X343383Y-161523D01*
X343883Y-161190D01*
G01X349650Y-161690D02*
Y-158357D01*
G01Y-158940D02*
X349317Y-158607D01*
X348817Y-158440D01*
X348233Y-158357D01*
X347650Y-158523D01*
X347150Y-158857D01*
X346817Y-159357D01*
X346650Y-160023D01*
X346817Y-160690D01*
X347150Y-161190D01*
X347650Y-161523D01*
X348233Y-161690D01*
X348817Y-161607D01*
X349317Y-161357D01*
X349650Y-161023D01*
G01X352333Y-161690D02*
Y-158357D01*
G01Y-159190D02*
X352667Y-158773D01*
X353167Y-158440D01*
X353833Y-158357D01*
X354417Y-158440D01*
X354917Y-158773D01*
X355167Y-159357D01*
Y-161690D01*
G01X359350Y-158357D02*
X360183Y-157315D01*
Y-156690D01*
X359558D01*
Y-157315D01*
X360183D01*
G01X364950Y-156690D02*
Y-161690D01*
G01X363783Y-158357D02*
X366117D01*
G01X374650Y-161690D02*
Y-156690D01*
G01Y-159190D02*
X375067Y-158690D01*
X375567Y-158440D01*
X376067Y-158357D01*
X376817Y-158523D01*
X377317Y-158857D01*
X377650Y-159440D01*
Y-160107D01*
X377483Y-160773D01*
X377150Y-161273D01*
X376567Y-161607D01*
X376067Y-161690D01*
X375567Y-161607D01*
X375067Y-161357D01*
X374650Y-160940D01*
G01X380500Y-159440D02*
X383167D01*
X382917Y-158857D01*
X382500Y-158523D01*
X381917Y-158357D01*
X381333Y-158440D01*
X380833Y-158690D01*
X380500Y-159273D01*
X380333Y-159773D01*
Y-160273D01*
X380500Y-160773D01*
X380917Y-161273D01*
X381417Y-161607D01*
X382000Y-161690D01*
X382583Y-161523D01*
X383167Y-161023D01*
G01X391450Y-161690D02*
Y-156690D01*
G01Y-159190D02*
X391867Y-158690D01*
X392367Y-158440D01*
X392867Y-158357D01*
X393617Y-158523D01*
X394117Y-158857D01*
X394450Y-159440D01*
Y-160107D01*
X394283Y-160773D01*
X393950Y-161273D01*
X393367Y-161607D01*
X392867Y-161690D01*
X392367Y-161607D01*
X391867Y-161357D01*
X391450Y-160940D01*
G01X397383Y-161690D02*
Y-158357D01*
G01Y-159023D02*
X397800Y-158690D01*
X398217Y-158440D01*
X398800Y-158357D01*
X399217Y-158440D01*
X399717Y-158690D01*
G01X404150Y-161690D02*
X403650Y-161607D01*
X403150Y-161273D01*
X402817Y-160690D01*
X402650Y-160023D01*
X402817Y-159357D01*
X403150Y-158773D01*
X403650Y-158440D01*
X404150Y-158357D01*
X404650Y-158440D01*
X405150Y-158773D01*
X405483Y-159357D01*
X405567Y-160023D01*
X405483Y-160690D01*
X405150Y-161273D01*
X404650Y-161607D01*
X404150Y-161690D01*
G01X408333D02*
Y-156690D01*
G01X411000Y-158357D02*
X408333Y-160273D01*
G01X409417Y-159523D02*
X411167Y-161690D01*
G01X414100Y-159440D02*
X416767D01*
X416517Y-158857D01*
X416100Y-158523D01*
X415517Y-158357D01*
X414933Y-158440D01*
X414433Y-158690D01*
X414100Y-159273D01*
X413933Y-159773D01*
Y-160273D01*
X414100Y-160773D01*
X414517Y-161273D01*
X415017Y-161607D01*
X415600Y-161690D01*
X416183Y-161523D01*
X416767Y-161023D01*
G01X419533Y-161690D02*
Y-158357D01*
G01Y-159190D02*
X419867Y-158773D01*
X420367Y-158440D01*
X421033Y-158357D01*
X421617Y-158440D01*
X422117Y-158773D01*
X422367Y-159357D01*
Y-161690D01*
G01X432150D02*
Y-156690D01*
G01X439250Y-161690D02*
Y-158357D01*
G01Y-158940D02*
X438917Y-158607D01*
X438417Y-158440D01*
X437833Y-158357D01*
X437250Y-158523D01*
X436750Y-158857D01*
X436417Y-159357D01*
X436250Y-160023D01*
X436417Y-160690D01*
X436750Y-161190D01*
X437250Y-161523D01*
X437833Y-161690D01*
X438417Y-161607D01*
X438917Y-161357D01*
X439250Y-161023D01*
G01X441600Y-163190D02*
X442100Y-163357D01*
X442767Y-163190D01*
X443183Y-162857D01*
X443517Y-162440D01*
X444017Y-161107D01*
X445100Y-158357D01*
G01X442433D02*
X444017Y-161107D01*
G01X447700Y-159440D02*
X450367D01*
X450117Y-158857D01*
X449700Y-158523D01*
X449117Y-158357D01*
X448533Y-158440D01*
X448033Y-158690D01*
X447700Y-159273D01*
X447533Y-159773D01*
Y-160273D01*
X447700Y-160773D01*
X448117Y-161273D01*
X448617Y-161607D01*
X449200Y-161690D01*
X449783Y-161523D01*
X450367Y-161023D01*
G01X453383Y-161690D02*
Y-158357D01*
G01Y-159023D02*
X453800Y-158690D01*
X454217Y-158440D01*
X454800Y-158357D01*
X455217Y-158440D01*
X455717Y-158690D01*
G01X336000Y401500D02*
Y396500D01*
G01X334833Y399833D02*
X337167D01*
G01X340183Y396500D02*
Y401500D01*
G01Y399083D02*
X340600Y399500D01*
X341017Y399750D01*
X341683Y399833D01*
X342183Y399750D01*
X342767Y399417D01*
X343017Y398917D01*
Y396500D01*
G01X347200Y399833D02*
Y396500D01*
G01Y401167D02*
X347033Y401250D01*
Y401417D01*
X347200Y401500D01*
X347367Y401417D01*
Y401250D01*
X347200Y401167D01*
G01X354133Y399417D02*
X353550Y399750D01*
X353050Y399833D01*
X352383Y399667D01*
X351883Y399333D01*
X351550Y398750D01*
X351467Y398167D01*
X351550Y397583D01*
X351883Y397083D01*
X352383Y396667D01*
X353050Y396500D01*
X353633Y396667D01*
X354133Y397000D01*
G01X356983Y396500D02*
Y401500D01*
G01X359650Y399833D02*
X356983Y397917D01*
G01X358067Y398667D02*
X359817Y396500D01*
G01X362583D02*
Y399833D01*
G01Y399000D02*
X362917Y399417D01*
X363417Y399750D01*
X364083Y399833D01*
X364667Y399750D01*
X365167Y399417D01*
X365417Y398833D01*
Y396500D01*
G01X368350Y398750D02*
X371017D01*
X370767Y399333D01*
X370350Y399667D01*
X369767Y399833D01*
X369183Y399750D01*
X368683Y399500D01*
X368350Y398917D01*
X368183Y398417D01*
Y397917D01*
X368350Y397417D01*
X368767Y396917D01*
X369267Y396583D01*
X369850Y396500D01*
X370433Y396667D01*
X371017Y397167D01*
G01X373950Y397083D02*
X374367Y396750D01*
X374950Y396500D01*
X375450D01*
X375950Y396667D01*
X376283Y396917D01*
X376450Y397250D01*
X376367Y397750D01*
X376033Y398000D01*
X374533Y398500D01*
X374200Y399083D01*
X374367Y399500D01*
X374700Y399750D01*
X375200Y399833D01*
X375700Y399750D01*
X376200Y399500D01*
G01X379550Y397083D02*
X379967Y396750D01*
X380550Y396500D01*
X381050D01*
X381550Y396667D01*
X381883Y396917D01*
X382050Y397250D01*
X381967Y397750D01*
X381633Y398000D01*
X380133Y398500D01*
X379800Y399083D01*
X379967Y399500D01*
X380300Y399750D01*
X380800Y399833D01*
X381300Y399750D01*
X381800Y399500D01*
G01X329500Y577610D02*
Y509110D01*
G01Y532500D02*
X884500D01*
G01X343667Y-288500D02*
Y-283500D01*
X345333D01*
X346000Y-283750D01*
X346500Y-284083D01*
X346917Y-284583D01*
X347250Y-285167D01*
X347333Y-286000D01*
X347250Y-286833D01*
X346917Y-287417D01*
X346500Y-287917D01*
X346000Y-288250D01*
X345333Y-288500D01*
X343667D01*
G01X351100D02*
Y-283500D01*
X350100Y-284500D01*
G01Y-288500D02*
X352100D01*
G01X355117Y-286417D02*
X355700Y-285833D01*
X356200Y-285500D01*
X356867Y-285333D01*
X357450Y-285500D01*
X357867Y-285833D01*
X358200Y-286333D01*
X358283Y-286917D01*
X358200Y-287417D01*
X357867Y-287917D01*
X357367Y-288333D01*
X356783Y-288500D01*
X356117Y-288333D01*
X355533Y-287833D01*
X355200Y-287083D01*
X355117Y-286250D01*
X355283Y-285167D01*
X355533Y-284583D01*
X355950Y-284000D01*
X356533Y-283583D01*
X357117Y-283500D01*
X357700Y-283667D01*
X358117Y-284083D01*
G01X350500Y413500D02*
Y418500D01*
G01Y416000D02*
X350917Y416500D01*
X351417Y416750D01*
X351917Y416833D01*
X352667Y416667D01*
X353167Y416333D01*
X353500Y415750D01*
Y415083D01*
X353333Y414417D01*
X353000Y413917D01*
X352417Y413583D01*
X351917Y413500D01*
X351417Y413583D01*
X350917Y413833D01*
X350500Y414250D01*
G01X357600Y413500D02*
X357100Y413583D01*
X356600Y413917D01*
X356267Y414500D01*
X356100Y415167D01*
X356267Y415833D01*
X356600Y416417D01*
X357100Y416750D01*
X357600Y416833D01*
X358100Y416750D01*
X358600Y416417D01*
X358933Y415833D01*
X359017Y415167D01*
X358933Y414500D01*
X358600Y413917D01*
X358100Y413583D01*
X357600Y413500D01*
G01X364700D02*
Y416833D01*
G01Y416250D02*
X364367Y416583D01*
X363867Y416750D01*
X363283Y416833D01*
X362700Y416667D01*
X362200Y416333D01*
X361867Y415833D01*
X361700Y415167D01*
X361867Y414500D01*
X362200Y414000D01*
X362700Y413667D01*
X363283Y413500D01*
X363867Y413583D01*
X364367Y413833D01*
X364700Y414167D01*
G01X367633Y413500D02*
Y416833D01*
G01Y416167D02*
X368050Y416500D01*
X368467Y416750D01*
X369050Y416833D01*
X369467Y416750D01*
X369967Y416500D01*
G01X375900Y418500D02*
Y413500D01*
G01Y414250D02*
X375567Y413833D01*
X375067Y413583D01*
X374483Y413500D01*
X373817Y413667D01*
X373317Y414083D01*
X372983Y414583D01*
X372900Y415167D01*
X372983Y415750D01*
X373317Y416250D01*
X373817Y416667D01*
X374483Y416833D01*
X375067Y416750D01*
X375483Y416583D01*
X375900Y416250D01*
G01X340000Y522500D02*
Y517500D01*
G01X338083Y522500D02*
X341917D01*
G01X343517Y520833D02*
X344517Y517500D01*
X345600Y520833D01*
X346683Y517500D01*
X347683Y520833D01*
G01X351200D02*
Y517500D01*
G01Y522167D02*
X351033Y522250D01*
Y522417D01*
X351200Y522500D01*
X351367Y522417D01*
Y522250D01*
X351200Y522167D01*
G01X355550Y518083D02*
X355967Y517750D01*
X356550Y517500D01*
X357050D01*
X357550Y517667D01*
X357883Y517917D01*
X358050Y518250D01*
X357967Y518750D01*
X357633Y519000D01*
X356133Y519500D01*
X355800Y520083D01*
X355967Y520500D01*
X356300Y520750D01*
X356800Y520833D01*
X357300Y520750D01*
X357800Y520500D01*
G01X362400Y522500D02*
Y517500D01*
G01X361233Y520833D02*
X363567D01*
G01X375100Y517500D02*
Y520833D01*
G01Y520250D02*
X374767Y520583D01*
X374267Y520750D01*
X373683Y520833D01*
X373100Y520667D01*
X372600Y520333D01*
X372267Y519833D01*
X372100Y519167D01*
X372267Y518500D01*
X372600Y518000D01*
X373100Y517667D01*
X373683Y517500D01*
X374267Y517583D01*
X374767Y517833D01*
X375100Y518167D01*
G01X377783Y517500D02*
Y520833D01*
G01Y520000D02*
X378117Y520417D01*
X378617Y520750D01*
X379283Y520833D01*
X379867Y520750D01*
X380367Y520417D01*
X380617Y519833D01*
Y517500D01*
G01X386300Y522500D02*
Y517500D01*
G01Y518250D02*
X385967Y517833D01*
X385467Y517583D01*
X384883Y517500D01*
X384217Y517667D01*
X383717Y518083D01*
X383383Y518583D01*
X383300Y519167D01*
X383383Y519750D01*
X383717Y520250D01*
X384217Y520667D01*
X384883Y520833D01*
X385467Y520750D01*
X385883Y520583D01*
X386300Y520250D01*
G01X394500Y517500D02*
Y522500D01*
G01Y520000D02*
X394917Y520500D01*
X395417Y520750D01*
X395917Y520833D01*
X396667Y520667D01*
X397167Y520333D01*
X397500Y519750D01*
Y519083D01*
X397333Y518417D01*
X397000Y517917D01*
X396417Y517583D01*
X395917Y517500D01*
X395417Y517583D01*
X394917Y517833D01*
X394500Y518250D01*
G01X401600Y517500D02*
X401100Y517583D01*
X400600Y517917D01*
X400267Y518500D01*
X400100Y519167D01*
X400267Y519833D01*
X400600Y520417D01*
X401100Y520750D01*
X401600Y520833D01*
X402100Y520750D01*
X402600Y520417D01*
X402933Y519833D01*
X403017Y519167D01*
X402933Y518500D01*
X402600Y517917D01*
X402100Y517583D01*
X401600Y517500D01*
G01X405117Y520833D02*
X406117Y517500D01*
X407200Y520833D01*
X408283Y517500D01*
X409283Y520833D01*
G01X338333Y553500D02*
Y558500D01*
X340417D01*
X341083Y558250D01*
X341500Y557917D01*
X341667Y557250D01*
X341500Y556583D01*
X341000Y556167D01*
X340417Y555917D01*
X338333D01*
G01X340417D02*
X341667Y553500D01*
G01X345600D02*
X345100Y553583D01*
X344600Y553917D01*
X344267Y554500D01*
X344100Y555167D01*
X344267Y555833D01*
X344600Y556417D01*
X345100Y556750D01*
X345600Y556833D01*
X346100Y556750D01*
X346600Y556417D01*
X346933Y555833D01*
X347017Y555167D01*
X346933Y554500D01*
X346600Y553917D01*
X346100Y553583D01*
X345600Y553500D01*
G01X349783Y556833D02*
Y554500D01*
X350117Y553917D01*
X350617Y553583D01*
X351200Y553500D01*
X351783Y553583D01*
X352283Y553917D01*
X352617Y554500D01*
G01Y553500D02*
Y556833D01*
G01X356800Y558500D02*
Y553500D01*
G01X355633Y556833D02*
X357967D01*
G01X362400D02*
Y553500D01*
G01Y558167D02*
X362233Y558250D01*
Y558417D01*
X362400Y558500D01*
X362567Y558417D01*
Y558250D01*
X362400Y558167D01*
G01X366583Y553500D02*
Y556833D01*
G01Y556000D02*
X366917Y556417D01*
X367417Y556750D01*
X368083Y556833D01*
X368667Y556750D01*
X369167Y556417D01*
X369417Y555833D01*
Y553500D01*
G01X372433Y552250D02*
X373017Y551917D01*
X373683Y551833D01*
X374267Y551917D01*
X374767Y552333D01*
X375100Y552917D01*
Y556833D01*
G01Y556167D02*
X374767Y556500D01*
X374267Y556750D01*
X373683Y556833D01*
X373017Y556667D01*
X372600Y556333D01*
X372267Y555750D01*
X372100Y555167D01*
X372183Y554667D01*
X372517Y554083D01*
X373017Y553667D01*
X373683Y553500D01*
X374183Y553583D01*
X374767Y553917D01*
X375100Y554250D01*
G01X384800Y558500D02*
Y553500D01*
G01X383633Y556833D02*
X385967D01*
G01X390400Y553500D02*
X389900Y553583D01*
X389400Y553917D01*
X389067Y554500D01*
X388900Y555167D01*
X389067Y555833D01*
X389400Y556417D01*
X389900Y556750D01*
X390400Y556833D01*
X390900Y556750D01*
X391400Y556417D01*
X391733Y555833D01*
X391817Y555167D01*
X391733Y554500D01*
X391400Y553917D01*
X390900Y553583D01*
X390400Y553500D01*
G01X396000D02*
Y558500D01*
G01X400350Y555750D02*
X403017D01*
X402767Y556333D01*
X402350Y556667D01*
X401767Y556833D01*
X401183Y556750D01*
X400683Y556500D01*
X400350Y555917D01*
X400183Y555417D01*
Y554917D01*
X400350Y554417D01*
X400767Y553917D01*
X401267Y553583D01*
X401850Y553500D01*
X402433Y553667D01*
X403017Y554167D01*
G01X406033Y553500D02*
Y556833D01*
G01Y556167D02*
X406450Y556500D01*
X406867Y556750D01*
X407450Y556833D01*
X407867Y556750D01*
X408367Y556500D01*
G01X414300Y553500D02*
Y556833D01*
G01Y556250D02*
X413967Y556583D01*
X413467Y556750D01*
X412883Y556833D01*
X412300Y556667D01*
X411800Y556333D01*
X411467Y555833D01*
X411300Y555167D01*
X411467Y554500D01*
X411800Y554000D01*
X412300Y553667D01*
X412883Y553500D01*
X413467Y553583D01*
X413967Y553833D01*
X414300Y554167D01*
G01X416983Y553500D02*
Y556833D01*
G01Y556000D02*
X417317Y556417D01*
X417817Y556750D01*
X418483Y556833D01*
X419067Y556750D01*
X419567Y556417D01*
X419817Y555833D01*
Y553500D01*
G01X425333Y556417D02*
X424750Y556750D01*
X424250Y556833D01*
X423583Y556667D01*
X423083Y556333D01*
X422750Y555750D01*
X422667Y555167D01*
X422750Y554583D01*
X423083Y554083D01*
X423583Y553667D01*
X424250Y553500D01*
X424833Y553667D01*
X425333Y554000D01*
G01X428350Y555750D02*
X431017D01*
X430767Y556333D01*
X430350Y556667D01*
X429767Y556833D01*
X429183Y556750D01*
X428683Y556500D01*
X428350Y555917D01*
X428183Y555417D01*
Y554917D01*
X428350Y554417D01*
X428767Y553917D01*
X429267Y553583D01*
X429850Y553500D01*
X430433Y553667D01*
X431017Y554167D01*
G01X369167Y-122500D02*
Y-117500D01*
X370833D01*
X371500Y-117750D01*
X372000Y-118083D01*
X372417Y-118583D01*
X372750Y-119167D01*
X372833Y-120000D01*
X372750Y-120833D01*
X372417Y-121417D01*
X372000Y-121917D01*
X371500Y-122250D01*
X370833Y-122500D01*
X369167D01*
G01X376600D02*
Y-117500D01*
X375600Y-118500D01*
G01Y-122500D02*
X377600D01*
G01X367167Y41500D02*
Y46500D01*
X368833D01*
X369500Y46250D01*
X370000Y45917D01*
X370417Y45417D01*
X370750Y44833D01*
X370833Y44000D01*
X370750Y43167D01*
X370417Y42583D01*
X370000Y42083D01*
X369500Y41750D01*
X368833Y41500D01*
X367167D01*
G01X373017Y45667D02*
X373517Y46167D01*
X374100Y46417D01*
X374767Y46500D01*
X375600Y46333D01*
X376183Y45917D01*
X376350Y45417D01*
X376267Y44917D01*
X375933Y44500D01*
X374267Y43667D01*
X373517Y43083D01*
X373017Y42250D01*
X372850Y41500D01*
X376350D01*
G01X353500Y331500D02*
Y93000D01*
G01X363090Y103450D02*
Y106783D01*
G01Y106200D02*
X362757Y106533D01*
X362257Y106700D01*
X361673Y106783D01*
X361090Y106617D01*
X360590Y106283D01*
X360257Y105783D01*
X360090Y105117D01*
X360257Y104450D01*
X360590Y103950D01*
X361090Y103617D01*
X361673Y103450D01*
X362257Y103533D01*
X362757Y103783D01*
X363090Y104117D01*
G01X365773Y103450D02*
Y106783D01*
G01Y105950D02*
X366107Y106367D01*
X366607Y106700D01*
X367273Y106783D01*
X367857Y106700D01*
X368357Y106367D01*
X368607Y105783D01*
Y103450D01*
G01X374290Y108450D02*
Y103450D01*
G01Y104200D02*
X373957Y103783D01*
X373457Y103533D01*
X372873Y103450D01*
X372207Y103617D01*
X371707Y104033D01*
X371373Y104533D01*
X371290Y105117D01*
X371373Y105700D01*
X371707Y106200D01*
X372207Y106617D01*
X372873Y106783D01*
X373457Y106700D01*
X373873Y106533D01*
X374290Y106200D01*
G01X385323Y106367D02*
X384740Y106700D01*
X384240Y106783D01*
X383573Y106617D01*
X383073Y106283D01*
X382740Y105700D01*
X382657Y105117D01*
X382740Y104533D01*
X383073Y104033D01*
X383573Y103617D01*
X384240Y103450D01*
X384823Y103617D01*
X385323Y103950D01*
G01X389590Y103450D02*
X389090Y103533D01*
X388590Y103867D01*
X388257Y104450D01*
X388090Y105117D01*
X388257Y105783D01*
X388590Y106367D01*
X389090Y106700D01*
X389590Y106783D01*
X390090Y106700D01*
X390590Y106367D01*
X390923Y105783D01*
X391007Y105117D01*
X390923Y104450D01*
X390590Y103867D01*
X390090Y103533D01*
X389590Y103450D01*
G01X393690Y106783D02*
X395190Y103450D01*
X396690Y106783D01*
G01X399540Y105700D02*
X402207D01*
X401957Y106283D01*
X401540Y106617D01*
X400957Y106783D01*
X400373Y106700D01*
X399873Y106450D01*
X399540Y105867D01*
X399373Y105367D01*
Y104867D01*
X399540Y104367D01*
X399957Y103867D01*
X400457Y103533D01*
X401040Y103450D01*
X401623Y103617D01*
X402207Y104117D01*
G01X405223Y103450D02*
Y106783D01*
G01Y106117D02*
X405640Y106450D01*
X406057Y106700D01*
X406640Y106783D01*
X407057Y106700D01*
X407557Y106450D01*
G01X410740Y105700D02*
X413407D01*
X413157Y106283D01*
X412740Y106617D01*
X412157Y106783D01*
X411573Y106700D01*
X411073Y106450D01*
X410740Y105867D01*
X410573Y105367D01*
Y104867D01*
X410740Y104367D01*
X411157Y103867D01*
X411657Y103533D01*
X412240Y103450D01*
X412823Y103617D01*
X413407Y104117D01*
G01X419090Y108450D02*
Y103450D01*
G01Y104200D02*
X418757Y103783D01*
X418257Y103533D01*
X417673Y103450D01*
X417007Y103617D01*
X416507Y104033D01*
X416173Y104533D01*
X416090Y105117D01*
X416173Y105700D01*
X416507Y106200D01*
X417007Y106617D01*
X417673Y106783D01*
X418257Y106700D01*
X418673Y106533D01*
X419090Y106200D01*
G01X426707Y106783D02*
X427707Y103450D01*
X428790Y106783D01*
X429873Y103450D01*
X430873Y106783D01*
G01X434390D02*
Y103450D01*
G01Y108117D02*
X434223Y108200D01*
Y108367D01*
X434390Y108450D01*
X434557Y108367D01*
Y108200D01*
X434390Y108117D01*
G01X439990Y108450D02*
Y103450D01*
G01X438823Y106783D02*
X441157D01*
G01X444173Y103450D02*
Y108450D01*
G01Y106033D02*
X444590Y106450D01*
X445007Y106700D01*
X445673Y106783D01*
X446173Y106700D01*
X446757Y106367D01*
X447007Y105867D01*
Y103450D01*
G01X458123Y106367D02*
X457540Y106700D01*
X457040Y106783D01*
X456373Y106617D01*
X455873Y106283D01*
X455540Y105700D01*
X455457Y105117D01*
X455540Y104533D01*
X455873Y104033D01*
X456373Y103617D01*
X457040Y103450D01*
X457623Y103617D01*
X458123Y103950D01*
G01X462390Y103450D02*
X461890Y103533D01*
X461390Y103867D01*
X461057Y104450D01*
X460890Y105117D01*
X461057Y105783D01*
X461390Y106367D01*
X461890Y106700D01*
X462390Y106783D01*
X462890Y106700D01*
X463390Y106367D01*
X463723Y105783D01*
X463807Y105117D01*
X463723Y104450D01*
X463390Y103867D01*
X462890Y103533D01*
X462390Y103450D01*
G01X466490Y101783D02*
Y106783D01*
G01Y106033D02*
X466907Y106450D01*
X467323Y106700D01*
X467990Y106783D01*
X468573Y106700D01*
X469157Y106283D01*
X469407Y105700D01*
X469490Y105117D01*
X469407Y104533D01*
X469157Y103950D01*
X468657Y103617D01*
X467990Y103450D01*
X467407Y103533D01*
X466823Y103783D01*
X466490Y104117D01*
G01X472090Y101783D02*
Y106783D01*
G01Y106033D02*
X472507Y106450D01*
X472923Y106700D01*
X473590Y106783D01*
X474173Y106700D01*
X474757Y106283D01*
X475007Y105700D01*
X475090Y105117D01*
X475007Y104533D01*
X474757Y103950D01*
X474257Y103617D01*
X473590Y103450D01*
X473007Y103533D01*
X472423Y103783D01*
X472090Y104117D01*
G01X477940Y105700D02*
X480607D01*
X480357Y106283D01*
X479940Y106617D01*
X479357Y106783D01*
X478773Y106700D01*
X478273Y106450D01*
X477940Y105867D01*
X477773Y105367D01*
Y104867D01*
X477940Y104367D01*
X478357Y103867D01*
X478857Y103533D01*
X479440Y103450D01*
X480023Y103617D01*
X480607Y104117D01*
G01X483623Y103450D02*
Y106783D01*
G01Y106117D02*
X484040Y106450D01*
X484457Y106700D01*
X485040Y106783D01*
X485457Y106700D01*
X485957Y106450D01*
G01X361090Y116810D02*
Y121060D01*
X361257Y121477D01*
X361590Y121727D01*
X362090Y121810D01*
X362590Y121643D01*
X362840Y121227D01*
G01X361840Y119810D02*
X360173D01*
G01X367190Y116810D02*
X366690Y116893D01*
X366190Y117227D01*
X365857Y117810D01*
X365690Y118477D01*
X365857Y119143D01*
X366190Y119727D01*
X366690Y120060D01*
X367190Y120143D01*
X367690Y120060D01*
X368190Y119727D01*
X368523Y119143D01*
X368607Y118477D01*
X368523Y117810D01*
X368190Y117227D01*
X367690Y116893D01*
X367190Y116810D01*
G01X372790D02*
Y121810D01*
G01X378390Y116810D02*
Y121810D01*
G01X383990Y116810D02*
X383490Y116893D01*
X382990Y117227D01*
X382657Y117810D01*
X382490Y118477D01*
X382657Y119143D01*
X382990Y119727D01*
X383490Y120060D01*
X383990Y120143D01*
X384490Y120060D01*
X384990Y119727D01*
X385323Y119143D01*
X385407Y118477D01*
X385323Y117810D01*
X384990Y117227D01*
X384490Y116893D01*
X383990Y116810D01*
G01X387507Y120143D02*
X388507Y116810D01*
X389590Y120143D01*
X390673Y116810D01*
X391673Y120143D01*
G01X401290Y119310D02*
X402957D01*
Y117810D01*
X402457Y117310D01*
X401873Y116977D01*
X401040Y116810D01*
X400207Y116977D01*
X399623Y117310D01*
X399123Y117810D01*
X398790Y118393D01*
X398623Y119060D01*
Y119643D01*
X398790Y120143D01*
X399123Y120727D01*
X399623Y121227D01*
X400123Y121560D01*
X400790Y121810D01*
X401373D01*
X402040Y121643D01*
X402540Y121310D01*
G01X405140Y119060D02*
X407807D01*
X407557Y119643D01*
X407140Y119977D01*
X406557Y120143D01*
X405973Y120060D01*
X405473Y119810D01*
X405140Y119227D01*
X404973Y118727D01*
Y118227D01*
X405140Y117727D01*
X405557Y117227D01*
X406057Y116893D01*
X406640Y116810D01*
X407223Y116977D01*
X407807Y117477D01*
G01X410823Y116810D02*
Y120143D01*
G01Y119477D02*
X411240Y119810D01*
X411657Y120060D01*
X412240Y120143D01*
X412657Y120060D01*
X413157Y119810D01*
G01X416090Y116810D02*
Y121810D01*
G01Y119310D02*
X416507Y119810D01*
X417007Y120060D01*
X417507Y120143D01*
X418257Y119977D01*
X418757Y119643D01*
X419090Y119060D01*
Y118393D01*
X418923Y117727D01*
X418590Y117227D01*
X418007Y116893D01*
X417507Y116810D01*
X417007Y116893D01*
X416507Y117143D01*
X416090Y117560D01*
G01X421940Y119060D02*
X424607D01*
X424357Y119643D01*
X423940Y119977D01*
X423357Y120143D01*
X422773Y120060D01*
X422273Y119810D01*
X421940Y119227D01*
X421773Y118727D01*
Y118227D01*
X421940Y117727D01*
X422357Y117227D01*
X422857Y116893D01*
X423440Y116810D01*
X424023Y116977D01*
X424607Y117477D01*
G01X427623Y116810D02*
Y120143D01*
G01Y119477D02*
X428040Y119810D01*
X428457Y120060D01*
X429040Y120143D01*
X429457Y120060D01*
X429957Y119810D01*
G01X441490Y116810D02*
Y120143D01*
G01Y119560D02*
X441157Y119893D01*
X440657Y120060D01*
X440073Y120143D01*
X439490Y119977D01*
X438990Y119643D01*
X438657Y119143D01*
X438490Y118477D01*
X438657Y117810D01*
X438990Y117310D01*
X439490Y116977D01*
X440073Y116810D01*
X440657Y116893D01*
X441157Y117143D01*
X441490Y117477D01*
G01X444173Y116810D02*
Y120143D01*
G01Y119310D02*
X444507Y119727D01*
X445007Y120060D01*
X445673Y120143D01*
X446257Y120060D01*
X446757Y119727D01*
X447007Y119143D01*
Y116810D01*
G01X452690Y121810D02*
Y116810D01*
G01Y117560D02*
X452357Y117143D01*
X451857Y116893D01*
X451273Y116810D01*
X450607Y116977D01*
X450107Y117393D01*
X449773Y117893D01*
X449690Y118477D01*
X449773Y119060D01*
X450107Y119560D01*
X450607Y119977D01*
X451273Y120143D01*
X451857Y120060D01*
X452273Y119893D01*
X452690Y119560D01*
G01X460890Y115143D02*
Y120143D01*
G01Y119393D02*
X461307Y119810D01*
X461723Y120060D01*
X462390Y120143D01*
X462973Y120060D01*
X463557Y119643D01*
X463807Y119060D01*
X463890Y118477D01*
X463807Y117893D01*
X463557Y117310D01*
X463057Y116977D01*
X462390Y116810D01*
X461807Y116893D01*
X461223Y117143D01*
X460890Y117477D01*
G01X467990Y116810D02*
Y121810D01*
G01X472173Y120143D02*
Y117810D01*
X472507Y117227D01*
X473007Y116893D01*
X473590Y116810D01*
X474173Y116893D01*
X474673Y117227D01*
X475007Y117810D01*
G01Y116810D02*
Y120143D01*
G01X478023Y115560D02*
X478607Y115227D01*
X479273Y115143D01*
X479857Y115227D01*
X480357Y115643D01*
X480690Y116227D01*
Y120143D01*
G01Y119477D02*
X480357Y119810D01*
X479857Y120060D01*
X479273Y120143D01*
X478607Y119977D01*
X478190Y119643D01*
X477857Y119060D01*
X477690Y118477D01*
X477773Y117977D01*
X478107Y117393D01*
X478607Y116977D01*
X479273Y116810D01*
X479773Y116893D01*
X480357Y117227D01*
X480690Y117560D01*
G01X488307Y120143D02*
X489307Y116810D01*
X490390Y120143D01*
X491473Y116810D01*
X492473Y120143D01*
G01X495990D02*
Y116810D01*
G01Y121477D02*
X495823Y121560D01*
Y121727D01*
X495990Y121810D01*
X496157Y121727D01*
Y121560D01*
X495990Y121477D01*
G01X501590Y121810D02*
Y116810D01*
G01X500423Y120143D02*
X502757D01*
G01X505773Y116810D02*
Y121810D01*
G01Y119393D02*
X506190Y119810D01*
X506607Y120060D01*
X507273Y120143D01*
X507773Y120060D01*
X508357Y119727D01*
X508607Y119227D01*
Y116810D01*
G01X517223D02*
Y120143D01*
G01Y119477D02*
X517640Y119810D01*
X518057Y120060D01*
X518640Y120143D01*
X519057Y120060D01*
X519557Y119810D01*
G01X522740Y119060D02*
X525407D01*
X525157Y119643D01*
X524740Y119977D01*
X524157Y120143D01*
X523573Y120060D01*
X523073Y119810D01*
X522740Y119227D01*
X522573Y118727D01*
Y118227D01*
X522740Y117727D01*
X523157Y117227D01*
X523657Y116893D01*
X524240Y116810D01*
X524823Y116977D01*
X525407Y117477D01*
G01X528340Y117393D02*
X528757Y117060D01*
X529340Y116810D01*
X529840D01*
X530340Y116977D01*
X530673Y117227D01*
X530840Y117560D01*
X530757Y118060D01*
X530423Y118310D01*
X528923Y118810D01*
X528590Y119393D01*
X528757Y119810D01*
X529090Y120060D01*
X529590Y120143D01*
X530090Y120060D01*
X530590Y119810D01*
G01X535190Y120143D02*
Y116810D01*
G01Y121477D02*
X535023Y121560D01*
Y121727D01*
X535190Y121810D01*
X535357Y121727D01*
Y121560D01*
X535190Y121477D01*
G01X539373Y116810D02*
Y120143D01*
G01Y119310D02*
X539707Y119727D01*
X540207Y120060D01*
X540873Y120143D01*
X541457Y120060D01*
X541957Y119727D01*
X542207Y119143D01*
Y116810D01*
G01X363000Y146500D02*
Y150750D01*
X363167Y151167D01*
X363500Y151417D01*
X364000Y151500D01*
X364500Y151333D01*
X364750Y150917D01*
G01X363750Y149500D02*
X362083D01*
G01X369100Y146500D02*
X368600Y146583D01*
X368100Y146917D01*
X367767Y147500D01*
X367600Y148167D01*
X367767Y148833D01*
X368100Y149417D01*
X368600Y149750D01*
X369100Y149833D01*
X369600Y149750D01*
X370100Y149417D01*
X370433Y148833D01*
X370517Y148167D01*
X370433Y147500D01*
X370100Y146917D01*
X369600Y146583D01*
X369100Y146500D01*
G01X374700D02*
Y151500D01*
G01X380300Y146500D02*
Y151500D01*
G01X385900Y146500D02*
X385400Y146583D01*
X384900Y146917D01*
X384567Y147500D01*
X384400Y148167D01*
X384567Y148833D01*
X384900Y149417D01*
X385400Y149750D01*
X385900Y149833D01*
X386400Y149750D01*
X386900Y149417D01*
X387233Y148833D01*
X387317Y148167D01*
X387233Y147500D01*
X386900Y146917D01*
X386400Y146583D01*
X385900Y146500D01*
G01X389417Y149833D02*
X390417Y146500D01*
X391500Y149833D01*
X392583Y146500D01*
X393583Y149833D01*
G01X403200Y149000D02*
X404867D01*
Y147500D01*
X404367Y147000D01*
X403783Y146667D01*
X402950Y146500D01*
X402117Y146667D01*
X401533Y147000D01*
X401033Y147500D01*
X400700Y148083D01*
X400533Y148750D01*
Y149333D01*
X400700Y149833D01*
X401033Y150417D01*
X401533Y150917D01*
X402033Y151250D01*
X402700Y151500D01*
X403283D01*
X403950Y151333D01*
X404450Y151000D01*
G01X407050Y148750D02*
X409717D01*
X409467Y149333D01*
X409050Y149667D01*
X408467Y149833D01*
X407883Y149750D01*
X407383Y149500D01*
X407050Y148917D01*
X406883Y148417D01*
Y147917D01*
X407050Y147417D01*
X407467Y146917D01*
X407967Y146583D01*
X408550Y146500D01*
X409133Y146667D01*
X409717Y147167D01*
G01X412733Y146500D02*
Y149833D01*
G01Y149167D02*
X413150Y149500D01*
X413567Y149750D01*
X414150Y149833D01*
X414567Y149750D01*
X415067Y149500D01*
G01X418000Y146500D02*
Y151500D01*
G01Y149000D02*
X418417Y149500D01*
X418917Y149750D01*
X419417Y149833D01*
X420167Y149667D01*
X420667Y149333D01*
X421000Y148750D01*
Y148083D01*
X420833Y147417D01*
X420500Y146917D01*
X419917Y146583D01*
X419417Y146500D01*
X418917Y146583D01*
X418417Y146833D01*
X418000Y147250D01*
G01X423850Y148750D02*
X426517D01*
X426267Y149333D01*
X425850Y149667D01*
X425267Y149833D01*
X424683Y149750D01*
X424183Y149500D01*
X423850Y148917D01*
X423683Y148417D01*
Y147917D01*
X423850Y147417D01*
X424267Y146917D01*
X424767Y146583D01*
X425350Y146500D01*
X425933Y146667D01*
X426517Y147167D01*
G01X429533Y146500D02*
Y149833D01*
G01Y149167D02*
X429950Y149500D01*
X430367Y149750D01*
X430950Y149833D01*
X431367Y149750D01*
X431867Y149500D01*
G01X443400Y146500D02*
Y149833D01*
G01Y149250D02*
X443067Y149583D01*
X442567Y149750D01*
X441983Y149833D01*
X441400Y149667D01*
X440900Y149333D01*
X440567Y148833D01*
X440400Y148167D01*
X440567Y147500D01*
X440900Y147000D01*
X441400Y146667D01*
X441983Y146500D01*
X442567Y146583D01*
X443067Y146833D01*
X443400Y147167D01*
G01X446083Y146500D02*
Y149833D01*
G01Y149000D02*
X446417Y149417D01*
X446917Y149750D01*
X447583Y149833D01*
X448167Y149750D01*
X448667Y149417D01*
X448917Y148833D01*
Y146500D01*
G01X454600Y151500D02*
Y146500D01*
G01Y147250D02*
X454267Y146833D01*
X453767Y146583D01*
X453183Y146500D01*
X452517Y146667D01*
X452017Y147083D01*
X451683Y147583D01*
X451600Y148167D01*
X451683Y148750D01*
X452017Y149250D01*
X452517Y149667D01*
X453183Y149833D01*
X453767Y149750D01*
X454183Y149583D01*
X454600Y149250D01*
G01X462800Y144833D02*
Y149833D01*
G01Y149083D02*
X463217Y149500D01*
X463633Y149750D01*
X464300Y149833D01*
X464883Y149750D01*
X465467Y149333D01*
X465717Y148750D01*
X465800Y148167D01*
X465717Y147583D01*
X465467Y147000D01*
X464967Y146667D01*
X464300Y146500D01*
X463717Y146583D01*
X463133Y146833D01*
X462800Y147167D01*
G01X469900Y146500D02*
Y151500D01*
G01X474083Y149833D02*
Y147500D01*
X474417Y146917D01*
X474917Y146583D01*
X475500Y146500D01*
X476083Y146583D01*
X476583Y146917D01*
X476917Y147500D01*
G01Y146500D02*
Y149833D01*
G01X479933Y145250D02*
X480517Y144917D01*
X481183Y144833D01*
X481767Y144917D01*
X482267Y145333D01*
X482600Y145917D01*
Y149833D01*
G01Y149167D02*
X482267Y149500D01*
X481767Y149750D01*
X481183Y149833D01*
X480517Y149667D01*
X480100Y149333D01*
X479767Y148750D01*
X479600Y148167D01*
X479683Y147667D01*
X480017Y147083D01*
X480517Y146667D01*
X481183Y146500D01*
X481683Y146583D01*
X482267Y146917D01*
X482600Y147250D01*
G01X490217Y149833D02*
X491217Y146500D01*
X492300Y149833D01*
X493383Y146500D01*
X494383Y149833D01*
G01X497900D02*
Y146500D01*
G01Y151167D02*
X497733Y151250D01*
Y151417D01*
X497900Y151500D01*
X498067Y151417D01*
Y151250D01*
X497900Y151167D01*
G01X503500Y151500D02*
Y146500D01*
G01X502333Y149833D02*
X504667D01*
G01X507683Y146500D02*
Y151500D01*
G01Y149083D02*
X508100Y149500D01*
X508517Y149750D01*
X509183Y149833D01*
X509683Y149750D01*
X510267Y149417D01*
X510517Y148917D01*
Y146500D01*
G01X519133D02*
Y149833D01*
G01Y149167D02*
X519550Y149500D01*
X519967Y149750D01*
X520550Y149833D01*
X520967Y149750D01*
X521467Y149500D01*
G01X524650Y148750D02*
X527317D01*
X527067Y149333D01*
X526650Y149667D01*
X526067Y149833D01*
X525483Y149750D01*
X524983Y149500D01*
X524650Y148917D01*
X524483Y148417D01*
Y147917D01*
X524650Y147417D01*
X525067Y146917D01*
X525567Y146583D01*
X526150Y146500D01*
X526733Y146667D01*
X527317Y147167D01*
G01X530250Y147083D02*
X530667Y146750D01*
X531250Y146500D01*
X531750D01*
X532250Y146667D01*
X532583Y146917D01*
X532750Y147250D01*
X532667Y147750D01*
X532333Y148000D01*
X530833Y148500D01*
X530500Y149083D01*
X530667Y149500D01*
X531000Y149750D01*
X531500Y149833D01*
X532000Y149750D01*
X532500Y149500D01*
G01X537100Y149833D02*
Y146500D01*
G01Y151167D02*
X536933Y151250D01*
Y151417D01*
X537100Y151500D01*
X537267Y151417D01*
Y151250D01*
X537100Y151167D01*
G01X541283Y146500D02*
Y149833D01*
G01Y149000D02*
X541617Y149417D01*
X542117Y149750D01*
X542783Y149833D01*
X543367Y149750D01*
X543867Y149417D01*
X544117Y148833D01*
Y146500D01*
G01X363000Y167500D02*
Y171750D01*
X363167Y172167D01*
X363500Y172417D01*
X364000Y172500D01*
X364500Y172333D01*
X364750Y171917D01*
G01X363750Y170500D02*
X362083D01*
G01X369100Y167500D02*
X368600Y167583D01*
X368100Y167917D01*
X367767Y168500D01*
X367600Y169167D01*
X367767Y169833D01*
X368100Y170417D01*
X368600Y170750D01*
X369100Y170833D01*
X369600Y170750D01*
X370100Y170417D01*
X370433Y169833D01*
X370517Y169167D01*
X370433Y168500D01*
X370100Y167917D01*
X369600Y167583D01*
X369100Y167500D01*
G01X374700D02*
Y172500D01*
G01X380300Y167500D02*
Y172500D01*
G01X385900Y167500D02*
X385400Y167583D01*
X384900Y167917D01*
X384567Y168500D01*
X384400Y169167D01*
X384567Y169833D01*
X384900Y170417D01*
X385400Y170750D01*
X385900Y170833D01*
X386400Y170750D01*
X386900Y170417D01*
X387233Y169833D01*
X387317Y169167D01*
X387233Y168500D01*
X386900Y167917D01*
X386400Y167583D01*
X385900Y167500D01*
G01X389417Y170833D02*
X390417Y167500D01*
X391500Y170833D01*
X392583Y167500D01*
X393583Y170833D01*
G01X403200Y170000D02*
X404867D01*
Y168500D01*
X404367Y168000D01*
X403783Y167667D01*
X402950Y167500D01*
X402117Y167667D01*
X401533Y168000D01*
X401033Y168500D01*
X400700Y169083D01*
X400533Y169750D01*
Y170333D01*
X400700Y170833D01*
X401033Y171417D01*
X401533Y171917D01*
X402033Y172250D01*
X402700Y172500D01*
X403283D01*
X403950Y172333D01*
X404450Y172000D01*
G01X407050Y169750D02*
X409717D01*
X409467Y170333D01*
X409050Y170667D01*
X408467Y170833D01*
X407883Y170750D01*
X407383Y170500D01*
X407050Y169917D01*
X406883Y169417D01*
Y168917D01*
X407050Y168417D01*
X407467Y167917D01*
X407967Y167583D01*
X408550Y167500D01*
X409133Y167667D01*
X409717Y168167D01*
G01X412733Y167500D02*
Y170833D01*
G01Y170167D02*
X413150Y170500D01*
X413567Y170750D01*
X414150Y170833D01*
X414567Y170750D01*
X415067Y170500D01*
G01X418000Y167500D02*
Y172500D01*
G01Y170000D02*
X418417Y170500D01*
X418917Y170750D01*
X419417Y170833D01*
X420167Y170667D01*
X420667Y170333D01*
X421000Y169750D01*
Y169083D01*
X420833Y168417D01*
X420500Y167917D01*
X419917Y167583D01*
X419417Y167500D01*
X418917Y167583D01*
X418417Y167833D01*
X418000Y168250D01*
G01X423850Y169750D02*
X426517D01*
X426267Y170333D01*
X425850Y170667D01*
X425267Y170833D01*
X424683Y170750D01*
X424183Y170500D01*
X423850Y169917D01*
X423683Y169417D01*
Y168917D01*
X423850Y168417D01*
X424267Y167917D01*
X424767Y167583D01*
X425350Y167500D01*
X425933Y167667D01*
X426517Y168167D01*
G01X429533Y167500D02*
Y170833D01*
G01Y170167D02*
X429950Y170500D01*
X430367Y170750D01*
X430950Y170833D01*
X431367Y170750D01*
X431867Y170500D01*
G01X365000Y182500D02*
Y185833D01*
G01Y185250D02*
X364667Y185583D01*
X364167Y185750D01*
X363583Y185833D01*
X363000Y185667D01*
X362500Y185333D01*
X362167Y184833D01*
X362000Y184167D01*
X362167Y183500D01*
X362500Y183000D01*
X363000Y182667D01*
X363583Y182500D01*
X364167Y182583D01*
X364667Y182833D01*
X365000Y183167D01*
G01X367683Y182500D02*
Y185833D01*
G01Y185000D02*
X368017Y185417D01*
X368517Y185750D01*
X369183Y185833D01*
X369767Y185750D01*
X370267Y185417D01*
X370517Y184833D01*
Y182500D01*
G01X376200Y187500D02*
Y182500D01*
G01Y183250D02*
X375867Y182833D01*
X375367Y182583D01*
X374783Y182500D01*
X374117Y182667D01*
X373617Y183083D01*
X373283Y183583D01*
X373200Y184167D01*
X373283Y184750D01*
X373617Y185250D01*
X374117Y185667D01*
X374783Y185833D01*
X375367Y185750D01*
X375783Y185583D01*
X376200Y185250D01*
G01X384400Y182500D02*
Y187500D01*
G01Y185000D02*
X384817Y185500D01*
X385317Y185750D01*
X385817Y185833D01*
X386567Y185667D01*
X387067Y185333D01*
X387400Y184750D01*
Y184083D01*
X387233Y183417D01*
X386900Y182917D01*
X386317Y182583D01*
X385817Y182500D01*
X385317Y182583D01*
X384817Y182833D01*
X384400Y183250D01*
G01X391500Y182500D02*
X391000Y182583D01*
X390500Y182917D01*
X390167Y183500D01*
X390000Y184167D01*
X390167Y184833D01*
X390500Y185417D01*
X391000Y185750D01*
X391500Y185833D01*
X392000Y185750D01*
X392500Y185417D01*
X392833Y184833D01*
X392917Y184167D01*
X392833Y183500D01*
X392500Y182917D01*
X392000Y182583D01*
X391500Y182500D01*
G01X397100Y187500D02*
Y182500D01*
G01X395933Y185833D02*
X398267D01*
G01X402700Y187500D02*
Y182500D01*
G01X401533Y185833D02*
X403867D01*
G01X408300Y182500D02*
X407800Y182583D01*
X407300Y182917D01*
X406967Y183500D01*
X406800Y184167D01*
X406967Y184833D01*
X407300Y185417D01*
X407800Y185750D01*
X408300Y185833D01*
X408800Y185750D01*
X409300Y185417D01*
X409633Y184833D01*
X409717Y184167D01*
X409633Y183500D01*
X409300Y182917D01*
X408800Y182583D01*
X408300Y182500D01*
G01X411400D02*
Y185833D01*
G01Y184917D02*
X411650Y185333D01*
X412067Y185667D01*
X412650Y185833D01*
X413233Y185667D01*
X413650Y185333D01*
X413900Y184917D01*
Y182500D01*
G01Y184917D02*
X414150Y185333D01*
X414567Y185667D01*
X415150Y185833D01*
X415733Y185667D01*
X416150Y185333D01*
X416400Y184833D01*
Y182500D01*
G01X423850Y183083D02*
X424267Y182750D01*
X424850Y182500D01*
X425350D01*
X425850Y182667D01*
X426183Y182917D01*
X426350Y183250D01*
X426267Y183750D01*
X425933Y184000D01*
X424433Y184500D01*
X424100Y185083D01*
X424267Y185500D01*
X424600Y185750D01*
X425100Y185833D01*
X425600Y185750D01*
X426100Y185500D01*
G01X430700Y185833D02*
Y182500D01*
G01Y187167D02*
X430533Y187250D01*
Y187417D01*
X430700Y187500D01*
X430867Y187417D01*
Y187250D01*
X430700Y187167D01*
G01X437800Y187500D02*
Y182500D01*
G01Y183250D02*
X437467Y182833D01*
X436967Y182583D01*
X436383Y182500D01*
X435717Y182667D01*
X435217Y183083D01*
X434883Y183583D01*
X434800Y184167D01*
X434883Y184750D01*
X435217Y185250D01*
X435717Y185667D01*
X436383Y185833D01*
X436967Y185750D01*
X437383Y185583D01*
X437800Y185250D01*
G01X440650Y184750D02*
X443317D01*
X443067Y185333D01*
X442650Y185667D01*
X442067Y185833D01*
X441483Y185750D01*
X440983Y185500D01*
X440650Y184917D01*
X440483Y184417D01*
Y183917D01*
X440650Y183417D01*
X441067Y182917D01*
X441567Y182583D01*
X442150Y182500D01*
X442733Y182667D01*
X443317Y183167D01*
G01X361417Y197833D02*
X362417Y194500D01*
X363500Y197833D01*
X364583Y194500D01*
X365583Y197833D01*
G01X369100D02*
Y194500D01*
G01Y199167D02*
X368933Y199250D01*
Y199417D01*
X369100Y199500D01*
X369267Y199417D01*
Y199250D01*
X369100Y199167D01*
G01X374700Y199500D02*
Y194500D01*
G01X373533Y197833D02*
X375867D01*
G01X378883Y194500D02*
Y199500D01*
G01Y197083D02*
X379300Y197500D01*
X379717Y197750D01*
X380383Y197833D01*
X380883Y197750D01*
X381467Y197417D01*
X381717Y196917D01*
Y194500D01*
G01X385900D02*
X385400Y194583D01*
X384900Y194917D01*
X384567Y195500D01*
X384400Y196167D01*
X384567Y196833D01*
X384900Y197417D01*
X385400Y197750D01*
X385900Y197833D01*
X386400Y197750D01*
X386900Y197417D01*
X387233Y196833D01*
X387317Y196167D01*
X387233Y195500D01*
X386900Y194917D01*
X386400Y194583D01*
X385900Y194500D01*
G01X390083Y197833D02*
Y195500D01*
X390417Y194917D01*
X390917Y194583D01*
X391500Y194500D01*
X392083Y194583D01*
X392583Y194917D01*
X392917Y195500D01*
G01Y194500D02*
Y197833D01*
G01X397100Y199500D02*
Y194500D01*
G01X395933Y197833D02*
X398267D01*
G01X407050Y195083D02*
X407467Y194750D01*
X408050Y194500D01*
X408550D01*
X409050Y194667D01*
X409383Y194917D01*
X409550Y195250D01*
X409467Y195750D01*
X409133Y196000D01*
X407633Y196500D01*
X407300Y197083D01*
X407467Y197500D01*
X407800Y197750D01*
X408300Y197833D01*
X408800Y197750D01*
X409300Y197500D01*
G01X413900Y194500D02*
X413400Y194583D01*
X412900Y194917D01*
X412567Y195500D01*
X412400Y196167D01*
X412567Y196833D01*
X412900Y197417D01*
X413400Y197750D01*
X413900Y197833D01*
X414400Y197750D01*
X414900Y197417D01*
X415233Y196833D01*
X415317Y196167D01*
X415233Y195500D01*
X414900Y194917D01*
X414400Y194583D01*
X413900Y194500D01*
G01X419500D02*
Y199500D01*
G01X426600D02*
Y194500D01*
G01Y195250D02*
X426267Y194833D01*
X425767Y194583D01*
X425183Y194500D01*
X424517Y194667D01*
X424017Y195083D01*
X423683Y195583D01*
X423600Y196167D01*
X423683Y196750D01*
X424017Y197250D01*
X424517Y197667D01*
X425183Y197833D01*
X425767Y197750D01*
X426183Y197583D01*
X426600Y197250D01*
G01X429450Y196750D02*
X432117D01*
X431867Y197333D01*
X431450Y197667D01*
X430867Y197833D01*
X430283Y197750D01*
X429783Y197500D01*
X429450Y196917D01*
X429283Y196417D01*
Y195917D01*
X429450Y195417D01*
X429867Y194917D01*
X430367Y194583D01*
X430950Y194500D01*
X431533Y194667D01*
X432117Y195167D01*
G01X435133Y194500D02*
Y197833D01*
G01Y197167D02*
X435550Y197500D01*
X435967Y197750D01*
X436550Y197833D01*
X436967Y197750D01*
X437467Y197500D01*
G01X445000Y194500D02*
Y197833D01*
G01Y196917D02*
X445250Y197333D01*
X445667Y197667D01*
X446250Y197833D01*
X446833Y197667D01*
X447250Y197333D01*
X447500Y196917D01*
Y194500D01*
G01Y196917D02*
X447750Y197333D01*
X448167Y197667D01*
X448750Y197833D01*
X449333Y197667D01*
X449750Y197333D01*
X450000Y196833D01*
Y194500D01*
G01X454600D02*
Y197833D01*
G01Y197250D02*
X454267Y197583D01*
X453767Y197750D01*
X453183Y197833D01*
X452600Y197667D01*
X452100Y197333D01*
X451767Y196833D01*
X451600Y196167D01*
X451767Y195500D01*
X452100Y195000D01*
X452600Y194667D01*
X453183Y194500D01*
X453767Y194583D01*
X454267Y194833D01*
X454600Y195167D01*
G01X457450Y195083D02*
X457867Y194750D01*
X458450Y194500D01*
X458950D01*
X459450Y194667D01*
X459783Y194917D01*
X459950Y195250D01*
X459867Y195750D01*
X459533Y196000D01*
X458033Y196500D01*
X457700Y197083D01*
X457867Y197500D01*
X458200Y197750D01*
X458700Y197833D01*
X459200Y197750D01*
X459700Y197500D01*
G01X462883Y194500D02*
Y199500D01*
G01X465550Y197833D02*
X462883Y195917D01*
G01X463967Y196667D02*
X465717Y194500D01*
G01X474000Y192833D02*
Y197833D01*
G01Y197083D02*
X474417Y197500D01*
X474833Y197750D01*
X475500Y197833D01*
X476083Y197750D01*
X476667Y197333D01*
X476917Y196750D01*
X477000Y196167D01*
X476917Y195583D01*
X476667Y195000D01*
X476167Y194667D01*
X475500Y194500D01*
X474917Y194583D01*
X474333Y194833D01*
X474000Y195167D01*
G01X482600Y194500D02*
Y197833D01*
G01Y197250D02*
X482267Y197583D01*
X481767Y197750D01*
X481183Y197833D01*
X480600Y197667D01*
X480100Y197333D01*
X479767Y196833D01*
X479600Y196167D01*
X479767Y195500D01*
X480100Y195000D01*
X480600Y194667D01*
X481183Y194500D01*
X481767Y194583D01*
X482267Y194833D01*
X482600Y195167D01*
G01X488200Y199500D02*
Y194500D01*
G01Y195250D02*
X487867Y194833D01*
X487367Y194583D01*
X486783Y194500D01*
X486117Y194667D01*
X485617Y195083D01*
X485283Y195583D01*
X485200Y196167D01*
X485283Y196750D01*
X485617Y197250D01*
X486117Y197667D01*
X486783Y197833D01*
X487367Y197750D01*
X487783Y197583D01*
X488200Y197250D01*
G01X497900Y194500D02*
X497400Y194583D01*
X496900Y194917D01*
X496567Y195500D01*
X496400Y196167D01*
X496567Y196833D01*
X496900Y197417D01*
X497400Y197750D01*
X497900Y197833D01*
X498400Y197750D01*
X498900Y197417D01*
X499233Y196833D01*
X499317Y196167D01*
X499233Y195500D01*
X498900Y194917D01*
X498400Y194583D01*
X497900Y194500D01*
G01X502083D02*
Y197833D01*
G01Y197000D02*
X502417Y197417D01*
X502917Y197750D01*
X503583Y197833D01*
X504167Y197750D01*
X504667Y197417D01*
X504917Y196833D01*
Y194500D01*
G01X514700Y199500D02*
Y194500D01*
G01X513533Y197833D02*
X515867D01*
G01X520300Y194500D02*
X519800Y194583D01*
X519300Y194917D01*
X518967Y195500D01*
X518800Y196167D01*
X518967Y196833D01*
X519300Y197417D01*
X519800Y197750D01*
X520300Y197833D01*
X520800Y197750D01*
X521300Y197417D01*
X521633Y196833D01*
X521717Y196167D01*
X521633Y195500D01*
X521300Y194917D01*
X520800Y194583D01*
X520300Y194500D01*
G01X524400Y192833D02*
Y197833D01*
G01Y197083D02*
X524817Y197500D01*
X525233Y197750D01*
X525900Y197833D01*
X526483Y197750D01*
X527067Y197333D01*
X527317Y196750D01*
X527400Y196167D01*
X527317Y195583D01*
X527067Y195000D01*
X526567Y194667D01*
X525900Y194500D01*
X525317Y194583D01*
X524733Y194833D01*
X524400Y195167D01*
G01X363500Y296000D02*
Y301000D01*
X362500Y300000D01*
G01Y296000D02*
X364500D01*
G01X369100Y295833D02*
X368933Y295917D01*
Y296083D01*
X369100Y296167D01*
X369267Y296083D01*
Y295917D01*
X369100Y295833D01*
G01X374700Y296000D02*
X374033Y296083D01*
X373450Y296417D01*
X372950Y296917D01*
X372617Y297500D01*
X372450Y298167D01*
Y298833D01*
X372617Y299500D01*
X372950Y300083D01*
X373450Y300583D01*
X374033Y300917D01*
X374700Y301000D01*
X375367Y300917D01*
X375950Y300583D01*
X376450Y300083D01*
X376783Y299500D01*
X376950Y298833D01*
Y298167D01*
X376783Y297500D01*
X376450Y296917D01*
X375950Y296417D01*
X375367Y296083D01*
X374700Y296000D01*
G01X378883D02*
Y299333D01*
G01Y298500D02*
X379217Y298917D01*
X379717Y299250D01*
X380383Y299333D01*
X380967Y299250D01*
X381467Y298917D01*
X381717Y298333D01*
Y296000D01*
G01X384650Y298250D02*
X387317D01*
X387067Y298833D01*
X386650Y299167D01*
X386067Y299333D01*
X385483Y299250D01*
X384983Y299000D01*
X384650Y298417D01*
X384483Y297917D01*
Y297417D01*
X384650Y296917D01*
X385067Y296417D01*
X385567Y296083D01*
X386150Y296000D01*
X386733Y296167D01*
X387317Y296667D01*
G01X395850Y296583D02*
X396267Y296250D01*
X396850Y296000D01*
X397350D01*
X397850Y296167D01*
X398183Y296417D01*
X398350Y296750D01*
X398267Y297250D01*
X397933Y297500D01*
X396433Y298000D01*
X396100Y298583D01*
X396267Y299000D01*
X396600Y299250D01*
X397100Y299333D01*
X397600Y299250D01*
X398100Y299000D01*
G01X402700Y299333D02*
Y296000D01*
G01Y300667D02*
X402533Y300750D01*
Y300917D01*
X402700Y301000D01*
X402867Y300917D01*
Y300750D01*
X402700Y300667D01*
G01X409800Y301000D02*
Y296000D01*
G01Y296750D02*
X409467Y296333D01*
X408967Y296083D01*
X408383Y296000D01*
X407717Y296167D01*
X407217Y296583D01*
X406883Y297083D01*
X406800Y297667D01*
X406883Y298250D01*
X407217Y298750D01*
X407717Y299167D01*
X408383Y299333D01*
X408967Y299250D01*
X409383Y299083D01*
X409800Y298750D01*
G01X412650Y298250D02*
X415317D01*
X415067Y298833D01*
X414650Y299167D01*
X414067Y299333D01*
X413483Y299250D01*
X412983Y299000D01*
X412650Y298417D01*
X412483Y297917D01*
Y297417D01*
X412650Y296917D01*
X413067Y296417D01*
X413567Y296083D01*
X414150Y296000D01*
X414733Y296167D01*
X415317Y296667D01*
G01X423017Y299333D02*
X424017Y296000D01*
X425100Y299333D01*
X426183Y296000D01*
X427183Y299333D01*
G01X430700D02*
Y296000D01*
G01Y300667D02*
X430533Y300750D01*
Y300917D01*
X430700Y301000D01*
X430867Y300917D01*
Y300750D01*
X430700Y300667D01*
G01X436300Y301000D02*
Y296000D01*
G01X435133Y299333D02*
X437467D01*
G01X440483Y296000D02*
Y301000D01*
G01Y298583D02*
X440900Y299000D01*
X441317Y299250D01*
X441983Y299333D01*
X442483Y299250D01*
X443067Y298917D01*
X443317Y298417D01*
Y296000D01*
G01X451850Y296583D02*
X452267Y296250D01*
X452850Y296000D01*
X453350D01*
X453850Y296167D01*
X454183Y296417D01*
X454350Y296750D01*
X454267Y297250D01*
X453933Y297500D01*
X452433Y298000D01*
X452100Y298583D01*
X452267Y299000D01*
X452600Y299250D01*
X453100Y299333D01*
X453600Y299250D01*
X454100Y299000D01*
G01X458700Y296000D02*
X458200Y296083D01*
X457700Y296417D01*
X457367Y297000D01*
X457200Y297667D01*
X457367Y298333D01*
X457700Y298917D01*
X458200Y299250D01*
X458700Y299333D01*
X459200Y299250D01*
X459700Y298917D01*
X460033Y298333D01*
X460117Y297667D01*
X460033Y297000D01*
X459700Y296417D01*
X459200Y296083D01*
X458700Y296000D01*
G01X464300D02*
Y301000D01*
G01X471400D02*
Y296000D01*
G01Y296750D02*
X471067Y296333D01*
X470567Y296083D01*
X469983Y296000D01*
X469317Y296167D01*
X468817Y296583D01*
X468483Y297083D01*
X468400Y297667D01*
X468483Y298250D01*
X468817Y298750D01*
X469317Y299167D01*
X469983Y299333D01*
X470567Y299250D01*
X470983Y299083D01*
X471400Y298750D01*
G01X474250Y298250D02*
X476917D01*
X476667Y298833D01*
X476250Y299167D01*
X475667Y299333D01*
X475083Y299250D01*
X474583Y299000D01*
X474250Y298417D01*
X474083Y297917D01*
Y297417D01*
X474250Y296917D01*
X474667Y296417D01*
X475167Y296083D01*
X475750Y296000D01*
X476333Y296167D01*
X476917Y296667D01*
G01X479933Y296000D02*
Y299333D01*
G01Y298667D02*
X480350Y299000D01*
X480767Y299250D01*
X481350Y299333D01*
X481767Y299250D01*
X482267Y299000D01*
G01X489800Y296000D02*
Y299333D01*
G01Y298417D02*
X490050Y298833D01*
X490467Y299167D01*
X491050Y299333D01*
X491633Y299167D01*
X492050Y298833D01*
X492300Y298417D01*
Y296000D01*
G01Y298417D02*
X492550Y298833D01*
X492967Y299167D01*
X493550Y299333D01*
X494133Y299167D01*
X494550Y298833D01*
X494800Y298333D01*
Y296000D01*
G01X499400D02*
Y299333D01*
G01Y298750D02*
X499067Y299083D01*
X498567Y299250D01*
X497983Y299333D01*
X497400Y299167D01*
X496900Y298833D01*
X496567Y298333D01*
X496400Y297667D01*
X496567Y297000D01*
X496900Y296500D01*
X497400Y296167D01*
X497983Y296000D01*
X498567Y296083D01*
X499067Y296333D01*
X499400Y296667D01*
G01X502250Y296583D02*
X502667Y296250D01*
X503250Y296000D01*
X503750D01*
X504250Y296167D01*
X504583Y296417D01*
X504750Y296750D01*
X504667Y297250D01*
X504333Y297500D01*
X502833Y298000D01*
X502500Y298583D01*
X502667Y299000D01*
X503000Y299250D01*
X503500Y299333D01*
X504000Y299250D01*
X504500Y299000D01*
G01X507683Y296000D02*
Y301000D01*
G01X510350Y299333D02*
X507683Y297417D01*
G01X508767Y298167D02*
X510517Y296000D01*
G01X518800Y294333D02*
Y299333D01*
G01Y298583D02*
X519217Y299000D01*
X519633Y299250D01*
X520300Y299333D01*
X520883Y299250D01*
X521467Y298833D01*
X521717Y298250D01*
X521800Y297667D01*
X521717Y297083D01*
X521467Y296500D01*
X520967Y296167D01*
X520300Y296000D01*
X519717Y296083D01*
X519133Y296333D01*
X518800Y296667D01*
G01X527400Y296000D02*
Y299333D01*
G01Y298750D02*
X527067Y299083D01*
X526567Y299250D01*
X525983Y299333D01*
X525400Y299167D01*
X524900Y298833D01*
X524567Y298333D01*
X524400Y297667D01*
X524567Y297000D01*
X524900Y296500D01*
X525400Y296167D01*
X525983Y296000D01*
X526567Y296083D01*
X527067Y296333D01*
X527400Y296667D01*
G01X533000Y301000D02*
Y296000D01*
G01Y296750D02*
X532667Y296333D01*
X532167Y296083D01*
X531583Y296000D01*
X530917Y296167D01*
X530417Y296583D01*
X530083Y297083D01*
X530000Y297667D01*
X530083Y298250D01*
X530417Y298750D01*
X530917Y299167D01*
X531583Y299333D01*
X532167Y299250D01*
X532583Y299083D01*
X533000Y298750D01*
G01X371250Y269583D02*
X371667Y269250D01*
X372250Y269000D01*
X372750D01*
X373250Y269167D01*
X373583Y269417D01*
X373750Y269750D01*
X373667Y270250D01*
X373333Y270500D01*
X371833Y271000D01*
X371500Y271583D01*
X371667Y272000D01*
X372000Y272250D01*
X372500Y272333D01*
X373000Y272250D01*
X373500Y272000D01*
G01X378100Y269000D02*
X377600Y269083D01*
X377100Y269417D01*
X376767Y270000D01*
X376600Y270667D01*
X376767Y271333D01*
X377100Y271917D01*
X377600Y272250D01*
X378100Y272333D01*
X378600Y272250D01*
X379100Y271917D01*
X379433Y271333D01*
X379517Y270667D01*
X379433Y270000D01*
X379100Y269417D01*
X378600Y269083D01*
X378100Y269000D01*
G01X383700D02*
Y274000D01*
G01X390800D02*
Y269000D01*
G01Y269750D02*
X390467Y269333D01*
X389967Y269083D01*
X389383Y269000D01*
X388717Y269167D01*
X388217Y269583D01*
X387883Y270083D01*
X387800Y270667D01*
X387883Y271250D01*
X388217Y271750D01*
X388717Y272167D01*
X389383Y272333D01*
X389967Y272250D01*
X390383Y272083D01*
X390800Y271750D01*
G01X393650Y271250D02*
X396317D01*
X396067Y271833D01*
X395650Y272167D01*
X395067Y272333D01*
X394483Y272250D01*
X393983Y272000D01*
X393650Y271417D01*
X393483Y270917D01*
Y270417D01*
X393650Y269917D01*
X394067Y269417D01*
X394567Y269083D01*
X395150Y269000D01*
X395733Y269167D01*
X396317Y269667D01*
G01X399333Y269000D02*
Y272333D01*
G01Y271667D02*
X399750Y272000D01*
X400167Y272250D01*
X400750Y272333D01*
X401167Y272250D01*
X401667Y272000D01*
G01X409200Y269000D02*
Y272333D01*
G01Y271417D02*
X409450Y271833D01*
X409867Y272167D01*
X410450Y272333D01*
X411033Y272167D01*
X411450Y271833D01*
X411700Y271417D01*
Y269000D01*
G01Y271417D02*
X411950Y271833D01*
X412367Y272167D01*
X412950Y272333D01*
X413533Y272167D01*
X413950Y271833D01*
X414200Y271333D01*
Y269000D01*
G01X418800D02*
Y272333D01*
G01Y271750D02*
X418467Y272083D01*
X417967Y272250D01*
X417383Y272333D01*
X416800Y272167D01*
X416300Y271833D01*
X415967Y271333D01*
X415800Y270667D01*
X415967Y270000D01*
X416300Y269500D01*
X416800Y269167D01*
X417383Y269000D01*
X417967Y269083D01*
X418467Y269333D01*
X418800Y269667D01*
G01X421650Y269583D02*
X422067Y269250D01*
X422650Y269000D01*
X423150D01*
X423650Y269167D01*
X423983Y269417D01*
X424150Y269750D01*
X424067Y270250D01*
X423733Y270500D01*
X422233Y271000D01*
X421900Y271583D01*
X422067Y272000D01*
X422400Y272250D01*
X422900Y272333D01*
X423400Y272250D01*
X423900Y272000D01*
G01X427083Y269000D02*
Y274000D01*
G01X429750Y272333D02*
X427083Y270417D01*
G01X428167Y271167D02*
X429917Y269000D01*
G01X438200Y267333D02*
Y272333D01*
G01Y271583D02*
X438617Y272000D01*
X439033Y272250D01*
X439700Y272333D01*
X440283Y272250D01*
X440867Y271833D01*
X441117Y271250D01*
X441200Y270667D01*
X441117Y270083D01*
X440867Y269500D01*
X440367Y269167D01*
X439700Y269000D01*
X439117Y269083D01*
X438533Y269333D01*
X438200Y269667D01*
G01X446800Y269000D02*
Y272333D01*
G01Y271750D02*
X446467Y272083D01*
X445967Y272250D01*
X445383Y272333D01*
X444800Y272167D01*
X444300Y271833D01*
X443967Y271333D01*
X443800Y270667D01*
X443967Y270000D01*
X444300Y269500D01*
X444800Y269167D01*
X445383Y269000D01*
X445967Y269083D01*
X446467Y269333D01*
X446800Y269667D01*
G01X452400Y274000D02*
Y269000D01*
G01Y269750D02*
X452067Y269333D01*
X451567Y269083D01*
X450983Y269000D01*
X450317Y269167D01*
X449817Y269583D01*
X449483Y270083D01*
X449400Y270667D01*
X449483Y271250D01*
X449817Y271750D01*
X450317Y272167D01*
X450983Y272333D01*
X451567Y272250D01*
X451983Y272083D01*
X452400Y271750D01*
G01X372833Y278000D02*
Y281333D01*
G01Y280667D02*
X373250Y281000D01*
X373667Y281250D01*
X374250Y281333D01*
X374667Y281250D01*
X375167Y281000D01*
G01X379600Y281333D02*
Y278000D01*
G01Y282667D02*
X379433Y282750D01*
Y282917D01*
X379600Y283000D01*
X379767Y282917D01*
Y282750D01*
X379600Y282667D01*
G01X383783Y278000D02*
Y281333D01*
G01Y280500D02*
X384117Y280917D01*
X384617Y281250D01*
X385283Y281333D01*
X385867Y281250D01*
X386367Y280917D01*
X386617Y280333D01*
Y278000D01*
G01X389633Y276750D02*
X390217Y276417D01*
X390883Y276333D01*
X391467Y276417D01*
X391967Y276833D01*
X392300Y277417D01*
Y281333D01*
G01Y280667D02*
X391967Y281000D01*
X391467Y281250D01*
X390883Y281333D01*
X390217Y281167D01*
X389800Y280833D01*
X389467Y280250D01*
X389300Y279667D01*
X389383Y279167D01*
X389717Y278583D01*
X390217Y278167D01*
X390883Y278000D01*
X391383Y278083D01*
X391967Y278417D01*
X392300Y278750D01*
G01X400750Y278583D02*
X401167Y278250D01*
X401750Y278000D01*
X402250D01*
X402750Y278167D01*
X403083Y278417D01*
X403250Y278750D01*
X403167Y279250D01*
X402833Y279500D01*
X401333Y280000D01*
X401000Y280583D01*
X401167Y281000D01*
X401500Y281250D01*
X402000Y281333D01*
X402500Y281250D01*
X403000Y281000D01*
G01X407600Y281333D02*
Y278000D01*
G01Y282667D02*
X407433Y282750D01*
Y282917D01*
X407600Y283000D01*
X407767Y282917D01*
Y282750D01*
X407600Y282667D01*
G01X411950Y281333D02*
X414450D01*
X411950Y278000D01*
X414450D01*
G01X417550Y280250D02*
X420217D01*
X419967Y280833D01*
X419550Y281167D01*
X418967Y281333D01*
X418383Y281250D01*
X417883Y281000D01*
X417550Y280417D01*
X417383Y279917D01*
Y279417D01*
X417550Y278917D01*
X417967Y278417D01*
X418467Y278083D01*
X419050Y278000D01*
X419633Y278167D01*
X420217Y278667D01*
G01X429833Y277083D02*
X430167Y278167D01*
G01X371417Y290333D02*
X372417Y287000D01*
X373500Y290333D01*
X374583Y287000D01*
X375583Y290333D01*
G01X377683Y287000D02*
Y292000D01*
G01Y289583D02*
X378100Y290000D01*
X378517Y290250D01*
X379183Y290333D01*
X379683Y290250D01*
X380267Y289917D01*
X380517Y289417D01*
Y287000D01*
G01X384700Y290333D02*
Y287000D01*
G01Y291667D02*
X384533Y291750D01*
Y291917D01*
X384700Y292000D01*
X384867Y291917D01*
Y291750D01*
X384700Y291667D01*
G01X391633Y289917D02*
X391050Y290250D01*
X390550Y290333D01*
X389883Y290167D01*
X389383Y289833D01*
X389050Y289250D01*
X388967Y288667D01*
X389050Y288083D01*
X389383Y287583D01*
X389883Y287167D01*
X390550Y287000D01*
X391133Y287167D01*
X391633Y287500D01*
G01X394483Y287000D02*
Y292000D01*
G01Y289583D02*
X394900Y290000D01*
X395317Y290250D01*
X395983Y290333D01*
X396483Y290250D01*
X397067Y289917D01*
X397317Y289417D01*
Y287000D01*
G01X405850Y287583D02*
X406267Y287250D01*
X406850Y287000D01*
X407350D01*
X407850Y287167D01*
X408183Y287417D01*
X408350Y287750D01*
X408267Y288250D01*
X407933Y288500D01*
X406433Y289000D01*
X406100Y289583D01*
X406267Y290000D01*
X406600Y290250D01*
X407100Y290333D01*
X407600Y290250D01*
X408100Y290000D01*
G01X412700Y290333D02*
Y287000D01*
G01Y291667D02*
X412533Y291750D01*
Y291917D01*
X412700Y292000D01*
X412867Y291917D01*
Y291750D01*
X412700Y291667D01*
G01X417050Y290333D02*
X419550D01*
X417050Y287000D01*
X419550D01*
G01X422650Y289250D02*
X425317D01*
X425067Y289833D01*
X424650Y290167D01*
X424067Y290333D01*
X423483Y290250D01*
X422983Y290000D01*
X422650Y289417D01*
X422483Y288917D01*
Y288417D01*
X422650Y287917D01*
X423067Y287417D01*
X423567Y287083D01*
X424150Y287000D01*
X424733Y287167D01*
X425317Y287667D01*
G01X435100Y290333D02*
Y287000D01*
G01Y291667D02*
X434933Y291750D01*
Y291917D01*
X435100Y292000D01*
X435267Y291917D01*
Y291750D01*
X435100Y291667D01*
G01X439450Y287583D02*
X439867Y287250D01*
X440450Y287000D01*
X440950D01*
X441450Y287167D01*
X441783Y287417D01*
X441950Y287750D01*
X441867Y288250D01*
X441533Y288500D01*
X440033Y289000D01*
X439700Y289583D01*
X439867Y290000D01*
X440200Y290250D01*
X440700Y290333D01*
X441200Y290250D01*
X441700Y290000D01*
G01X450400Y287000D02*
Y292000D01*
G01Y289500D02*
X450817Y290000D01*
X451317Y290250D01*
X451817Y290333D01*
X452567Y290167D01*
X453067Y289833D01*
X453400Y289250D01*
Y288583D01*
X453233Y287917D01*
X452900Y287417D01*
X452317Y287083D01*
X451817Y287000D01*
X451317Y287083D01*
X450817Y287333D01*
X450400Y287750D01*
G01X457500Y290333D02*
Y287000D01*
G01Y291667D02*
X457333Y291750D01*
Y291917D01*
X457500Y292000D01*
X457667Y291917D01*
Y291750D01*
X457500Y291667D01*
G01X461933Y285750D02*
X462517Y285417D01*
X463183Y285333D01*
X463767Y285417D01*
X464267Y285833D01*
X464600Y286417D01*
Y290333D01*
G01Y289667D02*
X464267Y290000D01*
X463767Y290250D01*
X463183Y290333D01*
X462517Y290167D01*
X462100Y289833D01*
X461767Y289250D01*
X461600Y288667D01*
X461683Y288167D01*
X462017Y287583D01*
X462517Y287167D01*
X463183Y287000D01*
X463683Y287083D01*
X464267Y287417D01*
X464600Y287750D01*
G01X467533Y285750D02*
X468117Y285417D01*
X468783Y285333D01*
X469367Y285417D01*
X469867Y285833D01*
X470200Y286417D01*
Y290333D01*
G01Y289667D02*
X469867Y290000D01*
X469367Y290250D01*
X468783Y290333D01*
X468117Y290167D01*
X467700Y289833D01*
X467367Y289250D01*
X467200Y288667D01*
X467283Y288167D01*
X467617Y287583D01*
X468117Y287167D01*
X468783Y287000D01*
X469283Y287083D01*
X469867Y287417D01*
X470200Y287750D01*
G01X473050Y289250D02*
X475717D01*
X475467Y289833D01*
X475050Y290167D01*
X474467Y290333D01*
X473883Y290250D01*
X473383Y290000D01*
X473050Y289417D01*
X472883Y288917D01*
Y288417D01*
X473050Y287917D01*
X473467Y287417D01*
X473967Y287083D01*
X474550Y287000D01*
X475133Y287167D01*
X475717Y287667D01*
G01X478733Y287000D02*
Y290333D01*
G01Y289667D02*
X479150Y290000D01*
X479567Y290250D01*
X480150Y290333D01*
X480567Y290250D01*
X481067Y290000D01*
G01X491100Y292000D02*
Y287000D01*
G01X489933Y290333D02*
X492267D01*
G01X495283Y287000D02*
Y292000D01*
G01Y289583D02*
X495700Y290000D01*
X496117Y290250D01*
X496783Y290333D01*
X497283Y290250D01*
X497867Y289917D01*
X498117Y289417D01*
Y287000D01*
G01X503800D02*
Y290333D01*
G01Y289750D02*
X503467Y290083D01*
X502967Y290250D01*
X502383Y290333D01*
X501800Y290167D01*
X501300Y289833D01*
X500967Y289333D01*
X500800Y288667D01*
X500967Y288000D01*
X501300Y287500D01*
X501800Y287167D01*
X502383Y287000D01*
X502967Y287083D01*
X503467Y287333D01*
X503800Y287667D01*
G01X506483Y287000D02*
Y290333D01*
G01Y289500D02*
X506817Y289917D01*
X507317Y290250D01*
X507983Y290333D01*
X508567Y290250D01*
X509067Y289917D01*
X509317Y289333D01*
Y287000D01*
G01X520600D02*
Y290333D01*
G01Y289750D02*
X520267Y290083D01*
X519767Y290250D01*
X519183Y290333D01*
X518600Y290167D01*
X518100Y289833D01*
X517767Y289333D01*
X517600Y288667D01*
X517767Y288000D01*
X518100Y287500D01*
X518600Y287167D01*
X519183Y287000D01*
X519767Y287083D01*
X520267Y287333D01*
X520600Y287667D01*
G01X523283Y287000D02*
Y290333D01*
G01Y289500D02*
X523617Y289917D01*
X524117Y290250D01*
X524783Y290333D01*
X525367Y290250D01*
X525867Y289917D01*
X526117Y289333D01*
Y287000D01*
G01X528883D02*
Y290333D01*
G01Y289500D02*
X529217Y289917D01*
X529717Y290250D01*
X530383Y290333D01*
X530967Y290250D01*
X531467Y289917D01*
X531717Y289333D01*
Y287000D01*
G01X534483Y290333D02*
Y288000D01*
X534817Y287417D01*
X535317Y287083D01*
X535900Y287000D01*
X536483Y287083D01*
X536983Y287417D01*
X537317Y288000D01*
G01Y287000D02*
Y290333D01*
G01X543000Y287000D02*
Y290333D01*
G01Y289750D02*
X542667Y290083D01*
X542167Y290250D01*
X541583Y290333D01*
X541000Y290167D01*
X540500Y289833D01*
X540167Y289333D01*
X540000Y288667D01*
X540167Y288000D01*
X540500Y287500D01*
X541000Y287167D01*
X541583Y287000D01*
X542167Y287083D01*
X542667Y287333D01*
X543000Y287667D01*
G01X547100Y287000D02*
Y292000D01*
G01X384583Y461500D02*
Y466500D01*
G01Y464083D02*
X385000Y464500D01*
X385417Y464750D01*
X386083Y464833D01*
X386583Y464750D01*
X387167Y464417D01*
X387417Y463917D01*
Y461500D01*
G01X393100D02*
Y464833D01*
G01Y464250D02*
X392767Y464583D01*
X392267Y464750D01*
X391683Y464833D01*
X391100Y464667D01*
X390600Y464333D01*
X390267Y463833D01*
X390100Y463167D01*
X390267Y462500D01*
X390600Y462000D01*
X391100Y461667D01*
X391683Y461500D01*
X392267Y461583D01*
X392767Y461833D01*
X393100Y462167D01*
G01X397200Y461500D02*
Y466500D01*
G01X402300Y461500D02*
Y465750D01*
X402467Y466167D01*
X402800Y466417D01*
X403300Y466500D01*
X403800Y466333D01*
X404050Y465917D01*
G01X403050Y464500D02*
X401383D01*
G01X412500Y459833D02*
Y464833D01*
G01Y464083D02*
X412917Y464500D01*
X413333Y464750D01*
X414000Y464833D01*
X414583Y464750D01*
X415167Y464333D01*
X415417Y463750D01*
X415500Y463167D01*
X415417Y462583D01*
X415167Y462000D01*
X414667Y461667D01*
X414000Y461500D01*
X413417Y461583D01*
X412833Y461833D01*
X412500Y462167D01*
G01X419600Y461500D02*
Y466500D01*
G01X423783Y464833D02*
Y462500D01*
X424117Y461917D01*
X424617Y461583D01*
X425200Y461500D01*
X425783Y461583D01*
X426283Y461917D01*
X426617Y462500D01*
G01Y461500D02*
Y464833D01*
G01X429633Y460250D02*
X430217Y459917D01*
X430883Y459833D01*
X431467Y459917D01*
X431967Y460333D01*
X432300Y460917D01*
Y464833D01*
G01Y464167D02*
X431967Y464500D01*
X431467Y464750D01*
X430883Y464833D01*
X430217Y464667D01*
X429800Y464333D01*
X429467Y463750D01*
X429300Y463167D01*
X429383Y462667D01*
X429717Y462083D01*
X430217Y461667D01*
X430883Y461500D01*
X431383Y461583D01*
X431967Y461917D01*
X432300Y462250D01*
G01X435233Y460250D02*
X435817Y459917D01*
X436483Y459833D01*
X437067Y459917D01*
X437567Y460333D01*
X437900Y460917D01*
Y464833D01*
G01Y464167D02*
X437567Y464500D01*
X437067Y464750D01*
X436483Y464833D01*
X435817Y464667D01*
X435400Y464333D01*
X435067Y463750D01*
X434900Y463167D01*
X434983Y462667D01*
X435317Y462083D01*
X435817Y461667D01*
X436483Y461500D01*
X436983Y461583D01*
X437567Y461917D01*
X437900Y462250D01*
G01X442000Y464833D02*
Y461500D01*
G01Y466167D02*
X441833Y466250D01*
Y466417D01*
X442000Y466500D01*
X442167Y466417D01*
Y466250D01*
X442000Y466167D01*
G01X446183Y461500D02*
Y464833D01*
G01Y464000D02*
X446517Y464417D01*
X447017Y464750D01*
X447683Y464833D01*
X448267Y464750D01*
X448767Y464417D01*
X449017Y463833D01*
Y461500D01*
G01X452033Y460250D02*
X452617Y459917D01*
X453283Y459833D01*
X453867Y459917D01*
X454367Y460333D01*
X454700Y460917D01*
Y464833D01*
G01Y464167D02*
X454367Y464500D01*
X453867Y464750D01*
X453283Y464833D01*
X452617Y464667D01*
X452200Y464333D01*
X451867Y463750D01*
X451700Y463167D01*
X451783Y462667D01*
X452117Y462083D01*
X452617Y461667D01*
X453283Y461500D01*
X453783Y461583D01*
X454367Y461917D01*
X454700Y462250D01*
G01X409750Y-121000D02*
Y-116000D01*
G01X413250D02*
Y-121000D01*
G01Y-118500D02*
X409750D01*
G01X417100Y-121000D02*
X416433Y-120917D01*
X415850Y-120583D01*
X415350Y-120083D01*
X415017Y-119500D01*
X414850Y-118833D01*
Y-118167D01*
X415017Y-117500D01*
X415350Y-116917D01*
X415850Y-116417D01*
X416433Y-116083D01*
X417100Y-116000D01*
X417767Y-116083D01*
X418350Y-116417D01*
X418850Y-116917D01*
X419183Y-117500D01*
X419350Y-118167D01*
Y-118833D01*
X419183Y-119500D01*
X418850Y-120083D01*
X418350Y-120583D01*
X417767Y-120917D01*
X417100Y-121000D01*
G01X421033Y-116000D02*
Y-121000D01*
X424367D01*
G01X429967D02*
X426633D01*
Y-116000D01*
X429967D01*
G01X428633Y-118417D02*
X426633D01*
G01X453800Y-121000D02*
Y-117667D01*
G01Y-118583D02*
X454050Y-118167D01*
X454467Y-117833D01*
X455050Y-117667D01*
X455633Y-117833D01*
X456050Y-118167D01*
X456300Y-118583D01*
Y-121000D01*
G01Y-118583D02*
X456550Y-118167D01*
X456967Y-117833D01*
X457550Y-117667D01*
X458133Y-117833D01*
X458550Y-118167D01*
X458800Y-118667D01*
Y-121000D01*
G01X461900Y-117667D02*
Y-121000D01*
G01Y-116333D02*
X461733Y-116250D01*
Y-116083D01*
X461900Y-116000D01*
X462067Y-116083D01*
Y-116250D01*
X461900Y-116333D01*
G01X467500Y-121000D02*
Y-116000D01*
G01X471850Y-120417D02*
X472267Y-120750D01*
X472850Y-121000D01*
X473350D01*
X473850Y-120833D01*
X474183Y-120583D01*
X474350Y-120250D01*
X474267Y-119750D01*
X473933Y-119500D01*
X472433Y-119000D01*
X472100Y-118417D01*
X472267Y-118000D01*
X472600Y-117750D01*
X473100Y-117667D01*
X473600Y-117750D01*
X474100Y-118000D01*
G01X478283Y-122667D02*
X477450Y-121833D01*
X477033Y-121000D01*
Y-117667D01*
X477450Y-116833D01*
X478283Y-116000D01*
G01X482633Y-121000D02*
Y-116000D01*
X484633D01*
X485300Y-116250D01*
X485800Y-116833D01*
X485967Y-117500D01*
X485800Y-118167D01*
X485383Y-118667D01*
X484633Y-118917D01*
X482633D01*
G01X489900Y-116000D02*
Y-121000D01*
G01X487983Y-116000D02*
X491817D01*
G01X493750Y-121000D02*
Y-116000D01*
G01X497250D02*
Y-121000D01*
G01Y-118500D02*
X493750D01*
G01X501517Y-122667D02*
X502350Y-121833D01*
X502767Y-121000D01*
Y-117667D01*
X502350Y-116833D01*
X501517Y-116000D01*
G01X409667Y35167D02*
X410000Y35417D01*
X410250Y35833D01*
X410417Y36417D01*
X410250Y36917D01*
X409917Y37250D01*
X409333Y37500D01*
X407083D01*
Y32500D01*
X409833D01*
X410417Y32833D01*
X410750Y33333D01*
X410917Y33917D01*
X410750Y34500D01*
X410250Y35000D01*
X409667Y35167D01*
X407083D01*
G01X412517Y32500D02*
X414600Y37500D01*
X416683Y32500D01*
G01X415933Y34250D02*
X413267D01*
G01X422033Y37083D02*
X421533Y37333D01*
X420950Y37500D01*
X420283D01*
X419533Y37250D01*
X418950Y36833D01*
X418533Y36333D01*
X418200Y35500D01*
X418117Y34750D01*
X418283Y34000D01*
X418533Y33500D01*
X419033Y33000D01*
X419617Y32667D01*
X420200Y32500D01*
X420783D01*
X421367Y32667D01*
X421867Y32917D01*
X422283Y33250D01*
G01X423967Y32500D02*
Y37500D01*
G01X427133D02*
X423967Y34417D01*
G01X427633Y32500D02*
X425383Y35833D01*
G01X435167Y32500D02*
Y37500D01*
X436833D01*
X437500Y37250D01*
X438000Y36917D01*
X438417Y36417D01*
X438750Y35833D01*
X438833Y35000D01*
X438750Y34167D01*
X438417Y33583D01*
X438000Y33083D01*
X437500Y32750D01*
X436833Y32500D01*
X435167D01*
G01X440933D02*
Y37500D01*
X443017D01*
X443683Y37250D01*
X444100Y36917D01*
X444267Y36250D01*
X444100Y35583D01*
X443600Y35167D01*
X443017Y34917D01*
X440933D01*
G01X443017D02*
X444267Y32500D01*
G01X447200Y37500D02*
X449200D01*
G01X448200D02*
Y32500D01*
G01X447200D02*
X449200D01*
G01X452133Y37500D02*
Y32500D01*
X455467D01*
G01X457733Y37500D02*
Y32500D01*
X461067D01*
G01X484900D02*
Y35833D01*
G01Y34917D02*
X485150Y35333D01*
X485567Y35667D01*
X486150Y35833D01*
X486733Y35667D01*
X487150Y35333D01*
X487400Y34917D01*
Y32500D01*
G01Y34917D02*
X487650Y35333D01*
X488067Y35667D01*
X488650Y35833D01*
X489233Y35667D01*
X489650Y35333D01*
X489900Y34833D01*
Y32500D01*
G01X493000Y35833D02*
Y32500D01*
G01Y37167D02*
X492833Y37250D01*
Y37417D01*
X493000Y37500D01*
X493167Y37417D01*
Y37250D01*
X493000Y37167D01*
G01X498600Y32500D02*
Y37500D01*
G01X502950Y33083D02*
X503367Y32750D01*
X503950Y32500D01*
X504450D01*
X504950Y32667D01*
X505283Y32917D01*
X505450Y33250D01*
X505367Y33750D01*
X505033Y34000D01*
X503533Y34500D01*
X503200Y35083D01*
X503367Y35500D01*
X503700Y35750D01*
X504200Y35833D01*
X504700Y35750D01*
X505200Y35500D01*
G01X509383Y30833D02*
X508550Y31667D01*
X508133Y32500D01*
Y35833D01*
X508550Y36667D01*
X509383Y37500D01*
G01X513483Y32500D02*
Y37500D01*
X517317Y32500D01*
Y37500D01*
G01X519333Y32500D02*
Y37500D01*
X521333D01*
X522000Y37250D01*
X522500Y36667D01*
X522667Y36000D01*
X522500Y35333D01*
X522083Y34833D01*
X521333Y34583D01*
X519333D01*
G01X526600Y37500D02*
Y32500D01*
G01X524683Y37500D02*
X528517D01*
G01X530450Y32500D02*
Y37500D01*
G01X533950D02*
Y32500D01*
G01Y35000D02*
X530450D01*
G01X538217Y30833D02*
X539050Y31667D01*
X539467Y32500D01*
Y35833D01*
X539050Y36667D01*
X538217Y37500D01*
G01X419500Y318500D02*
X421167D01*
Y317000D01*
X420667Y316500D01*
X420083Y316167D01*
X419250Y316000D01*
X418417Y316167D01*
X417833Y316500D01*
X417333Y317000D01*
X417000Y317583D01*
X416833Y318250D01*
Y318833D01*
X417000Y319333D01*
X417333Y319917D01*
X417833Y320417D01*
X418333Y320750D01*
X419000Y321000D01*
X419583D01*
X420250Y320833D01*
X420750Y320500D01*
G01X423350Y318250D02*
X426017D01*
X425767Y318833D01*
X425350Y319167D01*
X424767Y319333D01*
X424183Y319250D01*
X423683Y319000D01*
X423350Y318417D01*
X423183Y317917D01*
Y317417D01*
X423350Y316917D01*
X423767Y316417D01*
X424267Y316083D01*
X424850Y316000D01*
X425433Y316167D01*
X426017Y316667D01*
G01X429033Y316000D02*
Y319333D01*
G01Y318667D02*
X429450Y319000D01*
X429867Y319250D01*
X430450Y319333D01*
X430867Y319250D01*
X431367Y319000D01*
G01X434300Y316000D02*
Y321000D01*
G01Y318500D02*
X434717Y319000D01*
X435217Y319250D01*
X435717Y319333D01*
X436467Y319167D01*
X436967Y318833D01*
X437300Y318250D01*
Y317583D01*
X437133Y316917D01*
X436800Y316417D01*
X436217Y316083D01*
X435717Y316000D01*
X435217Y316083D01*
X434717Y316333D01*
X434300Y316750D01*
G01X440150Y318250D02*
X442817D01*
X442567Y318833D01*
X442150Y319167D01*
X441567Y319333D01*
X440983Y319250D01*
X440483Y319000D01*
X440150Y318417D01*
X439983Y317917D01*
Y317417D01*
X440150Y316917D01*
X440567Y316417D01*
X441067Y316083D01*
X441650Y316000D01*
X442233Y316167D01*
X442817Y316667D01*
G01X445833Y316000D02*
Y319333D01*
G01Y318667D02*
X446250Y319000D01*
X446667Y319250D01*
X447250Y319333D01*
X447667Y319250D01*
X448167Y319000D01*
G01X459700Y321000D02*
Y316000D01*
G01Y316750D02*
X459367Y316333D01*
X458867Y316083D01*
X458283Y316000D01*
X457617Y316167D01*
X457117Y316583D01*
X456783Y317083D01*
X456700Y317667D01*
X456783Y318250D01*
X457117Y318750D01*
X457617Y319167D01*
X458283Y319333D01*
X458867Y319250D01*
X459283Y319083D01*
X459700Y318750D01*
G01X462550Y318250D02*
X465217D01*
X464967Y318833D01*
X464550Y319167D01*
X463967Y319333D01*
X463383Y319250D01*
X462883Y319000D01*
X462550Y318417D01*
X462383Y317917D01*
Y317417D01*
X462550Y316917D01*
X462967Y316417D01*
X463467Y316083D01*
X464050Y316000D01*
X464633Y316167D01*
X465217Y316667D01*
G01X468150Y316583D02*
X468567Y316250D01*
X469150Y316000D01*
X469650D01*
X470150Y316167D01*
X470483Y316417D01*
X470650Y316750D01*
X470567Y317250D01*
X470233Y317500D01*
X468733Y318000D01*
X468400Y318583D01*
X468567Y319000D01*
X468900Y319250D01*
X469400Y319333D01*
X469900Y319250D01*
X470400Y319000D01*
G01X475000Y319333D02*
Y316000D01*
G01Y320667D02*
X474833Y320750D01*
Y320917D01*
X475000Y321000D01*
X475167Y320917D01*
Y320750D01*
X475000Y320667D01*
G01X479433Y314750D02*
X480017Y314417D01*
X480683Y314333D01*
X481267Y314417D01*
X481767Y314833D01*
X482100Y315417D01*
Y319333D01*
G01Y318667D02*
X481767Y319000D01*
X481267Y319250D01*
X480683Y319333D01*
X480017Y319167D01*
X479600Y318833D01*
X479267Y318250D01*
X479100Y317667D01*
X479183Y317167D01*
X479517Y316583D01*
X480017Y316167D01*
X480683Y316000D01*
X481183Y316083D01*
X481767Y316417D01*
X482100Y316750D01*
G01X484783Y316000D02*
Y319333D01*
G01Y318500D02*
X485117Y318917D01*
X485617Y319250D01*
X486283Y319333D01*
X486867Y319250D01*
X487367Y318917D01*
X487617Y318333D01*
Y316000D01*
G01X430767Y76073D02*
X434433Y79740D01*
G01X432600Y80407D02*
Y75407D01*
G01X434433Y76073D02*
X430767Y79740D01*
G01X430100Y77907D02*
X435100D01*
G01X437783Y74573D02*
X436950Y75407D01*
X436533Y76240D01*
Y79573D01*
X436950Y80407D01*
X437783Y81240D01*
G01X441967Y76990D02*
X442467Y76573D01*
X443050Y76323D01*
X443800Y76240D01*
X444550Y76407D01*
X445133Y76740D01*
X445550Y77323D01*
X445633Y77990D01*
X445467Y78657D01*
X445050Y79073D01*
X444467Y79407D01*
X443883Y79490D01*
X443300Y79407D01*
X442550Y79073D01*
X442800Y81240D01*
X445050D01*
G01X449400Y76073D02*
X449233Y76157D01*
Y76323D01*
X449400Y76407D01*
X449567Y76323D01*
Y76157D01*
X449400Y76073D01*
G01X455000Y76240D02*
Y81240D01*
X454000Y80240D01*
G01Y76240D02*
X456000D01*
G01X461017Y74573D02*
X461850Y75407D01*
X462267Y76240D01*
Y79573D01*
X461850Y80407D01*
X461017Y81240D01*
G01X435500Y283000D02*
Y278000D01*
G01X434333Y281333D02*
X436667D01*
G01X439683Y278000D02*
Y283000D01*
G01Y280583D02*
X440100Y281000D01*
X440517Y281250D01*
X441183Y281333D01*
X441683Y281250D01*
X442267Y280917D01*
X442517Y280417D01*
Y278000D01*
G01X445450Y280250D02*
X448117D01*
X447867Y280833D01*
X447450Y281167D01*
X446867Y281333D01*
X446283Y281250D01*
X445783Y281000D01*
X445450Y280417D01*
X445283Y279917D01*
Y279417D01*
X445450Y278917D01*
X445867Y278417D01*
X446367Y278083D01*
X446950Y278000D01*
X447533Y278167D01*
X448117Y278667D01*
G01X457900Y278000D02*
X457400Y278083D01*
X456900Y278417D01*
X456567Y279000D01*
X456400Y279667D01*
X456567Y280333D01*
X456900Y280917D01*
X457400Y281250D01*
X457900Y281333D01*
X458400Y281250D01*
X458900Y280917D01*
X459233Y280333D01*
X459317Y279667D01*
X459233Y279000D01*
X458900Y278417D01*
X458400Y278083D01*
X457900Y278000D01*
G01X463500Y283000D02*
Y278000D01*
G01X462333Y281333D02*
X464667D01*
G01X467683Y278000D02*
Y283000D01*
G01Y280583D02*
X468100Y281000D01*
X468517Y281250D01*
X469183Y281333D01*
X469683Y281250D01*
X470267Y280917D01*
X470517Y280417D01*
Y278000D01*
G01X473450Y280250D02*
X476117D01*
X475867Y280833D01*
X475450Y281167D01*
X474867Y281333D01*
X474283Y281250D01*
X473783Y281000D01*
X473450Y280417D01*
X473283Y279917D01*
Y279417D01*
X473450Y278917D01*
X473867Y278417D01*
X474367Y278083D01*
X474950Y278000D01*
X475533Y278167D01*
X476117Y278667D01*
G01X479133Y278000D02*
Y281333D01*
G01Y280667D02*
X479550Y281000D01*
X479967Y281250D01*
X480550Y281333D01*
X480967Y281250D01*
X481467Y281000D01*
G01X490250Y278583D02*
X490667Y278250D01*
X491250Y278000D01*
X491750D01*
X492250Y278167D01*
X492583Y278417D01*
X492750Y278750D01*
X492667Y279250D01*
X492333Y279500D01*
X490833Y280000D01*
X490500Y280583D01*
X490667Y281000D01*
X491000Y281250D01*
X491500Y281333D01*
X492000Y281250D01*
X492500Y281000D01*
G01X497100Y281333D02*
Y278000D01*
G01Y282667D02*
X496933Y282750D01*
Y282917D01*
X497100Y283000D01*
X497267Y282917D01*
Y282750D01*
X497100Y282667D01*
G01X504200Y283000D02*
Y278000D01*
G01Y278750D02*
X503867Y278333D01*
X503367Y278083D01*
X502783Y278000D01*
X502117Y278167D01*
X501617Y278583D01*
X501283Y279083D01*
X501200Y279667D01*
X501283Y280250D01*
X501617Y280750D01*
X502117Y281167D01*
X502783Y281333D01*
X503367Y281250D01*
X503783Y281083D01*
X504200Y280750D01*
G01X507050Y280250D02*
X509717D01*
X509467Y280833D01*
X509050Y281167D01*
X508467Y281333D01*
X507883Y281250D01*
X507383Y281000D01*
X507050Y280417D01*
X506883Y279917D01*
Y279417D01*
X507050Y278917D01*
X507467Y278417D01*
X507967Y278083D01*
X508550Y278000D01*
X509133Y278167D01*
X509717Y278667D01*
G01X517417Y281333D02*
X518417Y278000D01*
X519500Y281333D01*
X520583Y278000D01*
X521583Y281333D01*
G01X525100D02*
Y278000D01*
G01Y282667D02*
X524933Y282750D01*
Y282917D01*
X525100Y283000D01*
X525267Y282917D01*
Y282750D01*
X525100Y282667D01*
G01X530700Y283000D02*
Y278000D01*
G01X529533Y281333D02*
X531867D01*
G01X534883Y278000D02*
Y283000D01*
G01Y280583D02*
X535300Y281000D01*
X535717Y281250D01*
X536383Y281333D01*
X536883Y281250D01*
X537467Y280917D01*
X537717Y280417D01*
Y278000D01*
G01X541900D02*
X541400Y278083D01*
X540900Y278417D01*
X540567Y279000D01*
X540400Y279667D01*
X540567Y280333D01*
X540900Y280917D01*
X541400Y281250D01*
X541900Y281333D01*
X542400Y281250D01*
X542900Y280917D01*
X543233Y280333D01*
X543317Y279667D01*
X543233Y279000D01*
X542900Y278417D01*
X542400Y278083D01*
X541900Y278000D01*
G01X546083Y281333D02*
Y279000D01*
X546417Y278417D01*
X546917Y278083D01*
X547500Y278000D01*
X548083Y278083D01*
X548583Y278417D01*
X548917Y279000D01*
G01Y278000D02*
Y281333D01*
G01X553100Y283000D02*
Y278000D01*
G01X551933Y281333D02*
X554267D01*
G01X450500Y-205500D02*
Y-200500D01*
X447417Y-204083D01*
X451583D01*
G01X453267Y-204750D02*
X453767Y-205167D01*
X454350Y-205417D01*
X455100Y-205500D01*
X455850Y-205333D01*
X456433Y-205000D01*
X456850Y-204417D01*
X456933Y-203750D01*
X456767Y-203083D01*
X456350Y-202667D01*
X455767Y-202333D01*
X455183Y-202250D01*
X454600Y-202333D01*
X453850Y-202667D01*
X454100Y-200500D01*
X456350D01*
G01X450750Y-88917D02*
X451167Y-89250D01*
X451750Y-89500D01*
X452250D01*
X452750Y-89333D01*
X453083Y-89083D01*
X453250Y-88750D01*
X453167Y-88250D01*
X452833Y-88000D01*
X451333Y-87500D01*
X451000Y-86917D01*
X451167Y-86500D01*
X451500Y-86250D01*
X452000Y-86167D01*
X452500Y-86250D01*
X453000Y-86500D01*
G01X457600Y-84500D02*
Y-89500D01*
G01X456433Y-86167D02*
X458767D01*
G01X461783D02*
Y-88500D01*
X462117Y-89083D01*
X462617Y-89417D01*
X463200Y-89500D01*
X463783Y-89417D01*
X464283Y-89083D01*
X464617Y-88500D01*
G01Y-89500D02*
Y-86167D01*
G01X467300Y-89500D02*
Y-84500D01*
G01Y-87000D02*
X467717Y-86500D01*
X468217Y-86250D01*
X468717Y-86167D01*
X469467Y-86333D01*
X469967Y-86667D01*
X470300Y-87250D01*
Y-87917D01*
X470133Y-88583D01*
X469800Y-89083D01*
X469217Y-89417D01*
X468717Y-89500D01*
X468217Y-89417D01*
X467717Y-89167D01*
X467300Y-88750D01*
G01X480000Y-89500D02*
Y-84500D01*
G01X484350Y-87250D02*
X487017D01*
X486767Y-86667D01*
X486350Y-86333D01*
X485767Y-86167D01*
X485183Y-86250D01*
X484683Y-86500D01*
X484350Y-87083D01*
X484183Y-87583D01*
Y-88083D01*
X484350Y-88583D01*
X484767Y-89083D01*
X485267Y-89417D01*
X485850Y-89500D01*
X486433Y-89333D01*
X487017Y-88833D01*
G01X489783Y-89500D02*
Y-86167D01*
G01Y-87000D02*
X490117Y-86583D01*
X490617Y-86250D01*
X491283Y-86167D01*
X491867Y-86250D01*
X492367Y-86583D01*
X492617Y-87167D01*
Y-89500D01*
G01X495633Y-90750D02*
X496217Y-91083D01*
X496883Y-91167D01*
X497467Y-91083D01*
X497967Y-90667D01*
X498300Y-90083D01*
Y-86167D01*
G01Y-86833D02*
X497967Y-86500D01*
X497467Y-86250D01*
X496883Y-86167D01*
X496217Y-86333D01*
X495800Y-86667D01*
X495467Y-87250D01*
X495300Y-87833D01*
X495383Y-88333D01*
X495717Y-88917D01*
X496217Y-89333D01*
X496883Y-89500D01*
X497383Y-89417D01*
X497967Y-89083D01*
X498300Y-88750D01*
G01X502400Y-84500D02*
Y-89500D01*
G01X501233Y-86167D02*
X503567D01*
G01X506583Y-89500D02*
Y-84500D01*
G01Y-86917D02*
X507000Y-86500D01*
X507417Y-86250D01*
X508083Y-86167D01*
X508583Y-86250D01*
X509167Y-86583D01*
X509417Y-87083D01*
Y-89500D01*
G01X512517Y-88583D02*
X514683D01*
G01Y-87083D02*
X512517D01*
G01X517617Y-87417D02*
X518200Y-86833D01*
X518700Y-86500D01*
X519367Y-86333D01*
X519950Y-86500D01*
X520367Y-86833D01*
X520700Y-87333D01*
X520783Y-87917D01*
X520700Y-88417D01*
X520367Y-88917D01*
X519867Y-89333D01*
X519283Y-89500D01*
X518617Y-89333D01*
X518033Y-88833D01*
X517700Y-88083D01*
X517617Y-87250D01*
X517783Y-86167D01*
X518033Y-85583D01*
X518450Y-85000D01*
X519033Y-84583D01*
X519617Y-84500D01*
X520200Y-84667D01*
X520617Y-85083D01*
G01X523883Y-87833D02*
X525883D01*
G01X524800Y-86750D02*
Y-88917D01*
G01X528900Y-89667D02*
X531900Y-84500D01*
G01X534917Y-87833D02*
X537083D01*
G01X539767Y-88750D02*
X540267Y-89167D01*
X540850Y-89417D01*
X541600Y-89500D01*
X542350Y-89333D01*
X542933Y-89000D01*
X543350Y-88417D01*
X543433Y-87750D01*
X543267Y-87083D01*
X542850Y-86667D01*
X542267Y-86333D01*
X541683Y-86250D01*
X541100Y-86333D01*
X540350Y-86667D01*
X540600Y-84500D01*
X542850D01*
G01X544700Y-89500D02*
Y-86167D01*
G01Y-87083D02*
X544950Y-86667D01*
X545367Y-86333D01*
X545950Y-86167D01*
X546533Y-86333D01*
X546950Y-86667D01*
X547200Y-87083D01*
Y-89500D01*
G01Y-87083D02*
X547450Y-86667D01*
X547867Y-86333D01*
X548450Y-86167D01*
X549033Y-86333D01*
X549450Y-86667D01*
X549700Y-87167D01*
Y-89500D01*
G01X552800Y-86167D02*
Y-89500D01*
G01Y-84833D02*
X552633Y-84750D01*
Y-84583D01*
X552800Y-84500D01*
X552967Y-84583D01*
Y-84750D01*
X552800Y-84833D01*
G01X558400Y-89500D02*
Y-84500D01*
G01X442333Y-58500D02*
Y-63500D01*
X445667D01*
G01X448183D02*
Y-60167D01*
G01Y-61000D02*
X448517Y-60583D01*
X449017Y-60250D01*
X449683Y-60167D01*
X450267Y-60250D01*
X450767Y-60583D01*
X451017Y-61167D01*
Y-63500D01*
G01X444333Y-17500D02*
Y-22500D01*
X447667D01*
G01X450350Y-19167D02*
X452850Y-22500D01*
G01Y-19167D02*
X450350Y-22500D01*
G01X470500Y461500D02*
Y465750D01*
X470667Y466167D01*
X471000Y466417D01*
X471500Y466500D01*
X472000Y466333D01*
X472250Y465917D01*
G01X471250Y464500D02*
X469583D01*
G01X475183Y464833D02*
Y462500D01*
X475517Y461917D01*
X476017Y461583D01*
X476600Y461500D01*
X477183Y461583D01*
X477683Y461917D01*
X478017Y462500D01*
G01Y461500D02*
Y464833D01*
G01X482200Y461500D02*
Y466500D01*
G01X487800Y461500D02*
Y466500D01*
G01X497500Y459833D02*
Y464833D01*
G01Y464083D02*
X497917Y464500D01*
X498333Y464750D01*
X499000Y464833D01*
X499583Y464750D01*
X500167Y464333D01*
X500417Y463750D01*
X500500Y463167D01*
X500417Y462583D01*
X500167Y462000D01*
X499667Y461667D01*
X499000Y461500D01*
X498417Y461583D01*
X497833Y461833D01*
X497500Y462167D01*
G01X504600Y461500D02*
Y466500D01*
G01X508783Y464833D02*
Y462500D01*
X509117Y461917D01*
X509617Y461583D01*
X510200Y461500D01*
X510783Y461583D01*
X511283Y461917D01*
X511617Y462500D01*
G01Y461500D02*
Y464833D01*
G01X514633Y460250D02*
X515217Y459917D01*
X515883Y459833D01*
X516467Y459917D01*
X516967Y460333D01*
X517300Y460917D01*
Y464833D01*
G01Y464167D02*
X516967Y464500D01*
X516467Y464750D01*
X515883Y464833D01*
X515217Y464667D01*
X514800Y464333D01*
X514467Y463750D01*
X514300Y463167D01*
X514383Y462667D01*
X514717Y462083D01*
X515217Y461667D01*
X515883Y461500D01*
X516383Y461583D01*
X516967Y461917D01*
X517300Y462250D01*
G01X520233Y460250D02*
X520817Y459917D01*
X521483Y459833D01*
X522067Y459917D01*
X522567Y460333D01*
X522900Y460917D01*
Y464833D01*
G01Y464167D02*
X522567Y464500D01*
X522067Y464750D01*
X521483Y464833D01*
X520817Y464667D01*
X520400Y464333D01*
X520067Y463750D01*
X519900Y463167D01*
X519983Y462667D01*
X520317Y462083D01*
X520817Y461667D01*
X521483Y461500D01*
X521983Y461583D01*
X522567Y461917D01*
X522900Y462250D01*
G01X527000Y464833D02*
Y461500D01*
G01Y466167D02*
X526833Y466250D01*
Y466417D01*
X527000Y466500D01*
X527167Y466417D01*
Y466250D01*
X527000Y466167D01*
G01X531183Y461500D02*
Y464833D01*
G01Y464000D02*
X531517Y464417D01*
X532017Y464750D01*
X532683Y464833D01*
X533267Y464750D01*
X533767Y464417D01*
X534017Y463833D01*
Y461500D01*
G01X537033Y460250D02*
X537617Y459917D01*
X538283Y459833D01*
X538867Y459917D01*
X539367Y460333D01*
X539700Y460917D01*
Y464833D01*
G01Y464167D02*
X539367Y464500D01*
X538867Y464750D01*
X538283Y464833D01*
X537617Y464667D01*
X537200Y464333D01*
X536867Y463750D01*
X536700Y463167D01*
X536783Y462667D01*
X537117Y462083D01*
X537617Y461667D01*
X538283Y461500D01*
X538783Y461583D01*
X539367Y461917D01*
X539700Y462250D01*
G01X470083Y-249917D02*
X470667Y-250333D01*
X471333Y-250500D01*
X472000Y-250333D01*
X472583Y-249833D01*
X473000Y-249083D01*
X473167Y-248333D01*
Y-247417D01*
X473000Y-246667D01*
X472583Y-246000D01*
X472083Y-245667D01*
X471500Y-245500D01*
X470833Y-245667D01*
X470333Y-246000D01*
X470000Y-246500D01*
X469833Y-247167D01*
X470000Y-247750D01*
X470417Y-248333D01*
X470917Y-248667D01*
X471500Y-248750D01*
X472167Y-248583D01*
X472667Y-248167D01*
X473167Y-247417D01*
G01X475517Y-248417D02*
X476100Y-247833D01*
X476600Y-247500D01*
X477267Y-247333D01*
X477850Y-247500D01*
X478267Y-247833D01*
X478600Y-248333D01*
X478683Y-248917D01*
X478600Y-249417D01*
X478267Y-249917D01*
X477767Y-250333D01*
X477183Y-250500D01*
X476517Y-250333D01*
X475933Y-249833D01*
X475600Y-249083D01*
X475517Y-248250D01*
X475683Y-247167D01*
X475933Y-246583D01*
X476350Y-246000D01*
X476933Y-245583D01*
X477517Y-245500D01*
X478100Y-245667D01*
X478517Y-246083D01*
G01X497500Y522980D02*
Y517980D01*
G01X495583Y522980D02*
X499417D01*
G01X501017Y521313D02*
X502017Y517980D01*
X503100Y521313D01*
X504183Y517980D01*
X505183Y521313D01*
G01X508700D02*
Y517980D01*
G01Y522647D02*
X508533Y522730D01*
Y522897D01*
X508700Y522980D01*
X508867Y522897D01*
Y522730D01*
X508700Y522647D01*
G01X513050Y518563D02*
X513467Y518230D01*
X514050Y517980D01*
X514550D01*
X515050Y518147D01*
X515383Y518397D01*
X515550Y518730D01*
X515467Y519230D01*
X515133Y519480D01*
X513633Y519980D01*
X513300Y520563D01*
X513467Y520980D01*
X513800Y521230D01*
X514300Y521313D01*
X514800Y521230D01*
X515300Y520980D01*
G01X519900Y522980D02*
Y517980D01*
G01X518733Y521313D02*
X521067D01*
G01X532600Y517980D02*
Y521313D01*
G01Y520730D02*
X532267Y521063D01*
X531767Y521230D01*
X531183Y521313D01*
X530600Y521147D01*
X530100Y520813D01*
X529767Y520313D01*
X529600Y519647D01*
X529767Y518980D01*
X530100Y518480D01*
X530600Y518147D01*
X531183Y517980D01*
X531767Y518063D01*
X532267Y518313D01*
X532600Y518647D01*
G01X535283Y517980D02*
Y521313D01*
G01Y520480D02*
X535617Y520897D01*
X536117Y521230D01*
X536783Y521313D01*
X537367Y521230D01*
X537867Y520897D01*
X538117Y520313D01*
Y517980D01*
G01X543800Y522980D02*
Y517980D01*
G01Y518730D02*
X543467Y518313D01*
X542967Y518063D01*
X542383Y517980D01*
X541717Y518147D01*
X541217Y518563D01*
X540883Y519063D01*
X540800Y519647D01*
X540883Y520230D01*
X541217Y520730D01*
X541717Y521147D01*
X542383Y521313D01*
X542967Y521230D01*
X543383Y521063D01*
X543800Y520730D01*
G01X552000Y517980D02*
Y522980D01*
G01Y520480D02*
X552417Y520980D01*
X552917Y521230D01*
X553417Y521313D01*
X554167Y521147D01*
X554667Y520813D01*
X555000Y520230D01*
Y519563D01*
X554833Y518897D01*
X554500Y518397D01*
X553917Y518063D01*
X553417Y517980D01*
X552917Y518063D01*
X552417Y518313D01*
X552000Y518730D01*
G01X559100Y517980D02*
X558600Y518063D01*
X558100Y518397D01*
X557767Y518980D01*
X557600Y519647D01*
X557767Y520313D01*
X558100Y520897D01*
X558600Y521230D01*
X559100Y521313D01*
X559600Y521230D01*
X560100Y520897D01*
X560433Y520313D01*
X560517Y519647D01*
X560433Y518980D01*
X560100Y518397D01*
X559600Y518063D01*
X559100Y517980D01*
G01X562617Y521313D02*
X563617Y517980D01*
X564700Y521313D01*
X565783Y517980D01*
X566783Y521313D01*
G01X489500Y577610D02*
Y509110D01*
G01X499000Y538500D02*
X500667D01*
Y537000D01*
X500167Y536500D01*
X499583Y536167D01*
X498750Y536000D01*
X497917Y536167D01*
X497333Y536500D01*
X496833Y537000D01*
X496500Y537583D01*
X496333Y538250D01*
Y538833D01*
X496500Y539333D01*
X496833Y539917D01*
X497333Y540417D01*
X497833Y540750D01*
X498500Y541000D01*
X499083D01*
X499750Y540833D01*
X500250Y540500D01*
G01X502600Y535833D02*
X505600Y541000D01*
G01X508117Y536000D02*
Y541000D01*
X511283D01*
G01X510117Y538583D02*
X508117D01*
G01X519150Y536667D02*
X519817Y536250D01*
X520567Y536000D01*
X521233D01*
X521900Y536250D01*
X522400Y536667D01*
X522650Y537250D01*
X522483Y537833D01*
X522067Y538333D01*
X521317Y538667D01*
X520317Y538833D01*
X519733Y539167D01*
X519483Y539750D01*
X519650Y540333D01*
X520067Y540750D01*
X520650Y541000D01*
X521233D01*
X521817Y540833D01*
X522317Y540417D01*
G01X526500Y536000D02*
Y541000D01*
G01X532100Y536000D02*
X531600Y536083D01*
X531100Y536417D01*
X530767Y537000D01*
X530600Y537667D01*
X530767Y538333D01*
X531100Y538917D01*
X531600Y539250D01*
X532100Y539333D01*
X532600Y539250D01*
X533100Y538917D01*
X533433Y538333D01*
X533517Y537667D01*
X533433Y537000D01*
X533100Y536417D01*
X532600Y536083D01*
X532100Y536000D01*
G01X537700Y541000D02*
Y536000D01*
G01X536533Y539333D02*
X538867D01*
G01X497250Y553250D02*
X499917D01*
X499667Y553833D01*
X499250Y554167D01*
X498667Y554333D01*
X498083Y554250D01*
X497583Y554000D01*
X497250Y553417D01*
X497083Y552917D01*
Y552417D01*
X497250Y551917D01*
X497667Y551417D01*
X498167Y551083D01*
X498750Y551000D01*
X499333Y551167D01*
X499917Y551667D01*
G01X505600Y556000D02*
Y551000D01*
G01Y551750D02*
X505267Y551333D01*
X504767Y551083D01*
X504183Y551000D01*
X503517Y551167D01*
X503017Y551583D01*
X502683Y552083D01*
X502600Y552667D01*
X502683Y553250D01*
X503017Y553750D01*
X503517Y554167D01*
X504183Y554333D01*
X504767Y554250D01*
X505183Y554083D01*
X505600Y553750D01*
G01X508533Y549750D02*
X509117Y549417D01*
X509783Y549333D01*
X510367Y549417D01*
X510867Y549833D01*
X511200Y550417D01*
Y554333D01*
G01Y553667D02*
X510867Y554000D01*
X510367Y554250D01*
X509783Y554333D01*
X509117Y554167D01*
X508700Y553833D01*
X508367Y553250D01*
X508200Y552667D01*
X508283Y552167D01*
X508617Y551583D01*
X509117Y551167D01*
X509783Y551000D01*
X510283Y551083D01*
X510867Y551417D01*
X511200Y551750D01*
G01X514050Y553250D02*
X516717D01*
X516467Y553833D01*
X516050Y554167D01*
X515467Y554333D01*
X514883Y554250D01*
X514383Y554000D01*
X514050Y553417D01*
X513883Y552917D01*
Y552417D01*
X514050Y551917D01*
X514467Y551417D01*
X514967Y551083D01*
X515550Y551000D01*
X516133Y551167D01*
X516717Y551667D01*
G01X526500Y556000D02*
Y551000D01*
G01X525333Y554333D02*
X527667D01*
G01X532100Y551000D02*
X531600Y551083D01*
X531100Y551417D01*
X530767Y552000D01*
X530600Y552667D01*
X530767Y553333D01*
X531100Y553917D01*
X531600Y554250D01*
X532100Y554333D01*
X532600Y554250D01*
X533100Y553917D01*
X533433Y553333D01*
X533517Y552667D01*
X533433Y552000D01*
X533100Y551417D01*
X532600Y551083D01*
X532100Y551000D01*
G01X541883D02*
Y556000D01*
G01Y553583D02*
X542300Y554000D01*
X542717Y554250D01*
X543383Y554333D01*
X543883Y554250D01*
X544467Y553917D01*
X544717Y553417D01*
Y551000D01*
G01X548900D02*
X548400Y551083D01*
X547900Y551417D01*
X547567Y552000D01*
X547400Y552667D01*
X547567Y553333D01*
X547900Y553917D01*
X548400Y554250D01*
X548900Y554333D01*
X549400Y554250D01*
X549900Y553917D01*
X550233Y553333D01*
X550317Y552667D01*
X550233Y552000D01*
X549900Y551417D01*
X549400Y551083D01*
X548900Y551000D01*
G01X554500D02*
Y556000D01*
G01X558850Y553250D02*
X561517D01*
X561267Y553833D01*
X560850Y554167D01*
X560267Y554333D01*
X559683Y554250D01*
X559183Y554000D01*
X558850Y553417D01*
X558683Y552917D01*
Y552417D01*
X558850Y551917D01*
X559267Y551417D01*
X559767Y551083D01*
X560350Y551000D01*
X560933Y551167D01*
X561517Y551667D01*
G01X490000Y546500D02*
X884500D01*
G01X497250Y569750D02*
X499917D01*
X499667Y570333D01*
X499250Y570667D01*
X498667Y570833D01*
X498083Y570750D01*
X497583Y570500D01*
X497250Y569917D01*
X497083Y569417D01*
Y568917D01*
X497250Y568417D01*
X497667Y567917D01*
X498167Y567583D01*
X498750Y567500D01*
X499333Y567667D01*
X499917Y568167D01*
G01X505600Y572500D02*
Y567500D01*
G01Y568250D02*
X505267Y567833D01*
X504767Y567583D01*
X504183Y567500D01*
X503517Y567667D01*
X503017Y568083D01*
X502683Y568583D01*
X502600Y569167D01*
X502683Y569750D01*
X503017Y570250D01*
X503517Y570667D01*
X504183Y570833D01*
X504767Y570750D01*
X505183Y570583D01*
X505600Y570250D01*
G01X508533Y566250D02*
X509117Y565917D01*
X509783Y565833D01*
X510367Y565917D01*
X510867Y566333D01*
X511200Y566917D01*
Y570833D01*
G01Y570167D02*
X510867Y570500D01*
X510367Y570750D01*
X509783Y570833D01*
X509117Y570667D01*
X508700Y570333D01*
X508367Y569750D01*
X508200Y569167D01*
X508283Y568667D01*
X508617Y568083D01*
X509117Y567667D01*
X509783Y567500D01*
X510283Y567583D01*
X510867Y567917D01*
X511200Y568250D01*
G01X514050Y569750D02*
X516717D01*
X516467Y570333D01*
X516050Y570667D01*
X515467Y570833D01*
X514883Y570750D01*
X514383Y570500D01*
X514050Y569917D01*
X513883Y569417D01*
Y568917D01*
X514050Y568417D01*
X514467Y567917D01*
X514967Y567583D01*
X515550Y567500D01*
X516133Y567667D01*
X516717Y568167D01*
G01X526500Y572500D02*
Y567500D01*
G01X525333Y570833D02*
X527667D01*
G01X532100Y567500D02*
X531600Y567583D01*
X531100Y567917D01*
X530767Y568500D01*
X530600Y569167D01*
X530767Y569833D01*
X531100Y570417D01*
X531600Y570750D01*
X532100Y570833D01*
X532600Y570750D01*
X533100Y570417D01*
X533433Y569833D01*
X533517Y569167D01*
X533433Y568500D01*
X533100Y567917D01*
X532600Y567583D01*
X532100Y567500D01*
G01X542050Y569750D02*
X544717D01*
X544467Y570333D01*
X544050Y570667D01*
X543467Y570833D01*
X542883Y570750D01*
X542383Y570500D01*
X542050Y569917D01*
X541883Y569417D01*
Y568917D01*
X542050Y568417D01*
X542467Y567917D01*
X542967Y567583D01*
X543550Y567500D01*
X544133Y567667D01*
X544717Y568167D01*
G01X550400Y572500D02*
Y567500D01*
G01Y568250D02*
X550067Y567833D01*
X549567Y567583D01*
X548983Y567500D01*
X548317Y567667D01*
X547817Y568083D01*
X547483Y568583D01*
X547400Y569167D01*
X547483Y569750D01*
X547817Y570250D01*
X548317Y570667D01*
X548983Y570833D01*
X549567Y570750D01*
X549983Y570583D01*
X550400Y570250D01*
G01X553333Y566250D02*
X553917Y565917D01*
X554583Y565833D01*
X555167Y565917D01*
X555667Y566333D01*
X556000Y566917D01*
Y570833D01*
G01Y570167D02*
X555667Y570500D01*
X555167Y570750D01*
X554583Y570833D01*
X553917Y570667D01*
X553500Y570333D01*
X553167Y569750D01*
X553000Y569167D01*
X553083Y568667D01*
X553417Y568083D01*
X553917Y567667D01*
X554583Y567500D01*
X555083Y567583D01*
X555667Y567917D01*
X556000Y568250D01*
G01X558850Y569750D02*
X561517D01*
X561267Y570333D01*
X560850Y570667D01*
X560267Y570833D01*
X559683Y570750D01*
X559183Y570500D01*
X558850Y569917D01*
X558683Y569417D01*
Y568917D01*
X558850Y568417D01*
X559267Y567917D01*
X559767Y567583D01*
X560350Y567500D01*
X560933Y567667D01*
X561517Y568167D01*
G01X490000Y561500D02*
X884500D01*
G01X522167Y-256500D02*
X518833D01*
Y-251500D01*
X522167D01*
G01X520833Y-253917D02*
X518833D01*
G01X524850Y-253167D02*
X527350Y-256500D01*
G01Y-253167D02*
X524850Y-256500D01*
G01X531700Y-256667D02*
X531533Y-256583D01*
Y-256417D01*
X531700Y-256333D01*
X531867Y-256417D01*
Y-256583D01*
X531700Y-256667D01*
G01X535550Y-256500D02*
Y-251500D01*
G01X539050D02*
Y-256500D01*
G01Y-254000D02*
X535550D01*
G01X541233Y-256500D02*
Y-251500D01*
X543317D01*
X543983Y-251750D01*
X544400Y-252083D01*
X544567Y-252750D01*
X544400Y-253417D01*
X543900Y-253833D01*
X543317Y-254083D01*
X541233D01*
G01X543317D02*
X544567Y-256500D01*
G01X550167D02*
X546833D01*
Y-251500D01*
X550167D01*
G01X548833Y-253917D02*
X546833D01*
G01X555100Y-256500D02*
Y-251500D01*
X552017Y-255083D01*
X556183D01*
G01X557867Y-255750D02*
X558367Y-256167D01*
X558950Y-256417D01*
X559700Y-256500D01*
X560450Y-256333D01*
X561033Y-256000D01*
X561450Y-255417D01*
X561533Y-254750D01*
X561367Y-254083D01*
X560950Y-253667D01*
X560367Y-253333D01*
X559783Y-253250D01*
X559200Y-253333D01*
X558450Y-253667D01*
X558700Y-251500D01*
X560950D01*
G01X563550Y-256500D02*
X567050Y-251500D01*
G01X563550D02*
X567050Y-256500D01*
G01X569483Y-255917D02*
X570067Y-256333D01*
X570733Y-256500D01*
X571400Y-256333D01*
X571983Y-255833D01*
X572400Y-255083D01*
X572567Y-254333D01*
Y-253417D01*
X572400Y-252667D01*
X571983Y-252000D01*
X571483Y-251667D01*
X570900Y-251500D01*
X570233Y-251667D01*
X569733Y-252000D01*
X569400Y-252500D01*
X569233Y-253167D01*
X569400Y-253750D01*
X569817Y-254333D01*
X570317Y-254667D01*
X570900Y-254750D01*
X571567Y-254583D01*
X572067Y-254167D01*
X572567Y-253417D01*
G01X574917Y-254417D02*
X575500Y-253833D01*
X576000Y-253500D01*
X576667Y-253333D01*
X577250Y-253500D01*
X577667Y-253833D01*
X578000Y-254333D01*
X578083Y-254917D01*
X578000Y-255417D01*
X577667Y-255917D01*
X577167Y-256333D01*
X576583Y-256500D01*
X575917Y-256333D01*
X575333Y-255833D01*
X575000Y-255083D01*
X574917Y-254250D01*
X575083Y-253167D01*
X575333Y-252583D01*
X575750Y-252000D01*
X576333Y-251583D01*
X576917Y-251500D01*
X577500Y-251667D01*
X577917Y-252083D01*
G01X581683Y-258167D02*
X580850Y-257333D01*
X580433Y-256500D01*
Y-253167D01*
X580850Y-252333D01*
X581683Y-251500D01*
G01X585867Y-256500D02*
Y-251500D01*
X587533D01*
X588200Y-251750D01*
X588700Y-252083D01*
X589117Y-252583D01*
X589450Y-253167D01*
X589533Y-254000D01*
X589450Y-254833D01*
X589117Y-255417D01*
X588700Y-255917D01*
X588200Y-256250D01*
X587533Y-256500D01*
X585867D01*
G01X593300D02*
Y-251500D01*
X592300Y-252500D01*
G01Y-256500D02*
X594300D01*
G01X597317Y-254417D02*
X597900Y-253833D01*
X598400Y-253500D01*
X599067Y-253333D01*
X599650Y-253500D01*
X600067Y-253833D01*
X600400Y-254333D01*
X600483Y-254917D01*
X600400Y-255417D01*
X600067Y-255917D01*
X599567Y-256333D01*
X598983Y-256500D01*
X598317Y-256333D01*
X597733Y-255833D01*
X597400Y-255083D01*
X597317Y-254250D01*
X597483Y-253167D01*
X597733Y-252583D01*
X598150Y-252000D01*
X598733Y-251583D01*
X599317Y-251500D01*
X599900Y-251667D01*
X600317Y-252083D01*
G01X602750Y-256500D02*
X606250Y-251500D01*
G01X602750D02*
X606250Y-256500D01*
G01X611100D02*
Y-251500D01*
X608017Y-255083D01*
X612183D01*
G01X616117Y-258167D02*
X616950Y-257333D01*
X617367Y-256500D01*
Y-253167D01*
X616950Y-252333D01*
X616117Y-251500D01*
G01X518833Y-207500D02*
Y-202500D01*
X520917D01*
X521583Y-202750D01*
X522000Y-203083D01*
X522167Y-203750D01*
X522000Y-204417D01*
X521500Y-204833D01*
X520917Y-205083D01*
X518833D01*
G01X520917D02*
X522167Y-207500D01*
G01X527767D02*
X524433D01*
Y-202500D01*
X527767D01*
G01X526433Y-204917D02*
X524433D01*
G01X533533Y-202917D02*
X533033Y-202667D01*
X532450Y-202500D01*
X531783D01*
X531033Y-202750D01*
X530450Y-203167D01*
X530033Y-203667D01*
X529700Y-204500D01*
X529617Y-205250D01*
X529783Y-206000D01*
X530033Y-206500D01*
X530533Y-207000D01*
X531117Y-207333D01*
X531700Y-207500D01*
X532283D01*
X532867Y-207333D01*
X533367Y-207083D01*
X533783Y-206750D01*
G01X537300Y-202500D02*
Y-207500D01*
G01X535383Y-202500D02*
X539217D01*
G01X540817Y-207500D02*
X542900Y-202500D01*
X544983Y-207500D01*
G01X544233Y-205750D02*
X541567D01*
G01X546583Y-207500D02*
Y-202500D01*
X550417Y-207500D01*
Y-202500D01*
G01X554600Y-205000D02*
X556267D01*
Y-206500D01*
X555767Y-207000D01*
X555183Y-207333D01*
X554350Y-207500D01*
X553517Y-207333D01*
X552933Y-207000D01*
X552433Y-206500D01*
X552100Y-205917D01*
X551933Y-205250D01*
Y-204667D01*
X552100Y-204167D01*
X552433Y-203583D01*
X552933Y-203083D01*
X553433Y-202750D01*
X554100Y-202500D01*
X554683D01*
X555350Y-202667D01*
X555850Y-203000D01*
G01X558033Y-202500D02*
Y-207500D01*
X561367D01*
G01X566967D02*
X563633D01*
Y-202500D01*
X566967D01*
G01X565633Y-204917D02*
X563633D01*
G01X574667Y-207500D02*
Y-202500D01*
X576333D01*
X577000Y-202750D01*
X577500Y-203083D01*
X577917Y-203583D01*
X578250Y-204167D01*
X578333Y-205000D01*
X578250Y-205833D01*
X577917Y-206417D01*
X577500Y-206917D01*
X577000Y-207250D01*
X576333Y-207500D01*
X574667D01*
G01X580433D02*
Y-202500D01*
X582517D01*
X583183Y-202750D01*
X583600Y-203083D01*
X583767Y-203750D01*
X583600Y-204417D01*
X583100Y-204833D01*
X582517Y-205083D01*
X580433D01*
G01X582517D02*
X583767Y-207500D01*
G01X586700Y-202500D02*
X588700D01*
G01X587700D02*
Y-207500D01*
G01X586700D02*
X588700D01*
G01X591633Y-202500D02*
Y-207500D01*
X594967D01*
G01X597233Y-202500D02*
Y-207500D01*
X600567D01*
G01X608350D02*
Y-202500D01*
G01X611850D02*
Y-207500D01*
G01Y-205000D02*
X608350D01*
G01X615700Y-207500D02*
X615033Y-207417D01*
X614450Y-207083D01*
X613950Y-206583D01*
X613617Y-206000D01*
X613450Y-205333D01*
Y-204667D01*
X613617Y-204000D01*
X613950Y-203417D01*
X614450Y-202917D01*
X615033Y-202583D01*
X615700Y-202500D01*
X616367Y-202583D01*
X616950Y-202917D01*
X617450Y-203417D01*
X617783Y-204000D01*
X617950Y-204667D01*
Y-205333D01*
X617783Y-206000D01*
X617450Y-206583D01*
X616950Y-207083D01*
X616367Y-207417D01*
X615700Y-207500D01*
G01X619633Y-202500D02*
Y-207500D01*
X622967D01*
G01X628567D02*
X625233D01*
Y-202500D01*
X628567D01*
G01X627233Y-204917D02*
X625233D01*
G01X636267Y-207500D02*
Y-202500D01*
X637933D01*
X638600Y-202750D01*
X639100Y-203083D01*
X639517Y-203583D01*
X639850Y-204167D01*
X639933Y-205000D01*
X639850Y-205833D01*
X639517Y-206417D01*
X639100Y-206917D01*
X638600Y-207250D01*
X637933Y-207500D01*
X636267D01*
G01X645367D02*
X642033D01*
Y-202500D01*
X645367D01*
G01X644033Y-204917D02*
X642033D01*
G01X647717Y-207500D02*
Y-202500D01*
X650883D01*
G01X649717Y-204917D02*
X647717D01*
G01X653900Y-202500D02*
X655900D01*
G01X654900D02*
Y-207500D01*
G01X653900D02*
X655900D01*
G01X658583D02*
Y-202500D01*
X662417Y-207500D01*
Y-202500D01*
G01X667767Y-207500D02*
X664433D01*
Y-202500D01*
X667767D01*
G01X666433Y-204917D02*
X664433D01*
G01X537167Y-267500D02*
Y-262500D01*
X538833D01*
X539500Y-262750D01*
X540000Y-263083D01*
X540417Y-263583D01*
X540750Y-264167D01*
X540833Y-265000D01*
X540750Y-265833D01*
X540417Y-266417D01*
X540000Y-266917D01*
X539500Y-267250D01*
X538833Y-267500D01*
X537167D01*
G01X544600D02*
Y-262500D01*
X543600Y-263500D01*
G01Y-267500D02*
X545600D01*
G01X548617Y-265417D02*
X549200Y-264833D01*
X549700Y-264500D01*
X550367Y-264333D01*
X550950Y-264500D01*
X551367Y-264833D01*
X551700Y-265333D01*
X551783Y-265917D01*
X551700Y-266417D01*
X551367Y-266917D01*
X550867Y-267333D01*
X550283Y-267500D01*
X549617Y-267333D01*
X549033Y-266833D01*
X548700Y-266083D01*
X548617Y-265250D01*
X548783Y-264167D01*
X549033Y-263583D01*
X549450Y-263000D01*
X550033Y-262583D01*
X550617Y-262500D01*
X551200Y-262667D01*
X551617Y-263083D01*
G01X555800Y-267667D02*
X555633Y-267583D01*
Y-267417D01*
X555800Y-267333D01*
X555967Y-267417D01*
Y-267583D01*
X555800Y-267667D01*
G01Y-265417D02*
X555633Y-265333D01*
Y-265167D01*
X555800Y-265083D01*
X555967Y-265167D01*
Y-265333D01*
X555800Y-265417D01*
G01X559567Y-267500D02*
Y-262500D01*
X561233D01*
X561900Y-262750D01*
X562400Y-263083D01*
X562817Y-263583D01*
X563150Y-264167D01*
X563233Y-265000D01*
X563150Y-265833D01*
X562817Y-266417D01*
X562400Y-266917D01*
X561900Y-267250D01*
X561233Y-267500D01*
X559567D01*
G01X567000Y-264167D02*
Y-267500D01*
G01Y-262833D02*
X566833Y-262750D01*
Y-262583D01*
X567000Y-262500D01*
X567167Y-262583D01*
Y-262750D01*
X567000Y-262833D01*
G01X574100Y-267500D02*
Y-264167D01*
G01Y-264750D02*
X573767Y-264417D01*
X573267Y-264250D01*
X572683Y-264167D01*
X572100Y-264333D01*
X571600Y-264667D01*
X571267Y-265167D01*
X571100Y-265833D01*
X571267Y-266500D01*
X571600Y-267000D01*
X572100Y-267333D01*
X572683Y-267500D01*
X573267Y-267417D01*
X573767Y-267167D01*
X574100Y-266833D01*
G01X575700Y-267500D02*
Y-264167D01*
G01Y-265083D02*
X575950Y-264667D01*
X576367Y-264333D01*
X576950Y-264167D01*
X577533Y-264333D01*
X577950Y-264667D01*
X578200Y-265083D01*
Y-267500D01*
G01Y-265083D02*
X578450Y-264667D01*
X578867Y-264333D01*
X579450Y-264167D01*
X580033Y-264333D01*
X580450Y-264667D01*
X580700Y-265167D01*
Y-267500D01*
G01X582550Y-265250D02*
X585217D01*
X584967Y-264667D01*
X584550Y-264333D01*
X583967Y-264167D01*
X583383Y-264250D01*
X582883Y-264500D01*
X582550Y-265083D01*
X582383Y-265583D01*
Y-266083D01*
X582550Y-266583D01*
X582967Y-267083D01*
X583467Y-267417D01*
X584050Y-267500D01*
X584633Y-267333D01*
X585217Y-266833D01*
G01X589400Y-262500D02*
Y-267500D01*
G01X588233Y-264167D02*
X590567D01*
G01X593750Y-265250D02*
X596417D01*
X596167Y-264667D01*
X595750Y-264333D01*
X595167Y-264167D01*
X594583Y-264250D01*
X594083Y-264500D01*
X593750Y-265083D01*
X593583Y-265583D01*
Y-266083D01*
X593750Y-266583D01*
X594167Y-267083D01*
X594667Y-267417D01*
X595250Y-267500D01*
X595833Y-267333D01*
X596417Y-266833D01*
G01X599433Y-267500D02*
Y-264167D01*
G01Y-264833D02*
X599850Y-264500D01*
X600267Y-264250D01*
X600850Y-264167D01*
X601267Y-264250D01*
X601767Y-264500D01*
G01X611800Y-267500D02*
Y-262500D01*
X610800Y-263500D01*
G01Y-267500D02*
X612800D01*
G01X615817Y-265417D02*
X616400Y-264833D01*
X616900Y-264500D01*
X617567Y-264333D01*
X618150Y-264500D01*
X618567Y-264833D01*
X618900Y-265333D01*
X618983Y-265917D01*
X618900Y-266417D01*
X618567Y-266917D01*
X618067Y-267333D01*
X617483Y-267500D01*
X616817Y-267333D01*
X616233Y-266833D01*
X615900Y-266083D01*
X615817Y-265250D01*
X615983Y-264167D01*
X616233Y-263583D01*
X616650Y-263000D01*
X617233Y-262583D01*
X617817Y-262500D01*
X618400Y-262667D01*
X618817Y-263083D01*
G01X620500Y-267500D02*
Y-264167D01*
G01Y-265083D02*
X620750Y-264667D01*
X621167Y-264333D01*
X621750Y-264167D01*
X622333Y-264333D01*
X622750Y-264667D01*
X623000Y-265083D01*
Y-267500D01*
G01Y-265083D02*
X623250Y-264667D01*
X623667Y-264333D01*
X624250Y-264167D01*
X624833Y-264333D01*
X625250Y-264667D01*
X625500Y-265167D01*
Y-267500D01*
G01X628600Y-264167D02*
Y-267500D01*
G01Y-262833D02*
X628433Y-262750D01*
Y-262583D01*
X628600Y-262500D01*
X628767Y-262583D01*
Y-262750D01*
X628600Y-262833D01*
G01X634200Y-267500D02*
Y-262500D01*
G01X567500Y63000D02*
Y-187000D01*
G01X557500Y331500D02*
Y93000D01*
G01X562917Y110667D02*
X563417Y111167D01*
X564000Y111417D01*
X564667Y111500D01*
X565500Y111333D01*
X566083Y110917D01*
X566250Y110417D01*
X566167Y109917D01*
X565833Y109500D01*
X564167Y108667D01*
X563417Y108083D01*
X562917Y107250D01*
X562750Y106500D01*
X566250D01*
G01X570100Y106333D02*
X569933Y106417D01*
Y106583D01*
X570100Y106667D01*
X570267Y106583D01*
Y106417D01*
X570100Y106333D01*
G01X573617Y111500D02*
X575700Y106500D01*
X577783Y111500D01*
G01X581300Y109833D02*
Y106500D01*
G01Y111167D02*
X581133Y111250D01*
Y111417D01*
X581300Y111500D01*
X581467Y111417D01*
Y111250D01*
X581300Y111167D01*
G01X588400Y106500D02*
Y109833D01*
G01Y109250D02*
X588067Y109583D01*
X587567Y109750D01*
X586983Y109833D01*
X586400Y109667D01*
X585900Y109333D01*
X585567Y108833D01*
X585400Y108167D01*
X585567Y107500D01*
X585900Y107000D01*
X586400Y106667D01*
X586983Y106500D01*
X587567Y106583D01*
X588067Y106833D01*
X588400Y107167D01*
G01X596850Y107083D02*
X597267Y106750D01*
X597850Y106500D01*
X598350D01*
X598850Y106667D01*
X599183Y106917D01*
X599350Y107250D01*
X599267Y107750D01*
X598933Y108000D01*
X597433Y108500D01*
X597100Y109083D01*
X597267Y109500D01*
X597600Y109750D01*
X598100Y109833D01*
X598600Y109750D01*
X599100Y109500D01*
G01X602283Y106500D02*
Y111500D01*
G01Y109083D02*
X602700Y109500D01*
X603117Y109750D01*
X603783Y109833D01*
X604283Y109750D01*
X604867Y109417D01*
X605117Y108917D01*
Y106500D01*
G01X609300D02*
X608800Y106583D01*
X608300Y106917D01*
X607967Y107500D01*
X607800Y108167D01*
X607967Y108833D01*
X608300Y109417D01*
X608800Y109750D01*
X609300Y109833D01*
X609800Y109750D01*
X610300Y109417D01*
X610633Y108833D01*
X610717Y108167D01*
X610633Y107500D01*
X610300Y106917D01*
X609800Y106583D01*
X609300Y106500D01*
G01X613483Y109833D02*
Y107500D01*
X613817Y106917D01*
X614317Y106583D01*
X614900Y106500D01*
X615483Y106583D01*
X615983Y106917D01*
X616317Y107500D01*
G01Y106500D02*
Y109833D01*
G01X620500Y106500D02*
Y111500D01*
G01X627600D02*
Y106500D01*
G01Y107250D02*
X627267Y106833D01*
X626767Y106583D01*
X626183Y106500D01*
X625517Y106667D01*
X625017Y107083D01*
X624683Y107583D01*
X624600Y108167D01*
X624683Y108750D01*
X625017Y109250D01*
X625517Y109667D01*
X626183Y109833D01*
X626767Y109750D01*
X627183Y109583D01*
X627600Y109250D01*
G01X635800Y106500D02*
Y111500D01*
G01Y109000D02*
X636217Y109500D01*
X636717Y109750D01*
X637217Y109833D01*
X637967Y109667D01*
X638467Y109333D01*
X638800Y108750D01*
Y108083D01*
X638633Y107417D01*
X638300Y106917D01*
X637717Y106583D01*
X637217Y106500D01*
X636717Y106583D01*
X636217Y106833D01*
X635800Y107250D01*
G01X641650Y108750D02*
X644317D01*
X644067Y109333D01*
X643650Y109667D01*
X643067Y109833D01*
X642483Y109750D01*
X641983Y109500D01*
X641650Y108917D01*
X641483Y108417D01*
Y107917D01*
X641650Y107417D01*
X642067Y106917D01*
X642567Y106583D01*
X643150Y106500D01*
X643733Y106667D01*
X644317Y107167D01*
G01X652600Y104833D02*
Y109833D01*
G01Y109083D02*
X653017Y109500D01*
X653433Y109750D01*
X654100Y109833D01*
X654683Y109750D01*
X655267Y109333D01*
X655517Y108750D01*
X655600Y108167D01*
X655517Y107583D01*
X655267Y107000D01*
X654767Y106667D01*
X654100Y106500D01*
X653517Y106583D01*
X652933Y106833D01*
X652600Y107167D01*
G01X659700Y106500D02*
Y111500D01*
G01X663883Y109833D02*
Y107500D01*
X664217Y106917D01*
X664717Y106583D01*
X665300Y106500D01*
X665883Y106583D01*
X666383Y106917D01*
X666717Y107500D01*
G01Y106500D02*
Y109833D01*
G01X669733Y105250D02*
X670317Y104917D01*
X670983Y104833D01*
X671567Y104917D01*
X672067Y105333D01*
X672400Y105917D01*
Y109833D01*
G01Y109167D02*
X672067Y109500D01*
X671567Y109750D01*
X670983Y109833D01*
X670317Y109667D01*
X669900Y109333D01*
X669567Y108750D01*
X669400Y108167D01*
X669483Y107667D01*
X669817Y107083D01*
X670317Y106667D01*
X670983Y106500D01*
X671483Y106583D01*
X672067Y106917D01*
X672400Y107250D01*
G01X675333Y105250D02*
X675917Y104917D01*
X676583Y104833D01*
X677167Y104917D01*
X677667Y105333D01*
X678000Y105917D01*
Y109833D01*
G01Y109167D02*
X677667Y109500D01*
X677167Y109750D01*
X676583Y109833D01*
X675917Y109667D01*
X675500Y109333D01*
X675167Y108750D01*
X675000Y108167D01*
X675083Y107667D01*
X675417Y107083D01*
X675917Y106667D01*
X676583Y106500D01*
X677083Y106583D01*
X677667Y106917D01*
X678000Y107250D01*
G01X680850Y108750D02*
X683517D01*
X683267Y109333D01*
X682850Y109667D01*
X682267Y109833D01*
X681683Y109750D01*
X681183Y109500D01*
X680850Y108917D01*
X680683Y108417D01*
Y107917D01*
X680850Y107417D01*
X681267Y106917D01*
X681767Y106583D01*
X682350Y106500D01*
X682933Y106667D01*
X683517Y107167D01*
G01X689200Y111500D02*
Y106500D01*
G01Y107250D02*
X688867Y106833D01*
X688367Y106583D01*
X687783Y106500D01*
X687117Y106667D01*
X686617Y107083D01*
X686283Y107583D01*
X686200Y108167D01*
X686283Y108750D01*
X686617Y109250D01*
X687117Y109667D01*
X687783Y109833D01*
X688367Y109750D01*
X688783Y109583D01*
X689200Y109250D01*
G01X696817Y109833D02*
X697817Y106500D01*
X698900Y109833D01*
X699983Y106500D01*
X700983Y109833D01*
G01X704500D02*
Y106500D01*
G01Y111167D02*
X704333Y111250D01*
Y111417D01*
X704500Y111500D01*
X704667Y111417D01*
Y111250D01*
X704500Y111167D01*
G01X710100Y111500D02*
Y106500D01*
G01X708933Y109833D02*
X711267D01*
G01X714283Y106500D02*
Y111500D01*
G01Y109083D02*
X714700Y109500D01*
X715117Y109750D01*
X715783Y109833D01*
X716283Y109750D01*
X716867Y109417D01*
X717117Y108917D01*
Y106500D01*
G01X725233D02*
X728567Y108167D01*
X725233Y109833D01*
G01X731083Y107083D02*
X731667Y106667D01*
X732333Y106500D01*
X733000Y106667D01*
X733583Y107167D01*
X734000Y107917D01*
X734167Y108667D01*
Y109583D01*
X734000Y110333D01*
X733583Y111000D01*
X733083Y111333D01*
X732500Y111500D01*
X731833Y111333D01*
X731333Y111000D01*
X731000Y110500D01*
X730833Y109833D01*
X731000Y109250D01*
X731417Y108667D01*
X731917Y108333D01*
X732500Y108250D01*
X733167Y108417D01*
X733667Y108833D01*
X734167Y109583D01*
G01X738100Y111500D02*
X737433Y111333D01*
X736933Y110917D01*
X736600Y110417D01*
X736350Y109750D01*
X736267Y109000D01*
X736350Y108250D01*
X736600Y107583D01*
X736933Y107083D01*
X737433Y106667D01*
X738100Y106500D01*
X738767Y106667D01*
X739267Y107083D01*
X739600Y107583D01*
X739850Y108250D01*
X739933Y109000D01*
X739850Y109750D01*
X739600Y110417D01*
X739267Y110917D01*
X738767Y111333D01*
X738100Y111500D01*
G01X742200Y106333D02*
X745200Y111500D01*
G01X742200D02*
X741700Y111333D01*
X741450Y111083D01*
X741283Y110583D01*
X741450Y110083D01*
X741700Y109833D01*
X742200Y109667D01*
X742700Y109833D01*
X742950Y110083D01*
X743117Y110583D01*
X742950Y111083D01*
X742700Y111333D01*
X742200Y111500D01*
G01X745200Y108167D02*
X744700Y108000D01*
X744450Y107750D01*
X744283Y107250D01*
X744450Y106750D01*
X744700Y106500D01*
X745200Y106333D01*
X745700Y106500D01*
X745950Y106750D01*
X746117Y107250D01*
X745950Y107750D01*
X745700Y108000D01*
X745200Y108167D01*
G01X753733Y106500D02*
Y109833D01*
G01Y109167D02*
X754150Y109500D01*
X754567Y109750D01*
X755150Y109833D01*
X755567Y109750D01*
X756067Y109500D01*
G01X759250Y108750D02*
X761917D01*
X761667Y109333D01*
X761250Y109667D01*
X760667Y109833D01*
X760083Y109750D01*
X759583Y109500D01*
X759250Y108917D01*
X759083Y108417D01*
Y107917D01*
X759250Y107417D01*
X759667Y106917D01*
X760167Y106583D01*
X760750Y106500D01*
X761333Y106667D01*
X761917Y107167D01*
G01X764850Y107083D02*
X765267Y106750D01*
X765850Y106500D01*
X766350D01*
X766850Y106667D01*
X767183Y106917D01*
X767350Y107250D01*
X767267Y107750D01*
X766933Y108000D01*
X765433Y108500D01*
X765100Y109083D01*
X765267Y109500D01*
X765600Y109750D01*
X766100Y109833D01*
X766600Y109750D01*
X767100Y109500D01*
G01X771700Y109833D02*
Y106500D01*
G01Y111167D02*
X771533Y111250D01*
Y111417D01*
X771700Y111500D01*
X771867Y111417D01*
Y111250D01*
X771700Y111167D01*
G01X775883Y106500D02*
Y109833D01*
G01Y109000D02*
X776217Y109417D01*
X776717Y109750D01*
X777383Y109833D01*
X777967Y109750D01*
X778467Y109417D01*
X778717Y108833D01*
Y106500D01*
G01X787917Y105000D02*
X789083Y106167D01*
Y107333D01*
X787917D01*
Y106167D01*
X789083D01*
G01Y108167D02*
Y109333D01*
X787917D01*
Y108167D01*
X789083D01*
G01X792267Y106500D02*
Y111500D01*
X793933D01*
X794600Y111250D01*
X795100Y110917D01*
X795517Y110417D01*
X795850Y109833D01*
X795933Y109000D01*
X795850Y108167D01*
X795517Y107583D01*
X795100Y107083D01*
X794600Y106750D01*
X793933Y106500D01*
X792267D01*
G01X799700D02*
X799200Y106583D01*
X798700Y106917D01*
X798367Y107500D01*
X798200Y108167D01*
X798367Y108833D01*
X798700Y109417D01*
X799200Y109750D01*
X799700Y109833D01*
X800200Y109750D01*
X800700Y109417D01*
X801033Y108833D01*
X801117Y108167D01*
X801033Y107500D01*
X800700Y106917D01*
X800200Y106583D01*
X799700Y106500D01*
G01X809483D02*
Y109833D01*
G01Y109000D02*
X809817Y109417D01*
X810317Y109750D01*
X810983Y109833D01*
X811567Y109750D01*
X812067Y109417D01*
X812317Y108833D01*
Y106500D01*
G01X816500D02*
X816000Y106583D01*
X815500Y106917D01*
X815167Y107500D01*
X815000Y108167D01*
X815167Y108833D01*
X815500Y109417D01*
X816000Y109750D01*
X816500Y109833D01*
X817000Y109750D01*
X817500Y109417D01*
X817833Y108833D01*
X817917Y108167D01*
X817833Y107500D01*
X817500Y106917D01*
X817000Y106583D01*
X816500Y106500D01*
G01X822100Y111500D02*
Y106500D01*
G01X820933Y109833D02*
X823267D01*
G01X834800Y106500D02*
Y109833D01*
G01Y109250D02*
X834467Y109583D01*
X833967Y109750D01*
X833383Y109833D01*
X832800Y109667D01*
X832300Y109333D01*
X831967Y108833D01*
X831800Y108167D01*
X831967Y107500D01*
X832300Y107000D01*
X832800Y106667D01*
X833383Y106500D01*
X833967Y106583D01*
X834467Y106833D01*
X834800Y107167D01*
G01X838900Y106500D02*
Y111500D01*
G01X844500Y106500D02*
Y111500D01*
G01X850100Y106500D02*
X849600Y106583D01*
X849100Y106917D01*
X848767Y107500D01*
X848600Y108167D01*
X848767Y108833D01*
X849100Y109417D01*
X849600Y109750D01*
X850100Y109833D01*
X850600Y109750D01*
X851100Y109417D01*
X851433Y108833D01*
X851517Y108167D01*
X851433Y107500D01*
X851100Y106917D01*
X850600Y106583D01*
X850100Y106500D01*
G01X853617Y109833D02*
X854617Y106500D01*
X855700Y109833D01*
X856783Y106500D01*
X857783Y109833D01*
G01X564500Y117000D02*
Y122000D01*
X563500Y121000D01*
G01Y117000D02*
X565500D01*
G01X570100Y116833D02*
X569933Y116917D01*
Y117083D01*
X570100Y117167D01*
X570267Y117083D01*
Y116917D01*
X570100Y116833D01*
G01X573867Y117000D02*
Y122000D01*
X575533D01*
X576200Y121750D01*
X576700Y121417D01*
X577117Y120917D01*
X577450Y120333D01*
X577533Y119500D01*
X577450Y118667D01*
X577117Y118083D01*
X576700Y117583D01*
X576200Y117250D01*
X575533Y117000D01*
X573867D01*
G01X581300Y120333D02*
Y117000D01*
G01Y121667D02*
X581133Y121750D01*
Y121917D01*
X581300Y122000D01*
X581467Y121917D01*
Y121750D01*
X581300Y121667D01*
G01X584400Y117000D02*
Y120333D01*
G01Y119417D02*
X584650Y119833D01*
X585067Y120167D01*
X585650Y120333D01*
X586233Y120167D01*
X586650Y119833D01*
X586900Y119417D01*
Y117000D01*
G01Y119417D02*
X587150Y119833D01*
X587567Y120167D01*
X588150Y120333D01*
X588733Y120167D01*
X589150Y119833D01*
X589400Y119333D01*
Y117000D01*
G01X591000Y115333D02*
Y120333D01*
G01Y119583D02*
X591417Y120000D01*
X591833Y120250D01*
X592500Y120333D01*
X593083Y120250D01*
X593667Y119833D01*
X593917Y119250D01*
X594000Y118667D01*
X593917Y118083D01*
X593667Y117500D01*
X593167Y117167D01*
X592500Y117000D01*
X591917Y117083D01*
X591333Y117333D01*
X591000Y117667D01*
G01X598100Y117000D02*
Y122000D01*
G01X602450Y119250D02*
X605117D01*
X604867Y119833D01*
X604450Y120167D01*
X603867Y120333D01*
X603283Y120250D01*
X602783Y120000D01*
X602450Y119417D01*
X602283Y118917D01*
Y118417D01*
X602450Y117917D01*
X602867Y117417D01*
X603367Y117083D01*
X603950Y117000D01*
X604533Y117167D01*
X605117Y117667D01*
G01X616567Y117000D02*
X613233Y118667D01*
X616567Y120333D01*
G01X626100Y117000D02*
Y122000D01*
X625100Y121000D01*
G01Y117000D02*
X627100D01*
G01X634800D02*
Y120333D01*
G01Y119417D02*
X635050Y119833D01*
X635467Y120167D01*
X636050Y120333D01*
X636633Y120167D01*
X637050Y119833D01*
X637300Y119417D01*
Y117000D01*
G01Y119417D02*
X637550Y119833D01*
X637967Y120167D01*
X638550Y120333D01*
X639133Y120167D01*
X639550Y119833D01*
X639800Y119333D01*
Y117000D01*
G01X642900Y120333D02*
Y117000D01*
G01Y121667D02*
X642733Y121750D01*
Y121917D01*
X642900Y122000D01*
X643067Y121917D01*
Y121750D01*
X642900Y121667D01*
G01X648500Y117000D02*
Y122000D01*
G01X659117Y115500D02*
X660283Y116667D01*
Y117833D01*
X659117D01*
Y116667D01*
X660283D01*
G01Y118667D02*
Y119833D01*
X659117D01*
Y118667D01*
X660283D01*
G01X564500Y151000D02*
Y156000D01*
X563500Y155000D01*
G01Y151000D02*
X565500D01*
G01X570100Y150833D02*
X569933Y150917D01*
Y151083D01*
X570100Y151167D01*
X570267Y151083D01*
Y150917D01*
X570100Y150833D01*
G01X573617Y156000D02*
X575700Y151000D01*
X577783Y156000D01*
G01X581300Y154333D02*
Y151000D01*
G01Y155667D02*
X581133Y155750D01*
Y155917D01*
X581300Y156000D01*
X581467Y155917D01*
Y155750D01*
X581300Y155667D01*
G01X588400Y151000D02*
Y154333D01*
G01Y153750D02*
X588067Y154083D01*
X587567Y154250D01*
X586983Y154333D01*
X586400Y154167D01*
X585900Y153833D01*
X585567Y153333D01*
X585400Y152667D01*
X585567Y152000D01*
X585900Y151500D01*
X586400Y151167D01*
X586983Y151000D01*
X587567Y151083D01*
X588067Y151333D01*
X588400Y151667D01*
G01X596850Y151583D02*
X597267Y151250D01*
X597850Y151000D01*
X598350D01*
X598850Y151167D01*
X599183Y151417D01*
X599350Y151750D01*
X599267Y152250D01*
X598933Y152500D01*
X597433Y153000D01*
X597100Y153583D01*
X597267Y154000D01*
X597600Y154250D01*
X598100Y154333D01*
X598600Y154250D01*
X599100Y154000D01*
G01X602283Y151000D02*
Y156000D01*
G01Y153583D02*
X602700Y154000D01*
X603117Y154250D01*
X603783Y154333D01*
X604283Y154250D01*
X604867Y153917D01*
X605117Y153417D01*
Y151000D01*
G01X609300D02*
X608800Y151083D01*
X608300Y151417D01*
X607967Y152000D01*
X607800Y152667D01*
X607967Y153333D01*
X608300Y153917D01*
X608800Y154250D01*
X609300Y154333D01*
X609800Y154250D01*
X610300Y153917D01*
X610633Y153333D01*
X610717Y152667D01*
X610633Y152000D01*
X610300Y151417D01*
X609800Y151083D01*
X609300Y151000D01*
G01X613483Y154333D02*
Y152000D01*
X613817Y151417D01*
X614317Y151083D01*
X614900Y151000D01*
X615483Y151083D01*
X615983Y151417D01*
X616317Y152000D01*
G01Y151000D02*
Y154333D01*
G01X620500Y151000D02*
Y156000D01*
G01X627600D02*
Y151000D01*
G01Y151750D02*
X627267Y151333D01*
X626767Y151083D01*
X626183Y151000D01*
X625517Y151167D01*
X625017Y151583D01*
X624683Y152083D01*
X624600Y152667D01*
X624683Y153250D01*
X625017Y153750D01*
X625517Y154167D01*
X626183Y154333D01*
X626767Y154250D01*
X627183Y154083D01*
X627600Y153750D01*
G01X635800Y151000D02*
Y156000D01*
G01Y153500D02*
X636217Y154000D01*
X636717Y154250D01*
X637217Y154333D01*
X637967Y154167D01*
X638467Y153833D01*
X638800Y153250D01*
Y152583D01*
X638633Y151917D01*
X638300Y151417D01*
X637717Y151083D01*
X637217Y151000D01*
X636717Y151083D01*
X636217Y151333D01*
X635800Y151750D01*
G01X641650Y153250D02*
X644317D01*
X644067Y153833D01*
X643650Y154167D01*
X643067Y154333D01*
X642483Y154250D01*
X641983Y154000D01*
X641650Y153417D01*
X641483Y152917D01*
Y152417D01*
X641650Y151917D01*
X642067Y151417D01*
X642567Y151083D01*
X643150Y151000D01*
X643733Y151167D01*
X644317Y151667D01*
G01X652600Y149333D02*
Y154333D01*
G01Y153583D02*
X653017Y154000D01*
X653433Y154250D01*
X654100Y154333D01*
X654683Y154250D01*
X655267Y153833D01*
X655517Y153250D01*
X655600Y152667D01*
X655517Y152083D01*
X655267Y151500D01*
X654767Y151167D01*
X654100Y151000D01*
X653517Y151083D01*
X652933Y151333D01*
X652600Y151667D01*
G01X659700Y151000D02*
Y156000D01*
G01X663883Y154333D02*
Y152000D01*
X664217Y151417D01*
X664717Y151083D01*
X665300Y151000D01*
X665883Y151083D01*
X666383Y151417D01*
X666717Y152000D01*
G01Y151000D02*
Y154333D01*
G01X669733Y149750D02*
X670317Y149417D01*
X670983Y149333D01*
X671567Y149417D01*
X672067Y149833D01*
X672400Y150417D01*
Y154333D01*
G01Y153667D02*
X672067Y154000D01*
X671567Y154250D01*
X670983Y154333D01*
X670317Y154167D01*
X669900Y153833D01*
X669567Y153250D01*
X669400Y152667D01*
X669483Y152167D01*
X669817Y151583D01*
X670317Y151167D01*
X670983Y151000D01*
X671483Y151083D01*
X672067Y151417D01*
X672400Y151750D01*
G01X675333Y149750D02*
X675917Y149417D01*
X676583Y149333D01*
X677167Y149417D01*
X677667Y149833D01*
X678000Y150417D01*
Y154333D01*
G01Y153667D02*
X677667Y154000D01*
X677167Y154250D01*
X676583Y154333D01*
X675917Y154167D01*
X675500Y153833D01*
X675167Y153250D01*
X675000Y152667D01*
X675083Y152167D01*
X675417Y151583D01*
X675917Y151167D01*
X676583Y151000D01*
X677083Y151083D01*
X677667Y151417D01*
X678000Y151750D01*
G01X680850Y153250D02*
X683517D01*
X683267Y153833D01*
X682850Y154167D01*
X682267Y154333D01*
X681683Y154250D01*
X681183Y154000D01*
X680850Y153417D01*
X680683Y152917D01*
Y152417D01*
X680850Y151917D01*
X681267Y151417D01*
X681767Y151083D01*
X682350Y151000D01*
X682933Y151167D01*
X683517Y151667D01*
G01X689200Y156000D02*
Y151000D01*
G01Y151750D02*
X688867Y151333D01*
X688367Y151083D01*
X687783Y151000D01*
X687117Y151167D01*
X686617Y151583D01*
X686283Y152083D01*
X686200Y152667D01*
X686283Y153250D01*
X686617Y153750D01*
X687117Y154167D01*
X687783Y154333D01*
X688367Y154250D01*
X688783Y154083D01*
X689200Y153750D01*
G01X696817Y154333D02*
X697817Y151000D01*
X698900Y154333D01*
X699983Y151000D01*
X700983Y154333D01*
G01X704500D02*
Y151000D01*
G01Y155667D02*
X704333Y155750D01*
Y155917D01*
X704500Y156000D01*
X704667Y155917D01*
Y155750D01*
X704500Y155667D01*
G01X710100Y156000D02*
Y151000D01*
G01X708933Y154333D02*
X711267D01*
G01X714283Y151000D02*
Y156000D01*
G01Y153583D02*
X714700Y154000D01*
X715117Y154250D01*
X715783Y154333D01*
X716283Y154250D01*
X716867Y153917D01*
X717117Y153417D01*
Y151000D01*
G01X725233D02*
X728567Y152667D01*
X725233Y154333D01*
G01X731083Y151583D02*
X731667Y151167D01*
X732333Y151000D01*
X733000Y151167D01*
X733583Y151667D01*
X734000Y152417D01*
X734167Y153167D01*
Y154083D01*
X734000Y154833D01*
X733583Y155500D01*
X733083Y155833D01*
X732500Y156000D01*
X731833Y155833D01*
X731333Y155500D01*
X731000Y155000D01*
X730833Y154333D01*
X731000Y153750D01*
X731417Y153167D01*
X731917Y152833D01*
X732500Y152750D01*
X733167Y152917D01*
X733667Y153333D01*
X734167Y154083D01*
G01X738100Y156000D02*
X737433Y155833D01*
X736933Y155417D01*
X736600Y154917D01*
X736350Y154250D01*
X736267Y153500D01*
X736350Y152750D01*
X736600Y152083D01*
X736933Y151583D01*
X737433Y151167D01*
X738100Y151000D01*
X738767Y151167D01*
X739267Y151583D01*
X739600Y152083D01*
X739850Y152750D01*
X739933Y153500D01*
X739850Y154250D01*
X739600Y154917D01*
X739267Y155417D01*
X738767Y155833D01*
X738100Y156000D01*
G01X742200Y150833D02*
X745200Y156000D01*
G01X742200D02*
X741700Y155833D01*
X741450Y155583D01*
X741283Y155083D01*
X741450Y154583D01*
X741700Y154333D01*
X742200Y154167D01*
X742700Y154333D01*
X742950Y154583D01*
X743117Y155083D01*
X742950Y155583D01*
X742700Y155833D01*
X742200Y156000D01*
G01X745200Y152667D02*
X744700Y152500D01*
X744450Y152250D01*
X744283Y151750D01*
X744450Y151250D01*
X744700Y151000D01*
X745200Y150833D01*
X745700Y151000D01*
X745950Y151250D01*
X746117Y151750D01*
X745950Y152250D01*
X745700Y152500D01*
X745200Y152667D01*
G01X753733Y151000D02*
Y154333D01*
G01Y153667D02*
X754150Y154000D01*
X754567Y154250D01*
X755150Y154333D01*
X755567Y154250D01*
X756067Y154000D01*
G01X759250Y153250D02*
X761917D01*
X761667Y153833D01*
X761250Y154167D01*
X760667Y154333D01*
X760083Y154250D01*
X759583Y154000D01*
X759250Y153417D01*
X759083Y152917D01*
Y152417D01*
X759250Y151917D01*
X759667Y151417D01*
X760167Y151083D01*
X760750Y151000D01*
X761333Y151167D01*
X761917Y151667D01*
G01X764850Y151583D02*
X765267Y151250D01*
X765850Y151000D01*
X766350D01*
X766850Y151167D01*
X767183Y151417D01*
X767350Y151750D01*
X767267Y152250D01*
X766933Y152500D01*
X765433Y153000D01*
X765100Y153583D01*
X765267Y154000D01*
X765600Y154250D01*
X766100Y154333D01*
X766600Y154250D01*
X767100Y154000D01*
G01X771700Y154333D02*
Y151000D01*
G01Y155667D02*
X771533Y155750D01*
Y155917D01*
X771700Y156000D01*
X771867Y155917D01*
Y155750D01*
X771700Y155667D01*
G01X775883Y151000D02*
Y154333D01*
G01Y153500D02*
X776217Y153917D01*
X776717Y154250D01*
X777383Y154333D01*
X777967Y154250D01*
X778467Y153917D01*
X778717Y153333D01*
Y151000D01*
G01X787917Y149500D02*
X789083Y150667D01*
Y151833D01*
X787917D01*
Y150667D01*
X789083D01*
G01Y152667D02*
Y153833D01*
X787917D01*
Y152667D01*
X789083D01*
G01X792267Y151000D02*
Y156000D01*
X793933D01*
X794600Y155750D01*
X795100Y155417D01*
X795517Y154917D01*
X795850Y154333D01*
X795933Y153500D01*
X795850Y152667D01*
X795517Y152083D01*
X795100Y151583D01*
X794600Y151250D01*
X793933Y151000D01*
X792267D01*
G01X799700D02*
X799200Y151083D01*
X798700Y151417D01*
X798367Y152000D01*
X798200Y152667D01*
X798367Y153333D01*
X798700Y153917D01*
X799200Y154250D01*
X799700Y154333D01*
X800200Y154250D01*
X800700Y153917D01*
X801033Y153333D01*
X801117Y152667D01*
X801033Y152000D01*
X800700Y151417D01*
X800200Y151083D01*
X799700Y151000D01*
G01X809483D02*
Y154333D01*
G01Y153500D02*
X809817Y153917D01*
X810317Y154250D01*
X810983Y154333D01*
X811567Y154250D01*
X812067Y153917D01*
X812317Y153333D01*
Y151000D01*
G01X816500D02*
X816000Y151083D01*
X815500Y151417D01*
X815167Y152000D01*
X815000Y152667D01*
X815167Y153333D01*
X815500Y153917D01*
X816000Y154250D01*
X816500Y154333D01*
X817000Y154250D01*
X817500Y153917D01*
X817833Y153333D01*
X817917Y152667D01*
X817833Y152000D01*
X817500Y151417D01*
X817000Y151083D01*
X816500Y151000D01*
G01X822100Y156000D02*
Y151000D01*
G01X820933Y154333D02*
X823267D01*
G01X834800Y151000D02*
Y154333D01*
G01Y153750D02*
X834467Y154083D01*
X833967Y154250D01*
X833383Y154333D01*
X832800Y154167D01*
X832300Y153833D01*
X831967Y153333D01*
X831800Y152667D01*
X831967Y152000D01*
X832300Y151500D01*
X832800Y151167D01*
X833383Y151000D01*
X833967Y151083D01*
X834467Y151333D01*
X834800Y151667D01*
G01X838900Y151000D02*
Y156000D01*
G01X844500Y151000D02*
Y156000D01*
G01X850100Y151000D02*
X849600Y151083D01*
X849100Y151417D01*
X848767Y152000D01*
X848600Y152667D01*
X848767Y153333D01*
X849100Y153917D01*
X849600Y154250D01*
X850100Y154333D01*
X850600Y154250D01*
X851100Y153917D01*
X851433Y153333D01*
X851517Y152667D01*
X851433Y152000D01*
X851100Y151417D01*
X850600Y151083D01*
X850100Y151000D01*
G01X853617Y154333D02*
X854617Y151000D01*
X855700Y154333D01*
X856783Y151000D01*
X857783Y154333D01*
G01X566917Y172500D02*
X569000Y167500D01*
X571083Y172500D01*
G01X574600Y170833D02*
Y167500D01*
G01Y172167D02*
X574433Y172250D01*
Y172417D01*
X574600Y172500D01*
X574767Y172417D01*
Y172250D01*
X574600Y172167D01*
G01X581700Y167500D02*
Y170833D01*
G01Y170250D02*
X581367Y170583D01*
X580867Y170750D01*
X580283Y170833D01*
X579700Y170667D01*
X579200Y170333D01*
X578867Y169833D01*
X578700Y169167D01*
X578867Y168500D01*
X579200Y168000D01*
X579700Y167667D01*
X580283Y167500D01*
X580867Y167583D01*
X581367Y167833D01*
X581700Y168167D01*
G01X590150Y168083D02*
X590567Y167750D01*
X591150Y167500D01*
X591650D01*
X592150Y167667D01*
X592483Y167917D01*
X592650Y168250D01*
X592567Y168750D01*
X592233Y169000D01*
X590733Y169500D01*
X590400Y170083D01*
X590567Y170500D01*
X590900Y170750D01*
X591400Y170833D01*
X591900Y170750D01*
X592400Y170500D01*
G01X595583Y167500D02*
Y172500D01*
G01Y170083D02*
X596000Y170500D01*
X596417Y170750D01*
X597083Y170833D01*
X597583Y170750D01*
X598167Y170417D01*
X598417Y169917D01*
Y167500D01*
G01X602600D02*
X602100Y167583D01*
X601600Y167917D01*
X601267Y168500D01*
X601100Y169167D01*
X601267Y169833D01*
X601600Y170417D01*
X602100Y170750D01*
X602600Y170833D01*
X603100Y170750D01*
X603600Y170417D01*
X603933Y169833D01*
X604017Y169167D01*
X603933Y168500D01*
X603600Y167917D01*
X603100Y167583D01*
X602600Y167500D01*
G01X606783Y170833D02*
Y168500D01*
X607117Y167917D01*
X607617Y167583D01*
X608200Y167500D01*
X608783Y167583D01*
X609283Y167917D01*
X609617Y168500D01*
G01Y167500D02*
Y170833D01*
G01X613800Y167500D02*
Y172500D01*
G01X620900D02*
Y167500D01*
G01Y168250D02*
X620567Y167833D01*
X620067Y167583D01*
X619483Y167500D01*
X618817Y167667D01*
X618317Y168083D01*
X617983Y168583D01*
X617900Y169167D01*
X617983Y169750D01*
X618317Y170250D01*
X618817Y170667D01*
X619483Y170833D01*
X620067Y170750D01*
X620483Y170583D01*
X620900Y170250D01*
G01X629100Y167500D02*
Y172500D01*
G01Y170000D02*
X629517Y170500D01*
X630017Y170750D01*
X630517Y170833D01*
X631267Y170667D01*
X631767Y170333D01*
X632100Y169750D01*
Y169083D01*
X631933Y168417D01*
X631600Y167917D01*
X631017Y167583D01*
X630517Y167500D01*
X630017Y167583D01*
X629517Y167833D01*
X629100Y168250D01*
G01X634950Y169750D02*
X637617D01*
X637367Y170333D01*
X636950Y170667D01*
X636367Y170833D01*
X635783Y170750D01*
X635283Y170500D01*
X634950Y169917D01*
X634783Y169417D01*
Y168917D01*
X634950Y168417D01*
X635367Y167917D01*
X635867Y167583D01*
X636450Y167500D01*
X637033Y167667D01*
X637617Y168167D01*
G01X645900Y165833D02*
Y170833D01*
G01Y170083D02*
X646317Y170500D01*
X646733Y170750D01*
X647400Y170833D01*
X647983Y170750D01*
X648567Y170333D01*
X648817Y169750D01*
X648900Y169167D01*
X648817Y168583D01*
X648567Y168000D01*
X648067Y167667D01*
X647400Y167500D01*
X646817Y167583D01*
X646233Y167833D01*
X645900Y168167D01*
G01X653000Y167500D02*
Y172500D01*
G01X657183Y170833D02*
Y168500D01*
X657517Y167917D01*
X658017Y167583D01*
X658600Y167500D01*
X659183Y167583D01*
X659683Y167917D01*
X660017Y168500D01*
G01Y167500D02*
Y170833D01*
G01X663033Y166250D02*
X663617Y165917D01*
X664283Y165833D01*
X664867Y165917D01*
X665367Y166333D01*
X665700Y166917D01*
Y170833D01*
G01Y170167D02*
X665367Y170500D01*
X664867Y170750D01*
X664283Y170833D01*
X663617Y170667D01*
X663200Y170333D01*
X662867Y169750D01*
X662700Y169167D01*
X662783Y168667D01*
X663117Y168083D01*
X663617Y167667D01*
X664283Y167500D01*
X664783Y167583D01*
X665367Y167917D01*
X665700Y168250D01*
G01X668633Y166250D02*
X669217Y165917D01*
X669883Y165833D01*
X670467Y165917D01*
X670967Y166333D01*
X671300Y166917D01*
Y170833D01*
G01Y170167D02*
X670967Y170500D01*
X670467Y170750D01*
X669883Y170833D01*
X669217Y170667D01*
X668800Y170333D01*
X668467Y169750D01*
X668300Y169167D01*
X668383Y168667D01*
X668717Y168083D01*
X669217Y167667D01*
X669883Y167500D01*
X670383Y167583D01*
X670967Y167917D01*
X671300Y168250D01*
G01X674150Y169750D02*
X676817D01*
X676567Y170333D01*
X676150Y170667D01*
X675567Y170833D01*
X674983Y170750D01*
X674483Y170500D01*
X674150Y169917D01*
X673983Y169417D01*
Y168917D01*
X674150Y168417D01*
X674567Y167917D01*
X675067Y167583D01*
X675650Y167500D01*
X676233Y167667D01*
X676817Y168167D01*
G01X682500Y172500D02*
Y167500D01*
G01Y168250D02*
X682167Y167833D01*
X681667Y167583D01*
X681083Y167500D01*
X680417Y167667D01*
X679917Y168083D01*
X679583Y168583D01*
X679500Y169167D01*
X679583Y169750D01*
X679917Y170250D01*
X680417Y170667D01*
X681083Y170833D01*
X681667Y170750D01*
X682083Y170583D01*
X682500Y170250D01*
G01X690117Y170833D02*
X691117Y167500D01*
X692200Y170833D01*
X693283Y167500D01*
X694283Y170833D01*
G01X697800D02*
Y167500D01*
G01Y172167D02*
X697633Y172250D01*
Y172417D01*
X697800Y172500D01*
X697967Y172417D01*
Y172250D01*
X697800Y172167D01*
G01X703400Y172500D02*
Y167500D01*
G01X702233Y170833D02*
X704567D01*
G01X707583Y167500D02*
Y172500D01*
G01Y170083D02*
X708000Y170500D01*
X708417Y170750D01*
X709083Y170833D01*
X709583Y170750D01*
X710167Y170417D01*
X710417Y169917D01*
Y167500D01*
G01X718533D02*
X721867Y169167D01*
X718533Y170833D01*
G01X724383Y168083D02*
X724967Y167667D01*
X725633Y167500D01*
X726300Y167667D01*
X726883Y168167D01*
X727300Y168917D01*
X727467Y169667D01*
Y170583D01*
X727300Y171333D01*
X726883Y172000D01*
X726383Y172333D01*
X725800Y172500D01*
X725133Y172333D01*
X724633Y172000D01*
X724300Y171500D01*
X724133Y170833D01*
X724300Y170250D01*
X724717Y169667D01*
X725217Y169333D01*
X725800Y169250D01*
X726467Y169417D01*
X726967Y169833D01*
X727467Y170583D01*
G01X731400Y172500D02*
X730733Y172333D01*
X730233Y171917D01*
X729900Y171417D01*
X729650Y170750D01*
X729567Y170000D01*
X729650Y169250D01*
X729900Y168583D01*
X730233Y168083D01*
X730733Y167667D01*
X731400Y167500D01*
X732067Y167667D01*
X732567Y168083D01*
X732900Y168583D01*
X733150Y169250D01*
X733233Y170000D01*
X733150Y170750D01*
X732900Y171417D01*
X732567Y171917D01*
X732067Y172333D01*
X731400Y172500D01*
G01X735500Y167333D02*
X738500Y172500D01*
G01X735500D02*
X735000Y172333D01*
X734750Y172083D01*
X734583Y171583D01*
X734750Y171083D01*
X735000Y170833D01*
X735500Y170667D01*
X736000Y170833D01*
X736250Y171083D01*
X736417Y171583D01*
X736250Y172083D01*
X736000Y172333D01*
X735500Y172500D01*
G01X738500Y169167D02*
X738000Y169000D01*
X737750Y168750D01*
X737583Y168250D01*
X737750Y167750D01*
X738000Y167500D01*
X738500Y167333D01*
X739000Y167500D01*
X739250Y167750D01*
X739417Y168250D01*
X739250Y168750D01*
X739000Y169000D01*
X738500Y169167D01*
G01X747033Y167500D02*
Y170833D01*
G01Y170167D02*
X747450Y170500D01*
X747867Y170750D01*
X748450Y170833D01*
X748867Y170750D01*
X749367Y170500D01*
G01X752550Y169750D02*
X755217D01*
X754967Y170333D01*
X754550Y170667D01*
X753967Y170833D01*
X753383Y170750D01*
X752883Y170500D01*
X752550Y169917D01*
X752383Y169417D01*
Y168917D01*
X752550Y168417D01*
X752967Y167917D01*
X753467Y167583D01*
X754050Y167500D01*
X754633Y167667D01*
X755217Y168167D01*
G01X758150Y168083D02*
X758567Y167750D01*
X759150Y167500D01*
X759650D01*
X760150Y167667D01*
X760483Y167917D01*
X760650Y168250D01*
X760567Y168750D01*
X760233Y169000D01*
X758733Y169500D01*
X758400Y170083D01*
X758567Y170500D01*
X758900Y170750D01*
X759400Y170833D01*
X759900Y170750D01*
X760400Y170500D01*
G01X765000Y170833D02*
Y167500D01*
G01Y172167D02*
X764833Y172250D01*
Y172417D01*
X765000Y172500D01*
X765167Y172417D01*
Y172250D01*
X765000Y172167D01*
G01X769183Y167500D02*
Y170833D01*
G01Y170000D02*
X769517Y170417D01*
X770017Y170750D01*
X770683Y170833D01*
X771267Y170750D01*
X771767Y170417D01*
X772017Y169833D01*
Y167500D01*
G01X565417Y193500D02*
X567500Y188500D01*
X569583Y193500D01*
G01X573100Y191833D02*
Y188500D01*
G01Y193167D02*
X572933Y193250D01*
Y193417D01*
X573100Y193500D01*
X573267Y193417D01*
Y193250D01*
X573100Y193167D01*
G01X580200Y188500D02*
Y191833D01*
G01Y191250D02*
X579867Y191583D01*
X579367Y191750D01*
X578783Y191833D01*
X578200Y191667D01*
X577700Y191333D01*
X577367Y190833D01*
X577200Y190167D01*
X577367Y189500D01*
X577700Y189000D01*
X578200Y188667D01*
X578783Y188500D01*
X579367Y188583D01*
X579867Y188833D01*
X580200Y189167D01*
G01X588650Y189083D02*
X589067Y188750D01*
X589650Y188500D01*
X590150D01*
X590650Y188667D01*
X590983Y188917D01*
X591150Y189250D01*
X591067Y189750D01*
X590733Y190000D01*
X589233Y190500D01*
X588900Y191083D01*
X589067Y191500D01*
X589400Y191750D01*
X589900Y191833D01*
X590400Y191750D01*
X590900Y191500D01*
G01X594083Y188500D02*
Y193500D01*
G01Y191083D02*
X594500Y191500D01*
X594917Y191750D01*
X595583Y191833D01*
X596083Y191750D01*
X596667Y191417D01*
X596917Y190917D01*
Y188500D01*
G01X601100D02*
X600600Y188583D01*
X600100Y188917D01*
X599767Y189500D01*
X599600Y190167D01*
X599767Y190833D01*
X600100Y191417D01*
X600600Y191750D01*
X601100Y191833D01*
X601600Y191750D01*
X602100Y191417D01*
X602433Y190833D01*
X602517Y190167D01*
X602433Y189500D01*
X602100Y188917D01*
X601600Y188583D01*
X601100Y188500D01*
G01X605283Y191833D02*
Y189500D01*
X605617Y188917D01*
X606117Y188583D01*
X606700Y188500D01*
X607283Y188583D01*
X607783Y188917D01*
X608117Y189500D01*
G01Y188500D02*
Y191833D01*
G01X612300Y188500D02*
Y193500D01*
G01X619400D02*
Y188500D01*
G01Y189250D02*
X619067Y188833D01*
X618567Y188583D01*
X617983Y188500D01*
X617317Y188667D01*
X616817Y189083D01*
X616483Y189583D01*
X616400Y190167D01*
X616483Y190750D01*
X616817Y191250D01*
X617317Y191667D01*
X617983Y191833D01*
X618567Y191750D01*
X618983Y191583D01*
X619400Y191250D01*
G01X627600Y188500D02*
Y193500D01*
G01Y191000D02*
X628017Y191500D01*
X628517Y191750D01*
X629017Y191833D01*
X629767Y191667D01*
X630267Y191333D01*
X630600Y190750D01*
Y190083D01*
X630433Y189417D01*
X630100Y188917D01*
X629517Y188583D01*
X629017Y188500D01*
X628517Y188583D01*
X628017Y188833D01*
X627600Y189250D01*
G01X633450Y190750D02*
X636117D01*
X635867Y191333D01*
X635450Y191667D01*
X634867Y191833D01*
X634283Y191750D01*
X633783Y191500D01*
X633450Y190917D01*
X633283Y190417D01*
Y189917D01*
X633450Y189417D01*
X633867Y188917D01*
X634367Y188583D01*
X634950Y188500D01*
X635533Y188667D01*
X636117Y189167D01*
G01X644400Y186833D02*
Y191833D01*
G01Y191083D02*
X644817Y191500D01*
X645233Y191750D01*
X645900Y191833D01*
X646483Y191750D01*
X647067Y191333D01*
X647317Y190750D01*
X647400Y190167D01*
X647317Y189583D01*
X647067Y189000D01*
X646567Y188667D01*
X645900Y188500D01*
X645317Y188583D01*
X644733Y188833D01*
X644400Y189167D01*
G01X651500Y188500D02*
Y193500D01*
G01X655683Y191833D02*
Y189500D01*
X656017Y188917D01*
X656517Y188583D01*
X657100Y188500D01*
X657683Y188583D01*
X658183Y188917D01*
X658517Y189500D01*
G01Y188500D02*
Y191833D01*
G01X661533Y187250D02*
X662117Y186917D01*
X662783Y186833D01*
X663367Y186917D01*
X663867Y187333D01*
X664200Y187917D01*
Y191833D01*
G01Y191167D02*
X663867Y191500D01*
X663367Y191750D01*
X662783Y191833D01*
X662117Y191667D01*
X661700Y191333D01*
X661367Y190750D01*
X661200Y190167D01*
X661283Y189667D01*
X661617Y189083D01*
X662117Y188667D01*
X662783Y188500D01*
X663283Y188583D01*
X663867Y188917D01*
X664200Y189250D01*
G01X667133Y187250D02*
X667717Y186917D01*
X668383Y186833D01*
X668967Y186917D01*
X669467Y187333D01*
X669800Y187917D01*
Y191833D01*
G01Y191167D02*
X669467Y191500D01*
X668967Y191750D01*
X668383Y191833D01*
X667717Y191667D01*
X667300Y191333D01*
X666967Y190750D01*
X666800Y190167D01*
X666883Y189667D01*
X667217Y189083D01*
X667717Y188667D01*
X668383Y188500D01*
X668883Y188583D01*
X669467Y188917D01*
X669800Y189250D01*
G01X672650Y190750D02*
X675317D01*
X675067Y191333D01*
X674650Y191667D01*
X674067Y191833D01*
X673483Y191750D01*
X672983Y191500D01*
X672650Y190917D01*
X672483Y190417D01*
Y189917D01*
X672650Y189417D01*
X673067Y188917D01*
X673567Y188583D01*
X674150Y188500D01*
X674733Y188667D01*
X675317Y189167D01*
G01X681000Y193500D02*
Y188500D01*
G01Y189250D02*
X680667Y188833D01*
X680167Y188583D01*
X679583Y188500D01*
X678917Y188667D01*
X678417Y189083D01*
X678083Y189583D01*
X678000Y190167D01*
X678083Y190750D01*
X678417Y191250D01*
X678917Y191667D01*
X679583Y191833D01*
X680167Y191750D01*
X680583Y191583D01*
X681000Y191250D01*
G01X691700Y188500D02*
Y193500D01*
X688617Y189917D01*
X692783D01*
G01X696300Y193500D02*
X695633Y193333D01*
X695133Y192917D01*
X694800Y192417D01*
X694550Y191750D01*
X694467Y191000D01*
X694550Y190250D01*
X694800Y189583D01*
X695133Y189083D01*
X695633Y188667D01*
X696300Y188500D01*
X696967Y188667D01*
X697467Y189083D01*
X697800Y189583D01*
X698050Y190250D01*
X698133Y191000D01*
X698050Y191750D01*
X697800Y192417D01*
X697467Y192917D01*
X696967Y193333D01*
X696300Y193500D01*
G01X700400Y188333D02*
X703400Y193500D01*
G01X700400D02*
X699900Y193333D01*
X699650Y193083D01*
X699483Y192583D01*
X699650Y192083D01*
X699900Y191833D01*
X700400Y191667D01*
X700900Y191833D01*
X701150Y192083D01*
X701317Y192583D01*
X701150Y193083D01*
X700900Y193333D01*
X700400Y193500D01*
G01X703400Y190167D02*
X702900Y190000D01*
X702650Y189750D01*
X702483Y189250D01*
X702650Y188750D01*
X702900Y188500D01*
X703400Y188333D01*
X703900Y188500D01*
X704150Y188750D01*
X704317Y189250D01*
X704150Y189750D01*
X703900Y190000D01*
X703400Y190167D01*
G01X710600D02*
X711433Y191833D01*
X712267D01*
X713933Y188500D01*
X714767D01*
X715600Y190167D01*
G01X724300Y188500D02*
Y193500D01*
X723300Y192500D01*
G01Y188500D02*
X725300D01*
G01X729900Y193500D02*
X729233Y193333D01*
X728733Y192917D01*
X728400Y192417D01*
X728150Y191750D01*
X728067Y191000D01*
X728150Y190250D01*
X728400Y189583D01*
X728733Y189083D01*
X729233Y188667D01*
X729900Y188500D01*
X730567Y188667D01*
X731067Y189083D01*
X731400Y189583D01*
X731650Y190250D01*
X731733Y191000D01*
X731650Y191750D01*
X731400Y192417D01*
X731067Y192917D01*
X730567Y193333D01*
X729900Y193500D01*
G01X735500D02*
X734833Y193333D01*
X734333Y192917D01*
X734000Y192417D01*
X733750Y191750D01*
X733667Y191000D01*
X733750Y190250D01*
X734000Y189583D01*
X734333Y189083D01*
X734833Y188667D01*
X735500Y188500D01*
X736167Y188667D01*
X736667Y189083D01*
X737000Y189583D01*
X737250Y190250D01*
X737333Y191000D01*
X737250Y191750D01*
X737000Y192417D01*
X736667Y192917D01*
X736167Y193333D01*
X735500Y193500D01*
G01X739600Y188333D02*
X742600Y193500D01*
G01X739600D02*
X739100Y193333D01*
X738850Y193083D01*
X738683Y192583D01*
X738850Y192083D01*
X739100Y191833D01*
X739600Y191667D01*
X740100Y191833D01*
X740350Y192083D01*
X740517Y192583D01*
X740350Y193083D01*
X740100Y193333D01*
X739600Y193500D01*
G01X742600Y190167D02*
X742100Y190000D01*
X741850Y189750D01*
X741683Y189250D01*
X741850Y188750D01*
X742100Y188500D01*
X742600Y188333D01*
X743100Y188500D01*
X743350Y188750D01*
X743517Y189250D01*
X743350Y189750D01*
X743100Y190000D01*
X742600Y190167D01*
G01X751050Y189083D02*
X751467Y188750D01*
X752050Y188500D01*
X752550D01*
X753050Y188667D01*
X753383Y188917D01*
X753550Y189250D01*
X753467Y189750D01*
X753133Y190000D01*
X751633Y190500D01*
X751300Y191083D01*
X751467Y191500D01*
X751800Y191750D01*
X752300Y191833D01*
X752800Y191750D01*
X753300Y191500D01*
G01X757900Y188500D02*
X757400Y188583D01*
X756900Y188917D01*
X756567Y189500D01*
X756400Y190167D01*
X756567Y190833D01*
X756900Y191417D01*
X757400Y191750D01*
X757900Y191833D01*
X758400Y191750D01*
X758900Y191417D01*
X759233Y190833D01*
X759317Y190167D01*
X759233Y189500D01*
X758900Y188917D01*
X758400Y188583D01*
X757900Y188500D01*
G01X763500D02*
Y193500D01*
G01X770600D02*
Y188500D01*
G01Y189250D02*
X770267Y188833D01*
X769767Y188583D01*
X769183Y188500D01*
X768517Y188667D01*
X768017Y189083D01*
X767683Y189583D01*
X767600Y190167D01*
X767683Y190750D01*
X768017Y191250D01*
X768517Y191667D01*
X769183Y191833D01*
X769767Y191750D01*
X770183Y191583D01*
X770600Y191250D01*
G01X773450Y190750D02*
X776117D01*
X775867Y191333D01*
X775450Y191667D01*
X774867Y191833D01*
X774283Y191750D01*
X773783Y191500D01*
X773450Y190917D01*
X773283Y190417D01*
Y189917D01*
X773450Y189417D01*
X773867Y188917D01*
X774367Y188583D01*
X774950Y188500D01*
X775533Y188667D01*
X776117Y189167D01*
G01X779133Y188500D02*
Y191833D01*
G01Y191167D02*
X779550Y191500D01*
X779967Y191750D01*
X780550Y191833D01*
X780967Y191750D01*
X781467Y191500D01*
G01X789000Y188500D02*
Y191833D01*
G01Y190917D02*
X789250Y191333D01*
X789667Y191667D01*
X790250Y191833D01*
X790833Y191667D01*
X791250Y191333D01*
X791500Y190917D01*
Y188500D01*
G01Y190917D02*
X791750Y191333D01*
X792167Y191667D01*
X792750Y191833D01*
X793333Y191667D01*
X793750Y191333D01*
X794000Y190833D01*
Y188500D01*
G01X798600D02*
Y191833D01*
G01Y191250D02*
X798267Y191583D01*
X797767Y191750D01*
X797183Y191833D01*
X796600Y191667D01*
X796100Y191333D01*
X795767Y190833D01*
X795600Y190167D01*
X795767Y189500D01*
X796100Y189000D01*
X796600Y188667D01*
X797183Y188500D01*
X797767Y188583D01*
X798267Y188833D01*
X798600Y189167D01*
G01X801450Y189083D02*
X801867Y188750D01*
X802450Y188500D01*
X802950D01*
X803450Y188667D01*
X803783Y188917D01*
X803950Y189250D01*
X803867Y189750D01*
X803533Y190000D01*
X802033Y190500D01*
X801700Y191083D01*
X801867Y191500D01*
X802200Y191750D01*
X802700Y191833D01*
X803200Y191750D01*
X803700Y191500D01*
G01X806883Y188500D02*
Y193500D01*
G01X809550Y191833D02*
X806883Y189917D01*
G01X807967Y190667D02*
X809717Y188500D01*
G01X561917Y269667D02*
X562417Y270167D01*
X563000Y270417D01*
X563667Y270500D01*
X564500Y270333D01*
X565083Y269917D01*
X565250Y269417D01*
X565167Y268917D01*
X564833Y268500D01*
X563167Y267667D01*
X562417Y267083D01*
X561917Y266250D01*
X561750Y265500D01*
X565250D01*
G01X569100Y265333D02*
X568933Y265417D01*
Y265583D01*
X569100Y265667D01*
X569267Y265583D01*
Y265417D01*
X569100Y265333D01*
G01X574700Y270500D02*
Y265500D01*
G01X572783Y270500D02*
X576617D01*
G01X578883Y265500D02*
Y270500D01*
G01Y268083D02*
X579300Y268500D01*
X579717Y268750D01*
X580383Y268833D01*
X580883Y268750D01*
X581467Y268417D01*
X581717Y267917D01*
Y265500D01*
G01X584650Y267750D02*
X587317D01*
X587067Y268333D01*
X586650Y268667D01*
X586067Y268833D01*
X585483Y268750D01*
X584983Y268500D01*
X584650Y267917D01*
X584483Y267417D01*
Y266917D01*
X584650Y266417D01*
X585067Y265917D01*
X585567Y265583D01*
X586150Y265500D01*
X586733Y265667D01*
X587317Y266167D01*
G01X595850Y266083D02*
X596267Y265750D01*
X596850Y265500D01*
X597350D01*
X597850Y265667D01*
X598183Y265917D01*
X598350Y266250D01*
X598267Y266750D01*
X597933Y267000D01*
X596433Y267500D01*
X596100Y268083D01*
X596267Y268500D01*
X596600Y268750D01*
X597100Y268833D01*
X597600Y268750D01*
X598100Y268500D01*
G01X602700Y268833D02*
Y265500D01*
G01Y270167D02*
X602533Y270250D01*
Y270417D01*
X602700Y270500D01*
X602867Y270417D01*
Y270250D01*
X602700Y270167D01*
G01X609800Y270500D02*
Y265500D01*
G01Y266250D02*
X609467Y265833D01*
X608967Y265583D01*
X608383Y265500D01*
X607717Y265667D01*
X607217Y266083D01*
X606883Y266583D01*
X606800Y267167D01*
X606883Y267750D01*
X607217Y268250D01*
X607717Y268667D01*
X608383Y268833D01*
X608967Y268750D01*
X609383Y268583D01*
X609800Y268250D01*
G01X612650Y267750D02*
X615317D01*
X615067Y268333D01*
X614650Y268667D01*
X614067Y268833D01*
X613483Y268750D01*
X612983Y268500D01*
X612650Y267917D01*
X612483Y267417D01*
Y266917D01*
X612650Y266417D01*
X613067Y265917D01*
X613567Y265583D01*
X614150Y265500D01*
X614733Y265667D01*
X615317Y266167D01*
G01X623017Y268833D02*
X624017Y265500D01*
X625100Y268833D01*
X626183Y265500D01*
X627183Y268833D01*
G01X630700D02*
Y265500D01*
G01Y270167D02*
X630533Y270250D01*
Y270417D01*
X630700Y270500D01*
X630867Y270417D01*
Y270250D01*
X630700Y270167D01*
G01X636300Y270500D02*
Y265500D01*
G01X635133Y268833D02*
X637467D01*
G01X640483Y265500D02*
Y270500D01*
G01Y268083D02*
X640900Y268500D01*
X641317Y268750D01*
X641983Y268833D01*
X642483Y268750D01*
X643067Y268417D01*
X643317Y267917D01*
Y265500D01*
G01X651850Y266083D02*
X652267Y265750D01*
X652850Y265500D01*
X653350D01*
X653850Y265667D01*
X654183Y265917D01*
X654350Y266250D01*
X654267Y266750D01*
X653933Y267000D01*
X652433Y267500D01*
X652100Y268083D01*
X652267Y268500D01*
X652600Y268750D01*
X653100Y268833D01*
X653600Y268750D01*
X654100Y268500D01*
G01X658700Y265500D02*
X658200Y265583D01*
X657700Y265917D01*
X657367Y266500D01*
X657200Y267167D01*
X657367Y267833D01*
X657700Y268417D01*
X658200Y268750D01*
X658700Y268833D01*
X659200Y268750D01*
X659700Y268417D01*
X660033Y267833D01*
X660117Y267167D01*
X660033Y266500D01*
X659700Y265917D01*
X659200Y265583D01*
X658700Y265500D01*
G01X664300D02*
Y270500D01*
G01X671400D02*
Y265500D01*
G01Y266250D02*
X671067Y265833D01*
X670567Y265583D01*
X669983Y265500D01*
X669317Y265667D01*
X668817Y266083D01*
X668483Y266583D01*
X668400Y267167D01*
X668483Y267750D01*
X668817Y268250D01*
X669317Y268667D01*
X669983Y268833D01*
X670567Y268750D01*
X670983Y268583D01*
X671400Y268250D01*
G01X674250Y267750D02*
X676917D01*
X676667Y268333D01*
X676250Y268667D01*
X675667Y268833D01*
X675083Y268750D01*
X674583Y268500D01*
X674250Y267917D01*
X674083Y267417D01*
Y266917D01*
X674250Y266417D01*
X674667Y265917D01*
X675167Y265583D01*
X675750Y265500D01*
X676333Y265667D01*
X676917Y266167D01*
G01X679933Y265500D02*
Y268833D01*
G01Y268167D02*
X680350Y268500D01*
X680767Y268750D01*
X681350Y268833D01*
X681767Y268750D01*
X682267Y268500D01*
G01X689800Y265500D02*
Y268833D01*
G01Y267917D02*
X690050Y268333D01*
X690467Y268667D01*
X691050Y268833D01*
X691633Y268667D01*
X692050Y268333D01*
X692300Y267917D01*
Y265500D01*
G01Y267917D02*
X692550Y268333D01*
X692967Y268667D01*
X693550Y268833D01*
X694133Y268667D01*
X694550Y268333D01*
X694800Y267833D01*
Y265500D01*
G01X699400D02*
Y268833D01*
G01Y268250D02*
X699067Y268583D01*
X698567Y268750D01*
X697983Y268833D01*
X697400Y268667D01*
X696900Y268333D01*
X696567Y267833D01*
X696400Y267167D01*
X696567Y266500D01*
X696900Y266000D01*
X697400Y265667D01*
X697983Y265500D01*
X698567Y265583D01*
X699067Y265833D01*
X699400Y266167D01*
G01X702250Y266083D02*
X702667Y265750D01*
X703250Y265500D01*
X703750D01*
X704250Y265667D01*
X704583Y265917D01*
X704750Y266250D01*
X704667Y266750D01*
X704333Y267000D01*
X702833Y267500D01*
X702500Y268083D01*
X702667Y268500D01*
X703000Y268750D01*
X703500Y268833D01*
X704000Y268750D01*
X704500Y268500D01*
G01X707683Y265500D02*
Y270500D01*
G01X710350Y268833D02*
X707683Y266917D01*
G01X708767Y267667D02*
X710517Y265500D01*
G01X718800Y263833D02*
Y268833D01*
G01Y268083D02*
X719217Y268500D01*
X719633Y268750D01*
X720300Y268833D01*
X720883Y268750D01*
X721467Y268333D01*
X721717Y267750D01*
X721800Y267167D01*
X721717Y266583D01*
X721467Y266000D01*
X720967Y265667D01*
X720300Y265500D01*
X719717Y265583D01*
X719133Y265833D01*
X718800Y266167D01*
G01X727400Y265500D02*
Y268833D01*
G01Y268250D02*
X727067Y268583D01*
X726567Y268750D01*
X725983Y268833D01*
X725400Y268667D01*
X724900Y268333D01*
X724567Y267833D01*
X724400Y267167D01*
X724567Y266500D01*
X724900Y266000D01*
X725400Y265667D01*
X725983Y265500D01*
X726567Y265583D01*
X727067Y265833D01*
X727400Y266167D01*
G01X733000Y270500D02*
Y265500D01*
G01Y266250D02*
X732667Y265833D01*
X732167Y265583D01*
X731583Y265500D01*
X730917Y265667D01*
X730417Y266083D01*
X730083Y266583D01*
X730000Y267167D01*
X730083Y267750D01*
X730417Y268250D01*
X730917Y268667D01*
X731583Y268833D01*
X732167Y268750D01*
X732583Y268583D01*
X733000Y268250D01*
G01X736933Y264583D02*
X737267Y265667D01*
G01X748300Y270500D02*
Y265500D01*
G01X747133Y268833D02*
X749467D01*
G01X752483Y265500D02*
Y270500D01*
G01Y268083D02*
X752900Y268500D01*
X753317Y268750D01*
X753983Y268833D01*
X754483Y268750D01*
X755067Y268417D01*
X755317Y267917D01*
Y265500D01*
G01X758250Y267750D02*
X760917D01*
X760667Y268333D01*
X760250Y268667D01*
X759667Y268833D01*
X759083Y268750D01*
X758583Y268500D01*
X758250Y267917D01*
X758083Y267417D01*
Y266917D01*
X758250Y266417D01*
X758667Y265917D01*
X759167Y265583D01*
X759750Y265500D01*
X760333Y265667D01*
X760917Y266167D01*
G01X772200Y265500D02*
Y268833D01*
G01Y268250D02*
X771867Y268583D01*
X771367Y268750D01*
X770783Y268833D01*
X770200Y268667D01*
X769700Y268333D01*
X769367Y267833D01*
X769200Y267167D01*
X769367Y266500D01*
X769700Y266000D01*
X770200Y265667D01*
X770783Y265500D01*
X771367Y265583D01*
X771867Y265833D01*
X772200Y266167D01*
G01X774883Y265500D02*
Y268833D01*
G01Y268000D02*
X775217Y268417D01*
X775717Y268750D01*
X776383Y268833D01*
X776967Y268750D01*
X777467Y268417D01*
X777717Y267833D01*
Y265500D01*
G01X780483D02*
Y268833D01*
G01Y268000D02*
X780817Y268417D01*
X781317Y268750D01*
X781983Y268833D01*
X782567Y268750D01*
X783067Y268417D01*
X783317Y267833D01*
Y265500D01*
G01X786083Y268833D02*
Y266500D01*
X786417Y265917D01*
X786917Y265583D01*
X787500Y265500D01*
X788083Y265583D01*
X788583Y265917D01*
X788917Y266500D01*
G01Y265500D02*
Y268833D01*
G01X794600Y265500D02*
Y268833D01*
G01Y268250D02*
X794267Y268583D01*
X793767Y268750D01*
X793183Y268833D01*
X792600Y268667D01*
X792100Y268333D01*
X791767Y267833D01*
X791600Y267167D01*
X791767Y266500D01*
X792100Y266000D01*
X792600Y265667D01*
X793183Y265500D01*
X793767Y265583D01*
X794267Y265833D01*
X794600Y266167D01*
G01X798700Y265500D02*
Y270500D01*
G01X808733Y265500D02*
Y268833D01*
G01Y268167D02*
X809150Y268500D01*
X809567Y268750D01*
X810150Y268833D01*
X810567Y268750D01*
X811067Y268500D01*
G01X815500Y268833D02*
Y265500D01*
G01Y270167D02*
X815333Y270250D01*
Y270417D01*
X815500Y270500D01*
X815667Y270417D01*
Y270250D01*
X815500Y270167D01*
G01X819683Y265500D02*
Y268833D01*
G01Y268000D02*
X820017Y268417D01*
X820517Y268750D01*
X821183Y268833D01*
X821767Y268750D01*
X822267Y268417D01*
X822517Y267833D01*
Y265500D01*
G01X825533Y264250D02*
X826117Y263917D01*
X826783Y263833D01*
X827367Y263917D01*
X827867Y264333D01*
X828200Y264917D01*
Y268833D01*
G01Y268167D02*
X827867Y268500D01*
X827367Y268750D01*
X826783Y268833D01*
X826117Y268667D01*
X825700Y268333D01*
X825367Y267750D01*
X825200Y267167D01*
X825283Y266667D01*
X825617Y266083D01*
X826117Y265667D01*
X826783Y265500D01*
X827283Y265583D01*
X827867Y265917D01*
X828200Y266250D01*
G01X836650Y266083D02*
X837067Y265750D01*
X837650Y265500D01*
X838150D01*
X838650Y265667D01*
X838983Y265917D01*
X839150Y266250D01*
X839067Y266750D01*
X838733Y267000D01*
X837233Y267500D01*
X836900Y268083D01*
X837067Y268500D01*
X837400Y268750D01*
X837900Y268833D01*
X838400Y268750D01*
X838900Y268500D01*
G01X842083Y265500D02*
Y270500D01*
G01Y268083D02*
X842500Y268500D01*
X842917Y268750D01*
X843583Y268833D01*
X844083Y268750D01*
X844667Y268417D01*
X844917Y267917D01*
Y265500D01*
G01X849100D02*
X848600Y265583D01*
X848100Y265917D01*
X847767Y266500D01*
X847600Y267167D01*
X847767Y267833D01*
X848100Y268417D01*
X848600Y268750D01*
X849100Y268833D01*
X849600Y268750D01*
X850100Y268417D01*
X850433Y267833D01*
X850517Y267167D01*
X850433Y266500D01*
X850100Y265917D01*
X849600Y265583D01*
X849100Y265500D01*
G01X853283Y268833D02*
Y266500D01*
X853617Y265917D01*
X854117Y265583D01*
X854700Y265500D01*
X855283Y265583D01*
X855783Y265917D01*
X856117Y266500D01*
G01Y265500D02*
Y268833D01*
G01X860300Y265500D02*
Y270500D01*
G01X867400D02*
Y265500D01*
G01Y266250D02*
X867067Y265833D01*
X866567Y265583D01*
X865983Y265500D01*
X865317Y265667D01*
X864817Y266083D01*
X864483Y266583D01*
X864400Y267167D01*
X864483Y267750D01*
X864817Y268250D01*
X865317Y268667D01*
X865983Y268833D01*
X866567Y268750D01*
X866983Y268583D01*
X867400Y268250D01*
G01X563500Y296500D02*
Y301500D01*
X562500Y300500D01*
G01Y296500D02*
X564500D01*
G01X569100Y296333D02*
X568933Y296417D01*
Y296583D01*
X569100Y296667D01*
X569267Y296583D01*
Y296417D01*
X569100Y296333D01*
G01X574700Y301500D02*
Y296500D01*
G01X572783Y301500D02*
X576617D01*
G01X578883Y296500D02*
Y301500D01*
G01Y299083D02*
X579300Y299500D01*
X579717Y299750D01*
X580383Y299833D01*
X580883Y299750D01*
X581467Y299417D01*
X581717Y298917D01*
Y296500D01*
G01X584650Y298750D02*
X587317D01*
X587067Y299333D01*
X586650Y299667D01*
X586067Y299833D01*
X585483Y299750D01*
X584983Y299500D01*
X584650Y298917D01*
X584483Y298417D01*
Y297917D01*
X584650Y297417D01*
X585067Y296917D01*
X585567Y296583D01*
X586150Y296500D01*
X586733Y296667D01*
X587317Y297167D01*
G01X595850Y297083D02*
X596267Y296750D01*
X596850Y296500D01*
X597350D01*
X597850Y296667D01*
X598183Y296917D01*
X598350Y297250D01*
X598267Y297750D01*
X597933Y298000D01*
X596433Y298500D01*
X596100Y299083D01*
X596267Y299500D01*
X596600Y299750D01*
X597100Y299833D01*
X597600Y299750D01*
X598100Y299500D01*
G01X602700Y299833D02*
Y296500D01*
G01Y301167D02*
X602533Y301250D01*
Y301417D01*
X602700Y301500D01*
X602867Y301417D01*
Y301250D01*
X602700Y301167D01*
G01X609800Y301500D02*
Y296500D01*
G01Y297250D02*
X609467Y296833D01*
X608967Y296583D01*
X608383Y296500D01*
X607717Y296667D01*
X607217Y297083D01*
X606883Y297583D01*
X606800Y298167D01*
X606883Y298750D01*
X607217Y299250D01*
X607717Y299667D01*
X608383Y299833D01*
X608967Y299750D01*
X609383Y299583D01*
X609800Y299250D01*
G01X612650Y298750D02*
X615317D01*
X615067Y299333D01*
X614650Y299667D01*
X614067Y299833D01*
X613483Y299750D01*
X612983Y299500D01*
X612650Y298917D01*
X612483Y298417D01*
Y297917D01*
X612650Y297417D01*
X613067Y296917D01*
X613567Y296583D01*
X614150Y296500D01*
X614733Y296667D01*
X615317Y297167D01*
G01X623017Y299833D02*
X624017Y296500D01*
X625100Y299833D01*
X626183Y296500D01*
X627183Y299833D01*
G01X630700D02*
Y296500D01*
G01Y301167D02*
X630533Y301250D01*
Y301417D01*
X630700Y301500D01*
X630867Y301417D01*
Y301250D01*
X630700Y301167D01*
G01X636300Y301500D02*
Y296500D01*
G01X635133Y299833D02*
X637467D01*
G01X640483Y296500D02*
Y301500D01*
G01Y299083D02*
X640900Y299500D01*
X641317Y299750D01*
X641983Y299833D01*
X642483Y299750D01*
X643067Y299417D01*
X643317Y298917D01*
Y296500D01*
G01X647500D02*
X647000Y296583D01*
X646500Y296917D01*
X646167Y297500D01*
X646000Y298167D01*
X646167Y298833D01*
X646500Y299417D01*
X647000Y299750D01*
X647500Y299833D01*
X648000Y299750D01*
X648500Y299417D01*
X648833Y298833D01*
X648917Y298167D01*
X648833Y297500D01*
X648500Y296917D01*
X648000Y296583D01*
X647500Y296500D01*
G01X651683Y299833D02*
Y297500D01*
X652017Y296917D01*
X652517Y296583D01*
X653100Y296500D01*
X653683Y296583D01*
X654183Y296917D01*
X654517Y297500D01*
G01Y296500D02*
Y299833D01*
G01X658700Y301500D02*
Y296500D01*
G01X657533Y299833D02*
X659867D01*
G01X668650Y297083D02*
X669067Y296750D01*
X669650Y296500D01*
X670150D01*
X670650Y296667D01*
X670983Y296917D01*
X671150Y297250D01*
X671067Y297750D01*
X670733Y298000D01*
X669233Y298500D01*
X668900Y299083D01*
X669067Y299500D01*
X669400Y299750D01*
X669900Y299833D01*
X670400Y299750D01*
X670900Y299500D01*
G01X675500Y296500D02*
X675000Y296583D01*
X674500Y296917D01*
X674167Y297500D01*
X674000Y298167D01*
X674167Y298833D01*
X674500Y299417D01*
X675000Y299750D01*
X675500Y299833D01*
X676000Y299750D01*
X676500Y299417D01*
X676833Y298833D01*
X676917Y298167D01*
X676833Y297500D01*
X676500Y296917D01*
X676000Y296583D01*
X675500Y296500D01*
G01X681100D02*
Y301500D01*
G01X688200D02*
Y296500D01*
G01Y297250D02*
X687867Y296833D01*
X687367Y296583D01*
X686783Y296500D01*
X686117Y296667D01*
X685617Y297083D01*
X685283Y297583D01*
X685200Y298167D01*
X685283Y298750D01*
X685617Y299250D01*
X686117Y299667D01*
X686783Y299833D01*
X687367Y299750D01*
X687783Y299583D01*
X688200Y299250D01*
G01X691050Y298750D02*
X693717D01*
X693467Y299333D01*
X693050Y299667D01*
X692467Y299833D01*
X691883Y299750D01*
X691383Y299500D01*
X691050Y298917D01*
X690883Y298417D01*
Y297917D01*
X691050Y297417D01*
X691467Y296917D01*
X691967Y296583D01*
X692550Y296500D01*
X693133Y296667D01*
X693717Y297167D01*
G01X696733Y296500D02*
Y299833D01*
G01Y299167D02*
X697150Y299500D01*
X697567Y299750D01*
X698150Y299833D01*
X698567Y299750D01*
X699067Y299500D01*
G01X706600Y296500D02*
Y299833D01*
G01Y298917D02*
X706850Y299333D01*
X707267Y299667D01*
X707850Y299833D01*
X708433Y299667D01*
X708850Y299333D01*
X709100Y298917D01*
Y296500D01*
G01Y298917D02*
X709350Y299333D01*
X709767Y299667D01*
X710350Y299833D01*
X710933Y299667D01*
X711350Y299333D01*
X711600Y298833D01*
Y296500D01*
G01X716200D02*
Y299833D01*
G01Y299250D02*
X715867Y299583D01*
X715367Y299750D01*
X714783Y299833D01*
X714200Y299667D01*
X713700Y299333D01*
X713367Y298833D01*
X713200Y298167D01*
X713367Y297500D01*
X713700Y297000D01*
X714200Y296667D01*
X714783Y296500D01*
X715367Y296583D01*
X715867Y296833D01*
X716200Y297167D01*
G01X719050Y297083D02*
X719467Y296750D01*
X720050Y296500D01*
X720550D01*
X721050Y296667D01*
X721383Y296917D01*
X721550Y297250D01*
X721467Y297750D01*
X721133Y298000D01*
X719633Y298500D01*
X719300Y299083D01*
X719467Y299500D01*
X719800Y299750D01*
X720300Y299833D01*
X720800Y299750D01*
X721300Y299500D01*
G01X724483Y296500D02*
Y301500D01*
G01X727150Y299833D02*
X724483Y297917D01*
G01X725567Y298667D02*
X727317Y296500D01*
G01X735600Y294833D02*
Y299833D01*
G01Y299083D02*
X736017Y299500D01*
X736433Y299750D01*
X737100Y299833D01*
X737683Y299750D01*
X738267Y299333D01*
X738517Y298750D01*
X738600Y298167D01*
X738517Y297583D01*
X738267Y297000D01*
X737767Y296667D01*
X737100Y296500D01*
X736517Y296583D01*
X735933Y296833D01*
X735600Y297167D01*
G01X744200Y296500D02*
Y299833D01*
G01Y299250D02*
X743867Y299583D01*
X743367Y299750D01*
X742783Y299833D01*
X742200Y299667D01*
X741700Y299333D01*
X741367Y298833D01*
X741200Y298167D01*
X741367Y297500D01*
X741700Y297000D01*
X742200Y296667D01*
X742783Y296500D01*
X743367Y296583D01*
X743867Y296833D01*
X744200Y297167D01*
G01X749800Y301500D02*
Y296500D01*
G01Y297250D02*
X749467Y296833D01*
X748967Y296583D01*
X748383Y296500D01*
X747717Y296667D01*
X747217Y297083D01*
X746883Y297583D01*
X746800Y298167D01*
X746883Y298750D01*
X747217Y299250D01*
X747717Y299667D01*
X748383Y299833D01*
X748967Y299750D01*
X749383Y299583D01*
X749800Y299250D01*
G01X759333Y295583D02*
X759667Y296667D01*
G01X772200Y296500D02*
Y299833D01*
G01Y299250D02*
X771867Y299583D01*
X771367Y299750D01*
X770783Y299833D01*
X770200Y299667D01*
X769700Y299333D01*
X769367Y298833D01*
X769200Y298167D01*
X769367Y297500D01*
X769700Y297000D01*
X770200Y296667D01*
X770783Y296500D01*
X771367Y296583D01*
X771867Y296833D01*
X772200Y297167D01*
G01X774883Y296500D02*
Y299833D01*
G01Y299000D02*
X775217Y299417D01*
X775717Y299750D01*
X776383Y299833D01*
X776967Y299750D01*
X777467Y299417D01*
X777717Y298833D01*
Y296500D01*
G01X780483D02*
Y299833D01*
G01Y299000D02*
X780817Y299417D01*
X781317Y299750D01*
X781983Y299833D01*
X782567Y299750D01*
X783067Y299417D01*
X783317Y298833D01*
Y296500D01*
G01X786083Y299833D02*
Y297500D01*
X786417Y296917D01*
X786917Y296583D01*
X787500Y296500D01*
X788083Y296583D01*
X788583Y296917D01*
X788917Y297500D01*
G01Y296500D02*
Y299833D01*
G01X794600Y296500D02*
Y299833D01*
G01Y299250D02*
X794267Y299583D01*
X793767Y299750D01*
X793183Y299833D01*
X792600Y299667D01*
X792100Y299333D01*
X791767Y298833D01*
X791600Y298167D01*
X791767Y297500D01*
X792100Y297000D01*
X792600Y296667D01*
X793183Y296500D01*
X793767Y296583D01*
X794267Y296833D01*
X794600Y297167D01*
G01X798700Y296500D02*
Y301500D01*
G01X808733Y296500D02*
Y299833D01*
G01Y299167D02*
X809150Y299500D01*
X809567Y299750D01*
X810150Y299833D01*
X810567Y299750D01*
X811067Y299500D01*
G01X815500Y299833D02*
Y296500D01*
G01Y301167D02*
X815333Y301250D01*
Y301417D01*
X815500Y301500D01*
X815667Y301417D01*
Y301250D01*
X815500Y301167D01*
G01X819683Y296500D02*
Y299833D01*
G01Y299000D02*
X820017Y299417D01*
X820517Y299750D01*
X821183Y299833D01*
X821767Y299750D01*
X822267Y299417D01*
X822517Y298833D01*
Y296500D01*
G01X825533Y295250D02*
X826117Y294917D01*
X826783Y294833D01*
X827367Y294917D01*
X827867Y295333D01*
X828200Y295917D01*
Y299833D01*
G01Y299167D02*
X827867Y299500D01*
X827367Y299750D01*
X826783Y299833D01*
X826117Y299667D01*
X825700Y299333D01*
X825367Y298750D01*
X825200Y298167D01*
X825283Y297667D01*
X825617Y297083D01*
X826117Y296667D01*
X826783Y296500D01*
X827283Y296583D01*
X827867Y296917D01*
X828200Y297250D01*
G01X836483Y296500D02*
Y299833D01*
G01Y299000D02*
X836817Y299417D01*
X837317Y299750D01*
X837983Y299833D01*
X838567Y299750D01*
X839067Y299417D01*
X839317Y298833D01*
Y296500D01*
G01X842250Y298750D02*
X844917D01*
X844667Y299333D01*
X844250Y299667D01*
X843667Y299833D01*
X843083Y299750D01*
X842583Y299500D01*
X842250Y298917D01*
X842083Y298417D01*
Y297917D01*
X842250Y297417D01*
X842667Y296917D01*
X843167Y296583D01*
X843750Y296500D01*
X844333Y296667D01*
X844917Y297167D01*
G01X847850Y298750D02*
X850517D01*
X850267Y299333D01*
X849850Y299667D01*
X849267Y299833D01*
X848683Y299750D01*
X848183Y299500D01*
X847850Y298917D01*
X847683Y298417D01*
Y297917D01*
X847850Y297417D01*
X848267Y296917D01*
X848767Y296583D01*
X849350Y296500D01*
X849933Y296667D01*
X850517Y297167D01*
G01X856200Y301500D02*
Y296500D01*
G01Y297250D02*
X855867Y296833D01*
X855367Y296583D01*
X854783Y296500D01*
X854117Y296667D01*
X853617Y297083D01*
X853283Y297583D01*
X853200Y298167D01*
X853283Y298750D01*
X853617Y299250D01*
X854117Y299667D01*
X854783Y299833D01*
X855367Y299750D01*
X855783Y299583D01*
X856200Y299250D01*
G01X553583Y457500D02*
Y460833D01*
G01Y460000D02*
X553917Y460417D01*
X554417Y460750D01*
X555083Y460833D01*
X555667Y460750D01*
X556167Y460417D01*
X556417Y459833D01*
Y457500D01*
G01X560600D02*
X560100Y457583D01*
X559600Y457917D01*
X559267Y458500D01*
X559100Y459167D01*
X559267Y459833D01*
X559600Y460417D01*
X560100Y460750D01*
X560600Y460833D01*
X561100Y460750D01*
X561600Y460417D01*
X561933Y459833D01*
X562017Y459167D01*
X561933Y458500D01*
X561600Y457917D01*
X561100Y457583D01*
X560600Y457500D01*
G01X570300Y455833D02*
Y460833D01*
G01Y460083D02*
X570717Y460500D01*
X571133Y460750D01*
X571800Y460833D01*
X572383Y460750D01*
X572967Y460333D01*
X573217Y459750D01*
X573300Y459167D01*
X573217Y458583D01*
X572967Y458000D01*
X572467Y457667D01*
X571800Y457500D01*
X571217Y457583D01*
X570633Y457833D01*
X570300Y458167D01*
G01X577400Y457500D02*
Y462500D01*
G01X581583Y460833D02*
Y458500D01*
X581917Y457917D01*
X582417Y457583D01*
X583000Y457500D01*
X583583Y457583D01*
X584083Y457917D01*
X584417Y458500D01*
G01Y457500D02*
Y460833D01*
G01X587433Y456250D02*
X588017Y455917D01*
X588683Y455833D01*
X589267Y455917D01*
X589767Y456333D01*
X590100Y456917D01*
Y460833D01*
G01Y460167D02*
X589767Y460500D01*
X589267Y460750D01*
X588683Y460833D01*
X588017Y460667D01*
X587600Y460333D01*
X587267Y459750D01*
X587100Y459167D01*
X587183Y458667D01*
X587517Y458083D01*
X588017Y457667D01*
X588683Y457500D01*
X589183Y457583D01*
X589767Y457917D01*
X590100Y458250D01*
G01X593033Y456250D02*
X593617Y455917D01*
X594283Y455833D01*
X594867Y455917D01*
X595367Y456333D01*
X595700Y456917D01*
Y460833D01*
G01Y460167D02*
X595367Y460500D01*
X594867Y460750D01*
X594283Y460833D01*
X593617Y460667D01*
X593200Y460333D01*
X592867Y459750D01*
X592700Y459167D01*
X592783Y458667D01*
X593117Y458083D01*
X593617Y457667D01*
X594283Y457500D01*
X594783Y457583D01*
X595367Y457917D01*
X595700Y458250D01*
G01X599800Y460833D02*
Y457500D01*
G01Y462167D02*
X599633Y462250D01*
Y462417D01*
X599800Y462500D01*
X599967Y462417D01*
Y462250D01*
X599800Y462167D01*
G01X603983Y457500D02*
Y460833D01*
G01Y460000D02*
X604317Y460417D01*
X604817Y460750D01*
X605483Y460833D01*
X606067Y460750D01*
X606567Y460417D01*
X606817Y459833D01*
Y457500D01*
G01X609833Y456250D02*
X610417Y455917D01*
X611083Y455833D01*
X611667Y455917D01*
X612167Y456333D01*
X612500Y456917D01*
Y460833D01*
G01Y460167D02*
X612167Y460500D01*
X611667Y460750D01*
X611083Y460833D01*
X610417Y460667D01*
X610000Y460333D01*
X609667Y459750D01*
X609500Y459167D01*
X609583Y458667D01*
X609917Y458083D01*
X610417Y457667D01*
X611083Y457500D01*
X611583Y457583D01*
X612167Y457917D01*
X612500Y458250D01*
G01X575000Y97500D02*
Y102500D01*
G01Y100000D02*
X575417Y100500D01*
X575917Y100750D01*
X576417Y100833D01*
X577167Y100667D01*
X577667Y100333D01*
X578000Y99750D01*
Y99083D01*
X577833Y98417D01*
X577500Y97917D01*
X576917Y97583D01*
X576417Y97500D01*
X575917Y97583D01*
X575417Y97833D01*
X575000Y98250D01*
G01X580683Y100833D02*
Y98500D01*
X581017Y97917D01*
X581517Y97583D01*
X582100Y97500D01*
X582683Y97583D01*
X583183Y97917D01*
X583517Y98500D01*
G01Y97500D02*
Y100833D01*
G01X586200Y97500D02*
Y102500D01*
G01Y100000D02*
X586617Y100500D01*
X587117Y100750D01*
X587617Y100833D01*
X588367Y100667D01*
X588867Y100333D01*
X589200Y99750D01*
Y99083D01*
X589033Y98417D01*
X588700Y97917D01*
X588117Y97583D01*
X587617Y97500D01*
X587117Y97583D01*
X586617Y97833D01*
X586200Y98250D01*
G01X591800Y97500D02*
Y102500D01*
G01Y100000D02*
X592217Y100500D01*
X592717Y100750D01*
X593217Y100833D01*
X593967Y100667D01*
X594467Y100333D01*
X594800Y99750D01*
Y99083D01*
X594633Y98417D01*
X594300Y97917D01*
X593717Y97583D01*
X593217Y97500D01*
X592717Y97583D01*
X592217Y97833D01*
X591800Y98250D01*
G01X598900Y97500D02*
Y102500D01*
G01X603250Y99750D02*
X605917D01*
X605667Y100333D01*
X605250Y100667D01*
X604667Y100833D01*
X604083Y100750D01*
X603583Y100500D01*
X603250Y99917D01*
X603083Y99417D01*
Y98917D01*
X603250Y98417D01*
X603667Y97917D01*
X604167Y97583D01*
X604750Y97500D01*
X605333Y97667D01*
X605917Y98167D01*
G01X615700Y100833D02*
Y97500D01*
G01Y102167D02*
X615533Y102250D01*
Y102417D01*
X615700Y102500D01*
X615867Y102417D01*
Y102250D01*
X615700Y102167D01*
G01X619883Y97500D02*
Y100833D01*
G01Y100000D02*
X620217Y100417D01*
X620717Y100750D01*
X621383Y100833D01*
X621967Y100750D01*
X622467Y100417D01*
X622717Y99833D01*
Y97500D01*
G01X625650Y98083D02*
X626067Y97750D01*
X626650Y97500D01*
X627150D01*
X627650Y97667D01*
X627983Y97917D01*
X628150Y98250D01*
X628067Y98750D01*
X627733Y99000D01*
X626233Y99500D01*
X625900Y100083D01*
X626067Y100500D01*
X626400Y100750D01*
X626900Y100833D01*
X627400Y100750D01*
X627900Y100500D01*
G01X632500Y100833D02*
Y97500D01*
G01Y102167D02*
X632333Y102250D01*
Y102417D01*
X632500Y102500D01*
X632667Y102417D01*
Y102250D01*
X632500Y102167D01*
G01X639600Y102500D02*
Y97500D01*
G01Y98250D02*
X639267Y97833D01*
X638767Y97583D01*
X638183Y97500D01*
X637517Y97667D01*
X637017Y98083D01*
X636683Y98583D01*
X636600Y99167D01*
X636683Y99750D01*
X637017Y100250D01*
X637517Y100667D01*
X638183Y100833D01*
X638767Y100750D01*
X639183Y100583D01*
X639600Y100250D01*
G01X642450Y99750D02*
X645117D01*
X644867Y100333D01*
X644450Y100667D01*
X643867Y100833D01*
X643283Y100750D01*
X642783Y100500D01*
X642450Y99917D01*
X642283Y99417D01*
Y98917D01*
X642450Y98417D01*
X642867Y97917D01*
X643367Y97583D01*
X643950Y97500D01*
X644533Y97667D01*
X645117Y98167D01*
G01X654900Y102500D02*
Y97500D01*
G01X653733Y100833D02*
X656067D01*
G01X659083Y97500D02*
Y102500D01*
G01Y100083D02*
X659500Y100500D01*
X659917Y100750D01*
X660583Y100833D01*
X661083Y100750D01*
X661667Y100417D01*
X661917Y99917D01*
Y97500D01*
G01X664850Y99750D02*
X667517D01*
X667267Y100333D01*
X666850Y100667D01*
X666267Y100833D01*
X665683Y100750D01*
X665183Y100500D01*
X664850Y99917D01*
X664683Y99417D01*
Y98917D01*
X664850Y98417D01*
X665267Y97917D01*
X665767Y97583D01*
X666350Y97500D01*
X666933Y97667D01*
X667517Y98167D01*
G01X676133Y97500D02*
Y100833D01*
G01Y100167D02*
X676550Y100500D01*
X676967Y100750D01*
X677550Y100833D01*
X677967Y100750D01*
X678467Y100500D01*
G01X681650Y99750D02*
X684317D01*
X684067Y100333D01*
X683650Y100667D01*
X683067Y100833D01*
X682483Y100750D01*
X681983Y100500D01*
X681650Y99917D01*
X681483Y99417D01*
Y98917D01*
X681650Y98417D01*
X682067Y97917D01*
X682567Y97583D01*
X683150Y97500D01*
X683733Y97667D01*
X684317Y98167D01*
G01X687250Y98083D02*
X687667Y97750D01*
X688250Y97500D01*
X688750D01*
X689250Y97667D01*
X689583Y97917D01*
X689750Y98250D01*
X689667Y98750D01*
X689333Y99000D01*
X687833Y99500D01*
X687500Y100083D01*
X687667Y100500D01*
X688000Y100750D01*
X688500Y100833D01*
X689000Y100750D01*
X689500Y100500D01*
G01X694100Y100833D02*
Y97500D01*
G01Y102167D02*
X693933Y102250D01*
Y102417D01*
X694100Y102500D01*
X694267Y102417D01*
Y102250D01*
X694100Y102167D01*
G01X698283Y97500D02*
Y100833D01*
G01Y100000D02*
X698617Y100417D01*
X699117Y100750D01*
X699783Y100833D01*
X700367Y100750D01*
X700867Y100417D01*
X701117Y99833D01*
Y97500D01*
G01X705300Y97333D02*
X705133Y97417D01*
Y97583D01*
X705300Y97667D01*
X705467Y97583D01*
Y97417D01*
X705300Y97333D01*
G01X575000Y140500D02*
Y145500D01*
G01Y143000D02*
X575417Y143500D01*
X575917Y143750D01*
X576417Y143833D01*
X577167Y143667D01*
X577667Y143333D01*
X578000Y142750D01*
Y142083D01*
X577833Y141417D01*
X577500Y140917D01*
X576917Y140583D01*
X576417Y140500D01*
X575917Y140583D01*
X575417Y140833D01*
X575000Y141250D01*
G01X580683Y143833D02*
Y141500D01*
X581017Y140917D01*
X581517Y140583D01*
X582100Y140500D01*
X582683Y140583D01*
X583183Y140917D01*
X583517Y141500D01*
G01Y140500D02*
Y143833D01*
G01X586200Y140500D02*
Y145500D01*
G01Y143000D02*
X586617Y143500D01*
X587117Y143750D01*
X587617Y143833D01*
X588367Y143667D01*
X588867Y143333D01*
X589200Y142750D01*
Y142083D01*
X589033Y141417D01*
X588700Y140917D01*
X588117Y140583D01*
X587617Y140500D01*
X587117Y140583D01*
X586617Y140833D01*
X586200Y141250D01*
G01X591800Y140500D02*
Y145500D01*
G01Y143000D02*
X592217Y143500D01*
X592717Y143750D01*
X593217Y143833D01*
X593967Y143667D01*
X594467Y143333D01*
X594800Y142750D01*
Y142083D01*
X594633Y141417D01*
X594300Y140917D01*
X593717Y140583D01*
X593217Y140500D01*
X592717Y140583D01*
X592217Y140833D01*
X591800Y141250D01*
G01X598900Y140500D02*
Y145500D01*
G01X603250Y142750D02*
X605917D01*
X605667Y143333D01*
X605250Y143667D01*
X604667Y143833D01*
X604083Y143750D01*
X603583Y143500D01*
X603250Y142917D01*
X603083Y142417D01*
Y141917D01*
X603250Y141417D01*
X603667Y140917D01*
X604167Y140583D01*
X604750Y140500D01*
X605333Y140667D01*
X605917Y141167D01*
G01X615700Y143833D02*
Y140500D01*
G01Y145167D02*
X615533Y145250D01*
Y145417D01*
X615700Y145500D01*
X615867Y145417D01*
Y145250D01*
X615700Y145167D01*
G01X619883Y140500D02*
Y143833D01*
G01Y143000D02*
X620217Y143417D01*
X620717Y143750D01*
X621383Y143833D01*
X621967Y143750D01*
X622467Y143417D01*
X622717Y142833D01*
Y140500D01*
G01X625650Y141083D02*
X626067Y140750D01*
X626650Y140500D01*
X627150D01*
X627650Y140667D01*
X627983Y140917D01*
X628150Y141250D01*
X628067Y141750D01*
X627733Y142000D01*
X626233Y142500D01*
X625900Y143083D01*
X626067Y143500D01*
X626400Y143750D01*
X626900Y143833D01*
X627400Y143750D01*
X627900Y143500D01*
G01X632500Y143833D02*
Y140500D01*
G01Y145167D02*
X632333Y145250D01*
Y145417D01*
X632500Y145500D01*
X632667Y145417D01*
Y145250D01*
X632500Y145167D01*
G01X639600Y145500D02*
Y140500D01*
G01Y141250D02*
X639267Y140833D01*
X638767Y140583D01*
X638183Y140500D01*
X637517Y140667D01*
X637017Y141083D01*
X636683Y141583D01*
X636600Y142167D01*
X636683Y142750D01*
X637017Y143250D01*
X637517Y143667D01*
X638183Y143833D01*
X638767Y143750D01*
X639183Y143583D01*
X639600Y143250D01*
G01X642450Y142750D02*
X645117D01*
X644867Y143333D01*
X644450Y143667D01*
X643867Y143833D01*
X643283Y143750D01*
X642783Y143500D01*
X642450Y142917D01*
X642283Y142417D01*
Y141917D01*
X642450Y141417D01*
X642867Y140917D01*
X643367Y140583D01*
X643950Y140500D01*
X644533Y140667D01*
X645117Y141167D01*
G01X654900Y145500D02*
Y140500D01*
G01X653733Y143833D02*
X656067D01*
G01X659083Y140500D02*
Y145500D01*
G01Y143083D02*
X659500Y143500D01*
X659917Y143750D01*
X660583Y143833D01*
X661083Y143750D01*
X661667Y143417D01*
X661917Y142917D01*
Y140500D01*
G01X664850Y142750D02*
X667517D01*
X667267Y143333D01*
X666850Y143667D01*
X666267Y143833D01*
X665683Y143750D01*
X665183Y143500D01*
X664850Y142917D01*
X664683Y142417D01*
Y141917D01*
X664850Y141417D01*
X665267Y140917D01*
X665767Y140583D01*
X666350Y140500D01*
X666933Y140667D01*
X667517Y141167D01*
G01X676133Y140500D02*
Y143833D01*
G01Y143167D02*
X676550Y143500D01*
X676967Y143750D01*
X677550Y143833D01*
X677967Y143750D01*
X678467Y143500D01*
G01X681650Y142750D02*
X684317D01*
X684067Y143333D01*
X683650Y143667D01*
X683067Y143833D01*
X682483Y143750D01*
X681983Y143500D01*
X681650Y142917D01*
X681483Y142417D01*
Y141917D01*
X681650Y141417D01*
X682067Y140917D01*
X682567Y140583D01*
X683150Y140500D01*
X683733Y140667D01*
X684317Y141167D01*
G01X687250Y141083D02*
X687667Y140750D01*
X688250Y140500D01*
X688750D01*
X689250Y140667D01*
X689583Y140917D01*
X689750Y141250D01*
X689667Y141750D01*
X689333Y142000D01*
X687833Y142500D01*
X687500Y143083D01*
X687667Y143500D01*
X688000Y143750D01*
X688500Y143833D01*
X689000Y143750D01*
X689500Y143500D01*
G01X694100Y143833D02*
Y140500D01*
G01Y145167D02*
X693933Y145250D01*
Y145417D01*
X694100Y145500D01*
X694267Y145417D01*
Y145250D01*
X694100Y145167D01*
G01X698283Y140500D02*
Y143833D01*
G01Y143000D02*
X698617Y143417D01*
X699117Y143750D01*
X699783Y143833D01*
X700367Y143750D01*
X700867Y143417D01*
X701117Y142833D01*
Y140500D01*
G01X705300Y140333D02*
X705133Y140417D01*
Y140583D01*
X705300Y140667D01*
X705467Y140583D01*
Y140417D01*
X705300Y140333D01*
G01X577000Y218500D02*
Y223500D01*
G01Y221000D02*
X577417Y221500D01*
X577917Y221750D01*
X578417Y221833D01*
X579167Y221667D01*
X579667Y221333D01*
X580000Y220750D01*
Y220083D01*
X579833Y219417D01*
X579500Y218917D01*
X578917Y218583D01*
X578417Y218500D01*
X577917Y218583D01*
X577417Y218833D01*
X577000Y219250D01*
G01X584100Y218333D02*
X583933Y218417D01*
Y218583D01*
X584100Y218667D01*
X584267Y218583D01*
Y218417D01*
X584100Y218333D01*
G01X590367Y221167D02*
X590700Y221417D01*
X590950Y221833D01*
X591117Y222417D01*
X590950Y222917D01*
X590617Y223250D01*
X590033Y223500D01*
X587783D01*
Y218500D01*
X590533D01*
X591117Y218833D01*
X591450Y219333D01*
X591617Y219917D01*
X591450Y220500D01*
X590950Y221000D01*
X590367Y221167D01*
X587783D01*
G01X595300Y218500D02*
X594800Y218583D01*
X594300Y218917D01*
X593967Y219500D01*
X593800Y220167D01*
X593967Y220833D01*
X594300Y221417D01*
X594800Y221750D01*
X595300Y221833D01*
X595800Y221750D01*
X596300Y221417D01*
X596633Y220833D01*
X596717Y220167D01*
X596633Y219500D01*
X596300Y218917D01*
X595800Y218583D01*
X595300Y218500D01*
G01X602400D02*
Y221833D01*
G01Y221250D02*
X602067Y221583D01*
X601567Y221750D01*
X600983Y221833D01*
X600400Y221667D01*
X599900Y221333D01*
X599567Y220833D01*
X599400Y220167D01*
X599567Y219500D01*
X599900Y219000D01*
X600400Y218667D01*
X600983Y218500D01*
X601567Y218583D01*
X602067Y218833D01*
X602400Y219167D01*
G01X605333Y218500D02*
Y221833D01*
G01Y221167D02*
X605750Y221500D01*
X606167Y221750D01*
X606750Y221833D01*
X607167Y221750D01*
X607667Y221500D01*
G01X613600Y223500D02*
Y218500D01*
G01Y219250D02*
X613267Y218833D01*
X612767Y218583D01*
X612183Y218500D01*
X611517Y218667D01*
X611017Y219083D01*
X610683Y219583D01*
X610600Y220167D01*
X610683Y220750D01*
X611017Y221250D01*
X611517Y221667D01*
X612183Y221833D01*
X612767Y221750D01*
X613183Y221583D01*
X613600Y221250D01*
G01X623300Y223500D02*
Y218500D01*
G01X622133Y221833D02*
X624467D01*
G01X627483Y218500D02*
Y223500D01*
G01Y221083D02*
X627900Y221500D01*
X628317Y221750D01*
X628983Y221833D01*
X629483Y221750D01*
X630067Y221417D01*
X630317Y220917D01*
Y218500D01*
G01X634500Y221833D02*
Y218500D01*
G01Y223167D02*
X634333Y223250D01*
Y223417D01*
X634500Y223500D01*
X634667Y223417D01*
Y223250D01*
X634500Y223167D01*
G01X641433Y221417D02*
X640850Y221750D01*
X640350Y221833D01*
X639683Y221667D01*
X639183Y221333D01*
X638850Y220750D01*
X638767Y220167D01*
X638850Y219583D01*
X639183Y219083D01*
X639683Y218667D01*
X640350Y218500D01*
X640933Y218667D01*
X641433Y219000D01*
G01X644283Y218500D02*
Y223500D01*
G01X646950Y221833D02*
X644283Y219917D01*
G01X645367Y220667D02*
X647117Y218500D01*
G01X649883D02*
Y221833D01*
G01Y221000D02*
X650217Y221417D01*
X650717Y221750D01*
X651383Y221833D01*
X651967Y221750D01*
X652467Y221417D01*
X652717Y220833D01*
Y218500D01*
G01X655650Y220750D02*
X658317D01*
X658067Y221333D01*
X657650Y221667D01*
X657067Y221833D01*
X656483Y221750D01*
X655983Y221500D01*
X655650Y220917D01*
X655483Y220417D01*
Y219917D01*
X655650Y219417D01*
X656067Y218917D01*
X656567Y218583D01*
X657150Y218500D01*
X657733Y218667D01*
X658317Y219167D01*
G01X661250Y219083D02*
X661667Y218750D01*
X662250Y218500D01*
X662750D01*
X663250Y218667D01*
X663583Y218917D01*
X663750Y219250D01*
X663667Y219750D01*
X663333Y220000D01*
X661833Y220500D01*
X661500Y221083D01*
X661667Y221500D01*
X662000Y221750D01*
X662500Y221833D01*
X663000Y221750D01*
X663500Y221500D01*
G01X666850Y219083D02*
X667267Y218750D01*
X667850Y218500D01*
X668350D01*
X668850Y218667D01*
X669183Y218917D01*
X669350Y219250D01*
X669267Y219750D01*
X668933Y220000D01*
X667433Y220500D01*
X667100Y221083D01*
X667267Y221500D01*
X667600Y221750D01*
X668100Y221833D01*
X668600Y221750D01*
X669100Y221500D01*
G01X680967Y218500D02*
X677633Y220167D01*
X680967Y221833D01*
G01X690500Y223500D02*
X689833Y223333D01*
X689333Y222917D01*
X689000Y222417D01*
X688750Y221750D01*
X688667Y221000D01*
X688750Y220250D01*
X689000Y219583D01*
X689333Y219083D01*
X689833Y218667D01*
X690500Y218500D01*
X691167Y218667D01*
X691667Y219083D01*
X692000Y219583D01*
X692250Y220250D01*
X692333Y221000D01*
X692250Y221750D01*
X692000Y222417D01*
X691667Y222917D01*
X691167Y223333D01*
X690500Y223500D01*
G01X696100Y218333D02*
X695933Y218417D01*
Y218583D01*
X696100Y218667D01*
X696267Y218583D01*
Y218417D01*
X696100Y218333D01*
G01X700283Y219083D02*
X700867Y218667D01*
X701533Y218500D01*
X702200Y218667D01*
X702783Y219167D01*
X703200Y219917D01*
X703367Y220667D01*
Y221583D01*
X703200Y222333D01*
X702783Y223000D01*
X702283Y223333D01*
X701700Y223500D01*
X701033Y223333D01*
X700533Y223000D01*
X700200Y222500D01*
X700033Y221833D01*
X700200Y221250D01*
X700617Y220667D01*
X701117Y220333D01*
X701700Y220250D01*
X702367Y220417D01*
X702867Y220833D01*
X703367Y221583D01*
G01X704800Y218500D02*
Y221833D01*
G01Y220917D02*
X705050Y221333D01*
X705467Y221667D01*
X706050Y221833D01*
X706633Y221667D01*
X707050Y221333D01*
X707300Y220917D01*
Y218500D01*
G01Y220917D02*
X707550Y221333D01*
X707967Y221667D01*
X708550Y221833D01*
X709133Y221667D01*
X709550Y221333D01*
X709800Y220833D01*
Y218500D01*
G01X710400D02*
Y221833D01*
G01Y220917D02*
X710650Y221333D01*
X711067Y221667D01*
X711650Y221833D01*
X712233Y221667D01*
X712650Y221333D01*
X712900Y220917D01*
Y218500D01*
G01Y220917D02*
X713150Y221333D01*
X713567Y221667D01*
X714150Y221833D01*
X714733Y221667D01*
X715150Y221333D01*
X715400Y220833D01*
Y218500D01*
G01X718500Y218333D02*
X718333Y218417D01*
Y218583D01*
X718500Y218667D01*
X718667Y218583D01*
Y218417D01*
X718500Y218333D01*
G01Y220583D02*
X718333Y220667D01*
Y220833D01*
X718500Y220917D01*
X718667Y220833D01*
Y220667D01*
X718500Y220583D01*
G01X580000Y237500D02*
Y240833D01*
G01Y240250D02*
X579667Y240583D01*
X579167Y240750D01*
X578583Y240833D01*
X578000Y240667D01*
X577500Y240333D01*
X577167Y239833D01*
X577000Y239167D01*
X577167Y238500D01*
X577500Y238000D01*
X578000Y237667D01*
X578583Y237500D01*
X579167Y237583D01*
X579667Y237833D01*
X580000Y238167D01*
G01X584100Y237333D02*
X583933Y237417D01*
Y237583D01*
X584100Y237667D01*
X584267Y237583D01*
Y237417D01*
X584100Y237333D01*
G01X590367Y240167D02*
X590700Y240417D01*
X590950Y240833D01*
X591117Y241417D01*
X590950Y241917D01*
X590617Y242250D01*
X590033Y242500D01*
X587783D01*
Y237500D01*
X590533D01*
X591117Y237833D01*
X591450Y238333D01*
X591617Y238917D01*
X591450Y239500D01*
X590950Y240000D01*
X590367Y240167D01*
X587783D01*
G01X595300Y237500D02*
X594800Y237583D01*
X594300Y237917D01*
X593967Y238500D01*
X593800Y239167D01*
X593967Y239833D01*
X594300Y240417D01*
X594800Y240750D01*
X595300Y240833D01*
X595800Y240750D01*
X596300Y240417D01*
X596633Y239833D01*
X596717Y239167D01*
X596633Y238500D01*
X596300Y237917D01*
X595800Y237583D01*
X595300Y237500D01*
G01X602400D02*
Y240833D01*
G01Y240250D02*
X602067Y240583D01*
X601567Y240750D01*
X600983Y240833D01*
X600400Y240667D01*
X599900Y240333D01*
X599567Y239833D01*
X599400Y239167D01*
X599567Y238500D01*
X599900Y238000D01*
X600400Y237667D01*
X600983Y237500D01*
X601567Y237583D01*
X602067Y237833D01*
X602400Y238167D01*
G01X605333Y237500D02*
Y240833D01*
G01Y240167D02*
X605750Y240500D01*
X606167Y240750D01*
X606750Y240833D01*
X607167Y240750D01*
X607667Y240500D01*
G01X613600Y242500D02*
Y237500D01*
G01Y238250D02*
X613267Y237833D01*
X612767Y237583D01*
X612183Y237500D01*
X611517Y237667D01*
X611017Y238083D01*
X610683Y238583D01*
X610600Y239167D01*
X610683Y239750D01*
X611017Y240250D01*
X611517Y240667D01*
X612183Y240833D01*
X612767Y240750D01*
X613183Y240583D01*
X613600Y240250D01*
G01X623300Y242500D02*
Y237500D01*
G01X622133Y240833D02*
X624467D01*
G01X627483Y237500D02*
Y242500D01*
G01Y240083D02*
X627900Y240500D01*
X628317Y240750D01*
X628983Y240833D01*
X629483Y240750D01*
X630067Y240417D01*
X630317Y239917D01*
Y237500D01*
G01X634500Y240833D02*
Y237500D01*
G01Y242167D02*
X634333Y242250D01*
Y242417D01*
X634500Y242500D01*
X634667Y242417D01*
Y242250D01*
X634500Y242167D01*
G01X641433Y240417D02*
X640850Y240750D01*
X640350Y240833D01*
X639683Y240667D01*
X639183Y240333D01*
X638850Y239750D01*
X638767Y239167D01*
X638850Y238583D01*
X639183Y238083D01*
X639683Y237667D01*
X640350Y237500D01*
X640933Y237667D01*
X641433Y238000D01*
G01X644283Y237500D02*
Y242500D01*
G01X646950Y240833D02*
X644283Y238917D01*
G01X645367Y239667D02*
X647117Y237500D01*
G01X649883D02*
Y240833D01*
G01Y240000D02*
X650217Y240417D01*
X650717Y240750D01*
X651383Y240833D01*
X651967Y240750D01*
X652467Y240417D01*
X652717Y239833D01*
Y237500D01*
G01X655650Y239750D02*
X658317D01*
X658067Y240333D01*
X657650Y240667D01*
X657067Y240833D01*
X656483Y240750D01*
X655983Y240500D01*
X655650Y239917D01*
X655483Y239417D01*
Y238917D01*
X655650Y238417D01*
X656067Y237917D01*
X656567Y237583D01*
X657150Y237500D01*
X657733Y237667D01*
X658317Y238167D01*
G01X661250Y238083D02*
X661667Y237750D01*
X662250Y237500D01*
X662750D01*
X663250Y237667D01*
X663583Y237917D01*
X663750Y238250D01*
X663667Y238750D01*
X663333Y239000D01*
X661833Y239500D01*
X661500Y240083D01*
X661667Y240500D01*
X662000Y240750D01*
X662500Y240833D01*
X663000Y240750D01*
X663500Y240500D01*
G01X666850Y238083D02*
X667267Y237750D01*
X667850Y237500D01*
X668350D01*
X668850Y237667D01*
X669183Y237917D01*
X669350Y238250D01*
X669267Y238750D01*
X668933Y239000D01*
X667433Y239500D01*
X667100Y240083D01*
X667267Y240500D01*
X667600Y240750D01*
X668100Y240833D01*
X668600Y240750D01*
X669100Y240500D01*
G01X672033Y237500D02*
X675367Y239167D01*
X672033Y240833D01*
G01X678217Y238417D02*
X680383D01*
G01Y239917D02*
X678217D01*
G01X690500Y242500D02*
X689833Y242333D01*
X689333Y241917D01*
X689000Y241417D01*
X688750Y240750D01*
X688667Y240000D01*
X688750Y239250D01*
X689000Y238583D01*
X689333Y238083D01*
X689833Y237667D01*
X690500Y237500D01*
X691167Y237667D01*
X691667Y238083D01*
X692000Y238583D01*
X692250Y239250D01*
X692333Y240000D01*
X692250Y240750D01*
X692000Y241417D01*
X691667Y241917D01*
X691167Y242333D01*
X690500Y242500D01*
G01X696100Y237333D02*
X695933Y237417D01*
Y237583D01*
X696100Y237667D01*
X696267Y237583D01*
Y237417D01*
X696100Y237333D01*
G01X700283Y238083D02*
X700867Y237667D01*
X701533Y237500D01*
X702200Y237667D01*
X702783Y238167D01*
X703200Y238917D01*
X703367Y239667D01*
Y240583D01*
X703200Y241333D01*
X702783Y242000D01*
X702283Y242333D01*
X701700Y242500D01*
X701033Y242333D01*
X700533Y242000D01*
X700200Y241500D01*
X700033Y240833D01*
X700200Y240250D01*
X700617Y239667D01*
X701117Y239333D01*
X701700Y239250D01*
X702367Y239417D01*
X702867Y239833D01*
X703367Y240583D01*
G01X704800Y237500D02*
Y240833D01*
G01Y239917D02*
X705050Y240333D01*
X705467Y240667D01*
X706050Y240833D01*
X706633Y240667D01*
X707050Y240333D01*
X707300Y239917D01*
Y237500D01*
G01Y239917D02*
X707550Y240333D01*
X707967Y240667D01*
X708550Y240833D01*
X709133Y240667D01*
X709550Y240333D01*
X709800Y239833D01*
Y237500D01*
G01X712900Y237333D02*
X712733Y237417D01*
Y237583D01*
X712900Y237667D01*
X713067Y237583D01*
Y237417D01*
X712900Y237333D01*
G01Y239583D02*
X712733Y239667D01*
Y239833D01*
X712900Y239917D01*
X713067Y239833D01*
Y239667D01*
X712900Y239583D01*
G01X575750Y247500D02*
Y252500D01*
G01X579250D02*
Y247500D01*
G01Y250000D02*
X575750D01*
G01X584600Y247500D02*
Y250833D01*
G01Y250250D02*
X584267Y250583D01*
X583767Y250750D01*
X583183Y250833D01*
X582600Y250667D01*
X582100Y250333D01*
X581767Y249833D01*
X581600Y249167D01*
X581767Y248500D01*
X582100Y248000D01*
X582600Y247667D01*
X583183Y247500D01*
X583767Y247583D01*
X584267Y247833D01*
X584600Y248167D01*
G01X588700Y247500D02*
Y252500D01*
G01X593800Y247500D02*
Y251750D01*
X593967Y252167D01*
X594300Y252417D01*
X594800Y252500D01*
X595300Y252333D01*
X595550Y251917D01*
G01X594550Y250500D02*
X592883D01*
G01X598817Y249167D02*
X600983D01*
G01X604000Y245833D02*
Y250833D01*
G01Y250083D02*
X604417Y250500D01*
X604833Y250750D01*
X605500Y250833D01*
X606083Y250750D01*
X606667Y250333D01*
X606917Y249750D01*
X607000Y249167D01*
X606917Y248583D01*
X606667Y248000D01*
X606167Y247667D01*
X605500Y247500D01*
X604917Y247583D01*
X604333Y247833D01*
X604000Y248167D01*
G01X611100Y247500D02*
Y252500D01*
G01X615283Y250833D02*
Y248500D01*
X615617Y247917D01*
X616117Y247583D01*
X616700Y247500D01*
X617283Y247583D01*
X617783Y247917D01*
X618117Y248500D01*
G01Y247500D02*
Y250833D01*
G01X621133Y246250D02*
X621717Y245917D01*
X622383Y245833D01*
X622967Y245917D01*
X623467Y246333D01*
X623800Y246917D01*
Y250833D01*
G01Y250167D02*
X623467Y250500D01*
X622967Y250750D01*
X622383Y250833D01*
X621717Y250667D01*
X621300Y250333D01*
X620967Y249750D01*
X620800Y249167D01*
X620883Y248667D01*
X621217Y248083D01*
X621717Y247667D01*
X622383Y247500D01*
X622883Y247583D01*
X623467Y247917D01*
X623800Y248250D01*
G01X626733Y246250D02*
X627317Y245917D01*
X627983Y245833D01*
X628567Y245917D01*
X629067Y246333D01*
X629400Y246917D01*
Y250833D01*
G01Y250167D02*
X629067Y250500D01*
X628567Y250750D01*
X627983Y250833D01*
X627317Y250667D01*
X626900Y250333D01*
X626567Y249750D01*
X626400Y249167D01*
X626483Y248667D01*
X626817Y248083D01*
X627317Y247667D01*
X627983Y247500D01*
X628483Y247583D01*
X629067Y247917D01*
X629400Y248250D01*
G01X633500Y250833D02*
Y247500D01*
G01Y252167D02*
X633333Y252250D01*
Y252417D01*
X633500Y252500D01*
X633667Y252417D01*
Y252250D01*
X633500Y252167D01*
G01X637683Y247500D02*
Y250833D01*
G01Y250000D02*
X638017Y250417D01*
X638517Y250750D01*
X639183Y250833D01*
X639767Y250750D01*
X640267Y250417D01*
X640517Y249833D01*
Y247500D01*
G01X643533Y246250D02*
X644117Y245917D01*
X644783Y245833D01*
X645367Y245917D01*
X645867Y246333D01*
X646200Y246917D01*
Y250833D01*
G01Y250167D02*
X645867Y250500D01*
X645367Y250750D01*
X644783Y250833D01*
X644117Y250667D01*
X643700Y250333D01*
X643367Y249750D01*
X643200Y249167D01*
X643283Y248667D01*
X643617Y248083D01*
X644117Y247667D01*
X644783Y247500D01*
X645283Y247583D01*
X645867Y247917D01*
X646200Y248250D01*
G01X655900Y247333D02*
X655733Y247417D01*
Y247583D01*
X655900Y247667D01*
X656067Y247583D01*
Y247417D01*
X655900Y247333D01*
G01Y249583D02*
X655733Y249667D01*
Y249833D01*
X655900Y249917D01*
X656067Y249833D01*
Y249667D01*
X655900Y249583D01*
G01X667100Y252500D02*
Y247500D01*
G01X665933Y250833D02*
X668267D01*
G01X671283Y247500D02*
Y252500D01*
G01Y250083D02*
X671700Y250500D01*
X672117Y250750D01*
X672783Y250833D01*
X673283Y250750D01*
X673867Y250417D01*
X674117Y249917D01*
Y247500D01*
G01X677050Y249750D02*
X679717D01*
X679467Y250333D01*
X679050Y250667D01*
X678467Y250833D01*
X677883Y250750D01*
X677383Y250500D01*
X677050Y249917D01*
X676883Y249417D01*
Y248917D01*
X677050Y248417D01*
X677467Y247917D01*
X677967Y247583D01*
X678550Y247500D01*
X679133Y247667D01*
X679717Y248167D01*
G01X688000Y245833D02*
Y250833D01*
G01Y250083D02*
X688417Y250500D01*
X688833Y250750D01*
X689500Y250833D01*
X690083Y250750D01*
X690667Y250333D01*
X690917Y249750D01*
X691000Y249167D01*
X690917Y248583D01*
X690667Y248000D01*
X690167Y247667D01*
X689500Y247500D01*
X688917Y247583D01*
X688333Y247833D01*
X688000Y248167D01*
G01X695100Y247500D02*
Y252500D01*
G01X699283Y250833D02*
Y248500D01*
X699617Y247917D01*
X700117Y247583D01*
X700700Y247500D01*
X701283Y247583D01*
X701783Y247917D01*
X702117Y248500D01*
G01Y247500D02*
Y250833D01*
G01X705133Y246250D02*
X705717Y245917D01*
X706383Y245833D01*
X706967Y245917D01*
X707467Y246333D01*
X707800Y246917D01*
Y250833D01*
G01Y250167D02*
X707467Y250500D01*
X706967Y250750D01*
X706383Y250833D01*
X705717Y250667D01*
X705300Y250333D01*
X704967Y249750D01*
X704800Y249167D01*
X704883Y248667D01*
X705217Y248083D01*
X705717Y247667D01*
X706383Y247500D01*
X706883Y247583D01*
X707467Y247917D01*
X707800Y248250D01*
G01X710733Y246250D02*
X711317Y245917D01*
X711983Y245833D01*
X712567Y245917D01*
X713067Y246333D01*
X713400Y246917D01*
Y250833D01*
G01Y250167D02*
X713067Y250500D01*
X712567Y250750D01*
X711983Y250833D01*
X711317Y250667D01*
X710900Y250333D01*
X710567Y249750D01*
X710400Y249167D01*
X710483Y248667D01*
X710817Y248083D01*
X711317Y247667D01*
X711983Y247500D01*
X712483Y247583D01*
X713067Y247917D01*
X713400Y248250D01*
G01X717500Y250833D02*
Y247500D01*
G01Y252167D02*
X717333Y252250D01*
Y252417D01*
X717500Y252500D01*
X717667Y252417D01*
Y252250D01*
X717500Y252167D01*
G01X721683Y247500D02*
Y250833D01*
G01Y250000D02*
X722017Y250417D01*
X722517Y250750D01*
X723183Y250833D01*
X723767Y250750D01*
X724267Y250417D01*
X724517Y249833D01*
Y247500D01*
G01X727533Y246250D02*
X728117Y245917D01*
X728783Y245833D01*
X729367Y245917D01*
X729867Y246333D01*
X730200Y246917D01*
Y250833D01*
G01Y250167D02*
X729867Y250500D01*
X729367Y250750D01*
X728783Y250833D01*
X728117Y250667D01*
X727700Y250333D01*
X727367Y249750D01*
X727200Y249167D01*
X727283Y248667D01*
X727617Y248083D01*
X728117Y247667D01*
X728783Y247500D01*
X729283Y247583D01*
X729867Y247917D01*
X730200Y248250D01*
G01X738733Y247500D02*
Y250833D01*
G01Y250167D02*
X739150Y250500D01*
X739567Y250750D01*
X740150Y250833D01*
X740567Y250750D01*
X741067Y250500D01*
G01X747000Y247500D02*
Y250833D01*
G01Y250250D02*
X746667Y250583D01*
X746167Y250750D01*
X745583Y250833D01*
X745000Y250667D01*
X744500Y250333D01*
X744167Y249833D01*
X744000Y249167D01*
X744167Y248500D01*
X744500Y248000D01*
X745000Y247667D01*
X745583Y247500D01*
X746167Y247583D01*
X746667Y247833D01*
X747000Y248167D01*
G01X751100Y252500D02*
Y247500D01*
G01X749933Y250833D02*
X752267D01*
G01X756700D02*
Y247500D01*
G01Y252167D02*
X756533Y252250D01*
Y252417D01*
X756700Y252500D01*
X756867Y252417D01*
Y252250D01*
X756700Y252167D01*
G01X762300Y247500D02*
X761800Y247583D01*
X761300Y247917D01*
X760967Y248500D01*
X760800Y249167D01*
X760967Y249833D01*
X761300Y250417D01*
X761800Y250750D01*
X762300Y250833D01*
X762800Y250750D01*
X763300Y250417D01*
X763633Y249833D01*
X763717Y249167D01*
X763633Y248500D01*
X763300Y247917D01*
X762800Y247583D01*
X762300Y247500D01*
G01X772000Y245833D02*
Y250833D01*
G01Y250083D02*
X772417Y250500D01*
X772833Y250750D01*
X773500Y250833D01*
X774083Y250750D01*
X774667Y250333D01*
X774917Y249750D01*
X775000Y249167D01*
X774917Y248583D01*
X774667Y248000D01*
X774167Y247667D01*
X773500Y247500D01*
X772917Y247583D01*
X772333Y247833D01*
X772000Y248167D01*
G01X777850Y249750D02*
X780517D01*
X780267Y250333D01*
X779850Y250667D01*
X779267Y250833D01*
X778683Y250750D01*
X778183Y250500D01*
X777850Y249917D01*
X777683Y249417D01*
Y248917D01*
X777850Y248417D01*
X778267Y247917D01*
X778767Y247583D01*
X779350Y247500D01*
X779933Y247667D01*
X780517Y248167D01*
G01X783533Y247500D02*
Y250833D01*
G01Y250167D02*
X783950Y250500D01*
X784367Y250750D01*
X784950Y250833D01*
X785367Y250750D01*
X785867Y250500D01*
G01X795400Y247500D02*
Y251750D01*
X795567Y252167D01*
X795900Y252417D01*
X796400Y252500D01*
X796900Y252333D01*
X797150Y251917D01*
G01X796150Y250500D02*
X794483D01*
G01X801500Y247500D02*
X801000Y247583D01*
X800500Y247917D01*
X800167Y248500D01*
X800000Y249167D01*
X800167Y249833D01*
X800500Y250417D01*
X801000Y250750D01*
X801500Y250833D01*
X802000Y250750D01*
X802500Y250417D01*
X802833Y249833D01*
X802917Y249167D01*
X802833Y248500D01*
X802500Y247917D01*
X802000Y247583D01*
X801500Y247500D01*
G01X807100D02*
Y252500D01*
G01X812700Y247500D02*
Y252500D01*
G01X818300Y247500D02*
X817800Y247583D01*
X817300Y247917D01*
X816967Y248500D01*
X816800Y249167D01*
X816967Y249833D01*
X817300Y250417D01*
X817800Y250750D01*
X818300Y250833D01*
X818800Y250750D01*
X819300Y250417D01*
X819633Y249833D01*
X819717Y249167D01*
X819633Y248500D01*
X819300Y247917D01*
X818800Y247583D01*
X818300Y247500D01*
G01X821817Y250833D02*
X822817Y247500D01*
X823900Y250833D01*
X824983Y247500D01*
X825983Y250833D01*
G01X829500D02*
Y247500D01*
G01Y252167D02*
X829333Y252250D01*
Y252417D01*
X829500Y252500D01*
X829667Y252417D01*
Y252250D01*
X829500Y252167D01*
G01X833683Y247500D02*
Y250833D01*
G01Y250000D02*
X834017Y250417D01*
X834517Y250750D01*
X835183Y250833D01*
X835767Y250750D01*
X836267Y250417D01*
X836517Y249833D01*
Y247500D01*
G01X839533Y246250D02*
X840117Y245917D01*
X840783Y245833D01*
X841367Y245917D01*
X841867Y246333D01*
X842200Y246917D01*
Y250833D01*
G01Y250167D02*
X841867Y250500D01*
X841367Y250750D01*
X840783Y250833D01*
X840117Y250667D01*
X839700Y250333D01*
X839367Y249750D01*
X839200Y249167D01*
X839283Y248667D01*
X839617Y248083D01*
X840117Y247667D01*
X840783Y247500D01*
X841283Y247583D01*
X841867Y247917D01*
X842200Y248250D01*
G01X846300Y247333D02*
X846133Y247417D01*
Y247583D01*
X846300Y247667D01*
X846467Y247583D01*
Y247417D01*
X846300Y247333D01*
G01Y249583D02*
X846133Y249667D01*
Y249833D01*
X846300Y249917D01*
X846467Y249833D01*
Y249667D01*
X846300Y249583D01*
G01X575000Y256500D02*
Y261500D01*
G01Y259000D02*
X575417Y259500D01*
X575917Y259750D01*
X576417Y259833D01*
X577167Y259667D01*
X577667Y259333D01*
X578000Y258750D01*
Y258083D01*
X577833Y257417D01*
X577500Y256917D01*
X576917Y256583D01*
X576417Y256500D01*
X575917Y256583D01*
X575417Y256833D01*
X575000Y257250D01*
G01X580850Y258750D02*
X583517D01*
X583267Y259333D01*
X582850Y259667D01*
X582267Y259833D01*
X581683Y259750D01*
X581183Y259500D01*
X580850Y258917D01*
X580683Y258417D01*
Y257917D01*
X580850Y257417D01*
X581267Y256917D01*
X581767Y256583D01*
X582350Y256500D01*
X582933Y256667D01*
X583517Y257167D01*
G01X592800Y256500D02*
Y260750D01*
X592967Y261167D01*
X593300Y261417D01*
X593800Y261500D01*
X594300Y261333D01*
X594550Y260917D01*
G01X593550Y259500D02*
X591883D01*
G01X597733Y256500D02*
Y259833D01*
G01Y259167D02*
X598150Y259500D01*
X598567Y259750D01*
X599150Y259833D01*
X599567Y259750D01*
X600067Y259500D01*
G01X603250Y258750D02*
X605917D01*
X605667Y259333D01*
X605250Y259667D01*
X604667Y259833D01*
X604083Y259750D01*
X603583Y259500D01*
X603250Y258917D01*
X603083Y258417D01*
Y257917D01*
X603250Y257417D01*
X603667Y256917D01*
X604167Y256583D01*
X604750Y256500D01*
X605333Y256667D01*
X605917Y257167D01*
G01X608850Y258750D02*
X611517D01*
X611267Y259333D01*
X610850Y259667D01*
X610267Y259833D01*
X609683Y259750D01*
X609183Y259500D01*
X608850Y258917D01*
X608683Y258417D01*
Y257917D01*
X608850Y257417D01*
X609267Y256917D01*
X609767Y256583D01*
X610350Y256500D01*
X610933Y256667D01*
X611517Y257167D01*
G01X620800Y256500D02*
Y260750D01*
X620967Y261167D01*
X621300Y261417D01*
X621800Y261500D01*
X622300Y261333D01*
X622550Y260917D01*
G01X621550Y259500D02*
X619883D01*
G01X625733Y256500D02*
Y259833D01*
G01Y259167D02*
X626150Y259500D01*
X626567Y259750D01*
X627150Y259833D01*
X627567Y259750D01*
X628067Y259500D01*
G01X632500Y256500D02*
X632000Y256583D01*
X631500Y256917D01*
X631167Y257500D01*
X631000Y258167D01*
X631167Y258833D01*
X631500Y259417D01*
X632000Y259750D01*
X632500Y259833D01*
X633000Y259750D01*
X633500Y259417D01*
X633833Y258833D01*
X633917Y258167D01*
X633833Y257500D01*
X633500Y256917D01*
X633000Y256583D01*
X632500Y256500D01*
G01X635600D02*
Y259833D01*
G01Y258917D02*
X635850Y259333D01*
X636267Y259667D01*
X636850Y259833D01*
X637433Y259667D01*
X637850Y259333D01*
X638100Y258917D01*
Y256500D01*
G01Y258917D02*
X638350Y259333D01*
X638767Y259667D01*
X639350Y259833D01*
X639933Y259667D01*
X640350Y259333D01*
X640600Y258833D01*
Y256500D01*
G01X648050Y257083D02*
X648467Y256750D01*
X649050Y256500D01*
X649550D01*
X650050Y256667D01*
X650383Y256917D01*
X650550Y257250D01*
X650467Y257750D01*
X650133Y258000D01*
X648633Y258500D01*
X648300Y259083D01*
X648467Y259500D01*
X648800Y259750D01*
X649300Y259833D01*
X649800Y259750D01*
X650300Y259500D01*
G01X654900Y256500D02*
X654400Y256583D01*
X653900Y256917D01*
X653567Y257500D01*
X653400Y258167D01*
X653567Y258833D01*
X653900Y259417D01*
X654400Y259750D01*
X654900Y259833D01*
X655400Y259750D01*
X655900Y259417D01*
X656233Y258833D01*
X656317Y258167D01*
X656233Y257500D01*
X655900Y256917D01*
X655400Y256583D01*
X654900Y256500D01*
G01X660500D02*
Y261500D01*
G01X667600D02*
Y256500D01*
G01Y257250D02*
X667267Y256833D01*
X666767Y256583D01*
X666183Y256500D01*
X665517Y256667D01*
X665017Y257083D01*
X664683Y257583D01*
X664600Y258167D01*
X664683Y258750D01*
X665017Y259250D01*
X665517Y259667D01*
X666183Y259833D01*
X666767Y259750D01*
X667183Y259583D01*
X667600Y259250D01*
G01X670450Y258750D02*
X673117D01*
X672867Y259333D01*
X672450Y259667D01*
X671867Y259833D01*
X671283Y259750D01*
X670783Y259500D01*
X670450Y258917D01*
X670283Y258417D01*
Y257917D01*
X670450Y257417D01*
X670867Y256917D01*
X671367Y256583D01*
X671950Y256500D01*
X672533Y256667D01*
X673117Y257167D01*
G01X676133Y256500D02*
Y259833D01*
G01Y259167D02*
X676550Y259500D01*
X676967Y259750D01*
X677550Y259833D01*
X677967Y259750D01*
X678467Y259500D01*
G01X686000Y256500D02*
Y259833D01*
G01Y258917D02*
X686250Y259333D01*
X686667Y259667D01*
X687250Y259833D01*
X687833Y259667D01*
X688250Y259333D01*
X688500Y258917D01*
Y256500D01*
G01Y258917D02*
X688750Y259333D01*
X689167Y259667D01*
X689750Y259833D01*
X690333Y259667D01*
X690750Y259333D01*
X691000Y258833D01*
Y256500D01*
G01X695600D02*
Y259833D01*
G01Y259250D02*
X695267Y259583D01*
X694767Y259750D01*
X694183Y259833D01*
X693600Y259667D01*
X693100Y259333D01*
X692767Y258833D01*
X692600Y258167D01*
X692767Y257500D01*
X693100Y257000D01*
X693600Y256667D01*
X694183Y256500D01*
X694767Y256583D01*
X695267Y256833D01*
X695600Y257167D01*
G01X698450Y257083D02*
X698867Y256750D01*
X699450Y256500D01*
X699950D01*
X700450Y256667D01*
X700783Y256917D01*
X700950Y257250D01*
X700867Y257750D01*
X700533Y258000D01*
X699033Y258500D01*
X698700Y259083D01*
X698867Y259500D01*
X699200Y259750D01*
X699700Y259833D01*
X700200Y259750D01*
X700700Y259500D01*
G01X703883Y256500D02*
Y261500D01*
G01X706550Y259833D02*
X703883Y257917D01*
G01X704967Y258667D02*
X706717Y256500D01*
G01X710900Y256333D02*
X710733Y256417D01*
Y256583D01*
X710900Y256667D01*
X711067Y256583D01*
Y256417D01*
X710900Y256333D01*
G01X574000Y279500D02*
Y284500D01*
G01Y282000D02*
X574417Y282500D01*
X574917Y282750D01*
X575417Y282833D01*
X576167Y282667D01*
X576667Y282333D01*
X577000Y281750D01*
Y281083D01*
X576833Y280417D01*
X576500Y279917D01*
X575917Y279583D01*
X575417Y279500D01*
X574917Y279583D01*
X574417Y279833D01*
X574000Y280250D01*
G01X579850Y281750D02*
X582517D01*
X582267Y282333D01*
X581850Y282667D01*
X581267Y282833D01*
X580683Y282750D01*
X580183Y282500D01*
X579850Y281917D01*
X579683Y281417D01*
Y280917D01*
X579850Y280417D01*
X580267Y279917D01*
X580767Y279583D01*
X581350Y279500D01*
X581933Y279667D01*
X582517Y280167D01*
G01X592300Y284500D02*
Y279500D01*
G01X591133Y282833D02*
X593467D01*
G01X596650Y281750D02*
X599317D01*
X599067Y282333D01*
X598650Y282667D01*
X598067Y282833D01*
X597483Y282750D01*
X596983Y282500D01*
X596650Y281917D01*
X596483Y281417D01*
Y280917D01*
X596650Y280417D01*
X597067Y279917D01*
X597567Y279583D01*
X598150Y279500D01*
X598733Y279667D01*
X599317Y280167D01*
G01X602083Y279500D02*
Y282833D01*
G01Y282000D02*
X602417Y282417D01*
X602917Y282750D01*
X603583Y282833D01*
X604167Y282750D01*
X604667Y282417D01*
X604917Y281833D01*
Y279500D01*
G01X609100Y284500D02*
Y279500D01*
G01X607933Y282833D02*
X610267D01*
G01X613450Y281750D02*
X616117D01*
X615867Y282333D01*
X615450Y282667D01*
X614867Y282833D01*
X614283Y282750D01*
X613783Y282500D01*
X613450Y281917D01*
X613283Y281417D01*
Y280917D01*
X613450Y280417D01*
X613867Y279917D01*
X614367Y279583D01*
X614950Y279500D01*
X615533Y279667D01*
X616117Y280167D01*
G01X621800Y284500D02*
Y279500D01*
G01Y280250D02*
X621467Y279833D01*
X620967Y279583D01*
X620383Y279500D01*
X619717Y279667D01*
X619217Y280083D01*
X618883Y280583D01*
X618800Y281167D01*
X618883Y281750D01*
X619217Y282250D01*
X619717Y282667D01*
X620383Y282833D01*
X620967Y282750D01*
X621383Y282583D01*
X621800Y282250D01*
G01X629417Y282833D02*
X630417Y279500D01*
X631500Y282833D01*
X632583Y279500D01*
X633583Y282833D01*
G01X637100D02*
Y279500D01*
G01Y284167D02*
X636933Y284250D01*
Y284417D01*
X637100Y284500D01*
X637267Y284417D01*
Y284250D01*
X637100Y284167D01*
G01X642700Y284500D02*
Y279500D01*
G01X641533Y282833D02*
X643867D01*
G01X646883Y279500D02*
Y284500D01*
G01Y282083D02*
X647300Y282500D01*
X647717Y282750D01*
X648383Y282833D01*
X648883Y282750D01*
X649467Y282417D01*
X649717Y281917D01*
Y279500D01*
G01X658250Y280083D02*
X658667Y279750D01*
X659250Y279500D01*
X659750D01*
X660250Y279667D01*
X660583Y279917D01*
X660750Y280250D01*
X660667Y280750D01*
X660333Y281000D01*
X658833Y281500D01*
X658500Y282083D01*
X658667Y282500D01*
X659000Y282750D01*
X659500Y282833D01*
X660000Y282750D01*
X660500Y282500D01*
G01X665100Y279500D02*
X664600Y279583D01*
X664100Y279917D01*
X663767Y280500D01*
X663600Y281167D01*
X663767Y281833D01*
X664100Y282417D01*
X664600Y282750D01*
X665100Y282833D01*
X665600Y282750D01*
X666100Y282417D01*
X666433Y281833D01*
X666517Y281167D01*
X666433Y280500D01*
X666100Y279917D01*
X665600Y279583D01*
X665100Y279500D01*
G01X670700D02*
Y284500D01*
G01X677800D02*
Y279500D01*
G01Y280250D02*
X677467Y279833D01*
X676967Y279583D01*
X676383Y279500D01*
X675717Y279667D01*
X675217Y280083D01*
X674883Y280583D01*
X674800Y281167D01*
X674883Y281750D01*
X675217Y282250D01*
X675717Y282667D01*
X676383Y282833D01*
X676967Y282750D01*
X677383Y282583D01*
X677800Y282250D01*
G01X680650Y281750D02*
X683317D01*
X683067Y282333D01*
X682650Y282667D01*
X682067Y282833D01*
X681483Y282750D01*
X680983Y282500D01*
X680650Y281917D01*
X680483Y281417D01*
Y280917D01*
X680650Y280417D01*
X681067Y279917D01*
X681567Y279583D01*
X682150Y279500D01*
X682733Y279667D01*
X683317Y280167D01*
G01X686333Y279500D02*
Y282833D01*
G01Y282167D02*
X686750Y282500D01*
X687167Y282750D01*
X687750Y282833D01*
X688167Y282750D01*
X688667Y282500D01*
G01X696200Y279500D02*
Y282833D01*
G01Y281917D02*
X696450Y282333D01*
X696867Y282667D01*
X697450Y282833D01*
X698033Y282667D01*
X698450Y282333D01*
X698700Y281917D01*
Y279500D01*
G01Y281917D02*
X698950Y282333D01*
X699367Y282667D01*
X699950Y282833D01*
X700533Y282667D01*
X700950Y282333D01*
X701200Y281833D01*
Y279500D01*
G01X705800D02*
Y282833D01*
G01Y282250D02*
X705467Y282583D01*
X704967Y282750D01*
X704383Y282833D01*
X703800Y282667D01*
X703300Y282333D01*
X702967Y281833D01*
X702800Y281167D01*
X702967Y280500D01*
X703300Y280000D01*
X703800Y279667D01*
X704383Y279500D01*
X704967Y279583D01*
X705467Y279833D01*
X705800Y280167D01*
G01X708650Y280083D02*
X709067Y279750D01*
X709650Y279500D01*
X710150D01*
X710650Y279667D01*
X710983Y279917D01*
X711150Y280250D01*
X711067Y280750D01*
X710733Y281000D01*
X709233Y281500D01*
X708900Y282083D01*
X709067Y282500D01*
X709400Y282750D01*
X709900Y282833D01*
X710400Y282750D01*
X710900Y282500D01*
G01X714083Y279500D02*
Y284500D01*
G01X716750Y282833D02*
X714083Y280917D01*
G01X715167Y281667D02*
X716917Y279500D01*
G01X721100Y279333D02*
X720933Y279417D01*
Y279583D01*
X721100Y279667D01*
X721267Y279583D01*
Y279417D01*
X721100Y279333D01*
G01X575500Y293500D02*
Y288500D01*
G01X574333Y291833D02*
X576667D01*
G01X581100Y288500D02*
X580600Y288583D01*
X580100Y288917D01*
X579767Y289500D01*
X579600Y290167D01*
X579767Y290833D01*
X580100Y291417D01*
X580600Y291750D01*
X581100Y291833D01*
X581600Y291750D01*
X582100Y291417D01*
X582433Y290833D01*
X582517Y290167D01*
X582433Y289500D01*
X582100Y288917D01*
X581600Y288583D01*
X581100Y288500D01*
G01X590800D02*
Y293500D01*
G01Y291000D02*
X591217Y291500D01*
X591717Y291750D01*
X592217Y291833D01*
X592967Y291667D01*
X593467Y291333D01*
X593800Y290750D01*
Y290083D01*
X593633Y289417D01*
X593300Y288917D01*
X592717Y288583D01*
X592217Y288500D01*
X591717Y288583D01*
X591217Y288833D01*
X590800Y289250D01*
G01X596650Y290750D02*
X599317D01*
X599067Y291333D01*
X598650Y291667D01*
X598067Y291833D01*
X597483Y291750D01*
X596983Y291500D01*
X596650Y290917D01*
X596483Y290417D01*
Y289917D01*
X596650Y289417D01*
X597067Y288917D01*
X597567Y288583D01*
X598150Y288500D01*
X598733Y288667D01*
X599317Y289167D01*
G01X610433Y291417D02*
X609850Y291750D01*
X609350Y291833D01*
X608683Y291667D01*
X608183Y291333D01*
X607850Y290750D01*
X607767Y290167D01*
X607850Y289583D01*
X608183Y289083D01*
X608683Y288667D01*
X609350Y288500D01*
X609933Y288667D01*
X610433Y289000D01*
G01X614700Y288500D02*
X614200Y288583D01*
X613700Y288917D01*
X613367Y289500D01*
X613200Y290167D01*
X613367Y290833D01*
X613700Y291417D01*
X614200Y291750D01*
X614700Y291833D01*
X615200Y291750D01*
X615700Y291417D01*
X616033Y290833D01*
X616117Y290167D01*
X616033Y289500D01*
X615700Y288917D01*
X615200Y288583D01*
X614700Y288500D01*
G01X618800Y291833D02*
X620300Y288500D01*
X621800Y291833D01*
G01X624650Y290750D02*
X627317D01*
X627067Y291333D01*
X626650Y291667D01*
X626067Y291833D01*
X625483Y291750D01*
X624983Y291500D01*
X624650Y290917D01*
X624483Y290417D01*
Y289917D01*
X624650Y289417D01*
X625067Y288917D01*
X625567Y288583D01*
X626150Y288500D01*
X626733Y288667D01*
X627317Y289167D01*
G01X630333Y288500D02*
Y291833D01*
G01Y291167D02*
X630750Y291500D01*
X631167Y291750D01*
X631750Y291833D01*
X632167Y291750D01*
X632667Y291500D01*
G01X635850Y290750D02*
X638517D01*
X638267Y291333D01*
X637850Y291667D01*
X637267Y291833D01*
X636683Y291750D01*
X636183Y291500D01*
X635850Y290917D01*
X635683Y290417D01*
Y289917D01*
X635850Y289417D01*
X636267Y288917D01*
X636767Y288583D01*
X637350Y288500D01*
X637933Y288667D01*
X638517Y289167D01*
G01X644200Y293500D02*
Y288500D01*
G01Y289250D02*
X643867Y288833D01*
X643367Y288583D01*
X642783Y288500D01*
X642117Y288667D01*
X641617Y289083D01*
X641283Y289583D01*
X641200Y290167D01*
X641283Y290750D01*
X641617Y291250D01*
X642117Y291667D01*
X642783Y291833D01*
X643367Y291750D01*
X643783Y291583D01*
X644200Y291250D01*
G01X652400Y288500D02*
Y293500D01*
G01Y291000D02*
X652817Y291500D01*
X653317Y291750D01*
X653817Y291833D01*
X654567Y291667D01*
X655067Y291333D01*
X655400Y290750D01*
Y290083D01*
X655233Y289417D01*
X654900Y288917D01*
X654317Y288583D01*
X653817Y288500D01*
X653317Y288583D01*
X652817Y288833D01*
X652400Y289250D01*
G01X657750Y287000D02*
X658250Y286833D01*
X658917Y287000D01*
X659333Y287333D01*
X659667Y287750D01*
X660167Y289083D01*
X661250Y291833D01*
G01X658583D02*
X660167Y289083D01*
G01X669450D02*
X669867Y288750D01*
X670450Y288500D01*
X670950D01*
X671450Y288667D01*
X671783Y288917D01*
X671950Y289250D01*
X671867Y289750D01*
X671533Y290000D01*
X670033Y290500D01*
X669700Y291083D01*
X669867Y291500D01*
X670200Y291750D01*
X670700Y291833D01*
X671200Y291750D01*
X671700Y291500D01*
G01X676300Y288500D02*
X675800Y288583D01*
X675300Y288917D01*
X674967Y289500D01*
X674800Y290167D01*
X674967Y290833D01*
X675300Y291417D01*
X675800Y291750D01*
X676300Y291833D01*
X676800Y291750D01*
X677300Y291417D01*
X677633Y290833D01*
X677717Y290167D01*
X677633Y289500D01*
X677300Y288917D01*
X676800Y288583D01*
X676300Y288500D01*
G01X681900D02*
Y293500D01*
G01X689000D02*
Y288500D01*
G01Y289250D02*
X688667Y288833D01*
X688167Y288583D01*
X687583Y288500D01*
X686917Y288667D01*
X686417Y289083D01*
X686083Y289583D01*
X686000Y290167D01*
X686083Y290750D01*
X686417Y291250D01*
X686917Y291667D01*
X687583Y291833D01*
X688167Y291750D01*
X688583Y291583D01*
X689000Y291250D01*
G01X691850Y290750D02*
X694517D01*
X694267Y291333D01*
X693850Y291667D01*
X693267Y291833D01*
X692683Y291750D01*
X692183Y291500D01*
X691850Y290917D01*
X691683Y290417D01*
Y289917D01*
X691850Y289417D01*
X692267Y288917D01*
X692767Y288583D01*
X693350Y288500D01*
X693933Y288667D01*
X694517Y289167D01*
G01X697533Y288500D02*
Y291833D01*
G01Y291167D02*
X697950Y291500D01*
X698367Y291750D01*
X698950Y291833D01*
X699367Y291750D01*
X699867Y291500D01*
G01X707400Y288500D02*
Y291833D01*
G01Y290917D02*
X707650Y291333D01*
X708067Y291667D01*
X708650Y291833D01*
X709233Y291667D01*
X709650Y291333D01*
X709900Y290917D01*
Y288500D01*
G01Y290917D02*
X710150Y291333D01*
X710567Y291667D01*
X711150Y291833D01*
X711733Y291667D01*
X712150Y291333D01*
X712400Y290833D01*
Y288500D01*
G01X717000D02*
Y291833D01*
G01Y291250D02*
X716667Y291583D01*
X716167Y291750D01*
X715583Y291833D01*
X715000Y291667D01*
X714500Y291333D01*
X714167Y290833D01*
X714000Y290167D01*
X714167Y289500D01*
X714500Y289000D01*
X715000Y288667D01*
X715583Y288500D01*
X716167Y288583D01*
X716667Y288833D01*
X717000Y289167D01*
G01X719850Y289083D02*
X720267Y288750D01*
X720850Y288500D01*
X721350D01*
X721850Y288667D01*
X722183Y288917D01*
X722350Y289250D01*
X722267Y289750D01*
X721933Y290000D01*
X720433Y290500D01*
X720100Y291083D01*
X720267Y291500D01*
X720600Y291750D01*
X721100Y291833D01*
X721600Y291750D01*
X722100Y291500D01*
G01X725283Y288500D02*
Y293500D01*
G01X727950Y291833D02*
X725283Y289917D01*
G01X726367Y290667D02*
X728117Y288500D01*
G01X739400D02*
Y291833D01*
G01Y291250D02*
X739067Y291583D01*
X738567Y291750D01*
X737983Y291833D01*
X737400Y291667D01*
X736900Y291333D01*
X736567Y290833D01*
X736400Y290167D01*
X736567Y289500D01*
X736900Y289000D01*
X737400Y288667D01*
X737983Y288500D01*
X738567Y288583D01*
X739067Y288833D01*
X739400Y289167D01*
G01X742083Y288500D02*
Y291833D01*
G01Y291000D02*
X742417Y291417D01*
X742917Y291750D01*
X743583Y291833D01*
X744167Y291750D01*
X744667Y291417D01*
X744917Y290833D01*
Y288500D01*
G01X750600Y293500D02*
Y288500D01*
G01Y289250D02*
X750267Y288833D01*
X749767Y288583D01*
X749183Y288500D01*
X748517Y288667D01*
X748017Y289083D01*
X747683Y289583D01*
X747600Y290167D01*
X747683Y290750D01*
X748017Y291250D01*
X748517Y291667D01*
X749183Y291833D01*
X749767Y291750D01*
X750183Y291583D01*
X750600Y291250D01*
G01X758883Y288500D02*
Y293500D01*
G01Y291083D02*
X759300Y291500D01*
X759717Y291750D01*
X760383Y291833D01*
X760883Y291750D01*
X761467Y291417D01*
X761717Y290917D01*
Y288500D01*
G01X765900D02*
X765400Y288583D01*
X764900Y288917D01*
X764567Y289500D01*
X764400Y290167D01*
X764567Y290833D01*
X764900Y291417D01*
X765400Y291750D01*
X765900Y291833D01*
X766400Y291750D01*
X766900Y291417D01*
X767233Y290833D01*
X767317Y290167D01*
X767233Y289500D01*
X766900Y288917D01*
X766400Y288583D01*
X765900Y288500D01*
G01X771500D02*
Y293500D01*
G01X775850Y290750D02*
X778517D01*
X778267Y291333D01*
X777850Y291667D01*
X777267Y291833D01*
X776683Y291750D01*
X776183Y291500D01*
X775850Y290917D01*
X775683Y290417D01*
Y289917D01*
X775850Y289417D01*
X776267Y288917D01*
X776767Y288583D01*
X777350Y288500D01*
X777933Y288667D01*
X778517Y289167D01*
G01X789800Y288500D02*
Y291833D01*
G01Y291250D02*
X789467Y291583D01*
X788967Y291750D01*
X788383Y291833D01*
X787800Y291667D01*
X787300Y291333D01*
X786967Y290833D01*
X786800Y290167D01*
X786967Y289500D01*
X787300Y289000D01*
X787800Y288667D01*
X788383Y288500D01*
X788967Y288583D01*
X789467Y288833D01*
X789800Y289167D01*
G01X793900Y288500D02*
Y293500D01*
G01X798250Y289083D02*
X798667Y288750D01*
X799250Y288500D01*
X799750D01*
X800250Y288667D01*
X800583Y288917D01*
X800750Y289250D01*
X800667Y289750D01*
X800333Y290000D01*
X798833Y290500D01*
X798500Y291083D01*
X798667Y291500D01*
X799000Y291750D01*
X799500Y291833D01*
X800000Y291750D01*
X800500Y291500D01*
G01X805100Y288500D02*
X804600Y288583D01*
X804100Y288917D01*
X803767Y289500D01*
X803600Y290167D01*
X803767Y290833D01*
X804100Y291417D01*
X804600Y291750D01*
X805100Y291833D01*
X805600Y291750D01*
X806100Y291417D01*
X806433Y290833D01*
X806517Y290167D01*
X806433Y289500D01*
X806100Y288917D01*
X805600Y288583D01*
X805100Y288500D01*
G01X814883D02*
Y291833D01*
G01Y291000D02*
X815217Y291417D01*
X815717Y291750D01*
X816383Y291833D01*
X816967Y291750D01*
X817467Y291417D01*
X817717Y290833D01*
Y288500D01*
G01X820650Y290750D02*
X823317D01*
X823067Y291333D01*
X822650Y291667D01*
X822067Y291833D01*
X821483Y291750D01*
X820983Y291500D01*
X820650Y290917D01*
X820483Y290417D01*
Y289917D01*
X820650Y289417D01*
X821067Y288917D01*
X821567Y288583D01*
X822150Y288500D01*
X822733Y288667D01*
X823317Y289167D01*
G01X826250Y290750D02*
X828917D01*
X828667Y291333D01*
X828250Y291667D01*
X827667Y291833D01*
X827083Y291750D01*
X826583Y291500D01*
X826250Y290917D01*
X826083Y290417D01*
Y289917D01*
X826250Y289417D01*
X826667Y288917D01*
X827167Y288583D01*
X827750Y288500D01*
X828333Y288667D01*
X828917Y289167D01*
G01X834600Y293500D02*
Y288500D01*
G01Y289250D02*
X834267Y288833D01*
X833767Y288583D01*
X833183Y288500D01*
X832517Y288667D01*
X832017Y289083D01*
X831683Y289583D01*
X831600Y290167D01*
X831683Y290750D01*
X832017Y291250D01*
X832517Y291667D01*
X833183Y291833D01*
X833767Y291750D01*
X834183Y291583D01*
X834600Y291250D01*
G01X844300Y293500D02*
Y288500D01*
G01X843133Y291833D02*
X845467D01*
G01X849900Y288500D02*
X849400Y288583D01*
X848900Y288917D01*
X848567Y289500D01*
X848400Y290167D01*
X848567Y290833D01*
X848900Y291417D01*
X849400Y291750D01*
X849900Y291833D01*
X850400Y291750D01*
X850900Y291417D01*
X851233Y290833D01*
X851317Y290167D01*
X851233Y289500D01*
X850900Y288917D01*
X850400Y288583D01*
X849900Y288500D01*
G01X588000Y212833D02*
X589500Y209500D01*
X591000Y212833D01*
G01X595100D02*
Y209500D01*
G01Y214167D02*
X594933Y214250D01*
Y214417D01*
X595100Y214500D01*
X595267Y214417D01*
Y214250D01*
X595100Y214167D01*
G01X602200Y209500D02*
Y212833D01*
G01Y212250D02*
X601867Y212583D01*
X601367Y212750D01*
X600783Y212833D01*
X600200Y212667D01*
X599700Y212333D01*
X599367Y211833D01*
X599200Y211167D01*
X599367Y210500D01*
X599700Y210000D01*
X600200Y209667D01*
X600783Y209500D01*
X601367Y209583D01*
X601867Y209833D01*
X602200Y210167D01*
G01X610650Y210083D02*
X611067Y209750D01*
X611650Y209500D01*
X612150D01*
X612650Y209667D01*
X612983Y209917D01*
X613150Y210250D01*
X613067Y210750D01*
X612733Y211000D01*
X611233Y211500D01*
X610900Y212083D01*
X611067Y212500D01*
X611400Y212750D01*
X611900Y212833D01*
X612400Y212750D01*
X612900Y212500D01*
G01X616083Y209500D02*
Y214500D01*
G01Y212083D02*
X616500Y212500D01*
X616917Y212750D01*
X617583Y212833D01*
X618083Y212750D01*
X618667Y212417D01*
X618917Y211917D01*
Y209500D01*
G01X624600D02*
Y212833D01*
G01Y212250D02*
X624267Y212583D01*
X623767Y212750D01*
X623183Y212833D01*
X622600Y212667D01*
X622100Y212333D01*
X621767Y211833D01*
X621600Y211167D01*
X621767Y210500D01*
X622100Y210000D01*
X622600Y209667D01*
X623183Y209500D01*
X623767Y209583D01*
X624267Y209833D01*
X624600Y210167D01*
G01X628700Y209500D02*
Y214500D01*
G01X634300Y209500D02*
Y214500D01*
G01X644000Y209500D02*
Y214500D01*
G01Y212000D02*
X644417Y212500D01*
X644917Y212750D01*
X645417Y212833D01*
X646167Y212667D01*
X646667Y212333D01*
X647000Y211750D01*
Y211083D01*
X646833Y210417D01*
X646500Y209917D01*
X645917Y209583D01*
X645417Y209500D01*
X644917Y209583D01*
X644417Y209833D01*
X644000Y210250D01*
G01X649850Y211750D02*
X652517D01*
X652267Y212333D01*
X651850Y212667D01*
X651267Y212833D01*
X650683Y212750D01*
X650183Y212500D01*
X649850Y211917D01*
X649683Y211417D01*
Y210917D01*
X649850Y210417D01*
X650267Y209917D01*
X650767Y209583D01*
X651350Y209500D01*
X651933Y209667D01*
X652517Y210167D01*
G01X660217Y212833D02*
X661217Y209500D01*
X662300Y212833D01*
X663383Y209500D01*
X664383Y212833D01*
G01X667900D02*
Y209500D01*
G01Y214167D02*
X667733Y214250D01*
Y214417D01*
X667900Y214500D01*
X668067Y214417D01*
Y214250D01*
X667900Y214167D01*
G01X673500Y214500D02*
Y209500D01*
G01X672333Y212833D02*
X674667D01*
G01X677683Y209500D02*
Y214500D01*
G01Y212083D02*
X678100Y212500D01*
X678517Y212750D01*
X679183Y212833D01*
X679683Y212750D01*
X680267Y212417D01*
X680517Y211917D01*
Y209500D01*
G01X691967D02*
X688633Y211167D01*
X691967Y212833D01*
G01X701500Y209500D02*
X702083Y209583D01*
X702750Y209833D01*
X703167Y210250D01*
X703333Y210833D01*
X703167Y211417D01*
X702667Y211917D01*
X701917Y212167D01*
X701083D01*
X700583Y212333D01*
X700167Y212750D01*
X700000Y213333D01*
X700250Y213917D01*
X700833Y214333D01*
X701500Y214500D01*
X702167Y214333D01*
X702750Y213917D01*
X703000Y213333D01*
X702833Y212750D01*
X702417Y212333D01*
X701917Y212167D01*
X701083D01*
X700333Y211917D01*
X699833Y211417D01*
X699667Y210833D01*
X699833Y210250D01*
X700250Y209833D01*
X700917Y209583D01*
X701500Y209500D01*
G01X707100Y214500D02*
X706433Y214333D01*
X705933Y213917D01*
X705600Y213417D01*
X705350Y212750D01*
X705267Y212000D01*
X705350Y211250D01*
X705600Y210583D01*
X705933Y210083D01*
X706433Y209667D01*
X707100Y209500D01*
X707767Y209667D01*
X708267Y210083D01*
X708600Y210583D01*
X708850Y211250D01*
X708933Y212000D01*
X708850Y212750D01*
X708600Y213417D01*
X708267Y213917D01*
X707767Y214333D01*
X707100Y214500D01*
G01X716800Y209333D02*
X719800Y214500D01*
G01X716800D02*
X716300Y214333D01*
X716050Y214083D01*
X715883Y213583D01*
X716050Y213083D01*
X716300Y212833D01*
X716800Y212667D01*
X717300Y212833D01*
X717550Y213083D01*
X717717Y213583D01*
X717550Y214083D01*
X717300Y214333D01*
X716800Y214500D01*
G01X719800Y211167D02*
X719300Y211000D01*
X719050Y210750D01*
X718883Y210250D01*
X719050Y209750D01*
X719300Y209500D01*
X719800Y209333D01*
X720300Y209500D01*
X720550Y209750D01*
X720717Y210250D01*
X720550Y210750D01*
X720300Y211000D01*
X719800Y211167D01*
G01X728250Y210083D02*
X728667Y209750D01*
X729250Y209500D01*
X729750D01*
X730250Y209667D01*
X730583Y209917D01*
X730750Y210250D01*
X730667Y210750D01*
X730333Y211000D01*
X728833Y211500D01*
X728500Y212083D01*
X728667Y212500D01*
X729000Y212750D01*
X729500Y212833D01*
X730000Y212750D01*
X730500Y212500D01*
G01X735100Y209500D02*
X734600Y209583D01*
X734100Y209917D01*
X733767Y210500D01*
X733600Y211167D01*
X733767Y211833D01*
X734100Y212417D01*
X734600Y212750D01*
X735100Y212833D01*
X735600Y212750D01*
X736100Y212417D01*
X736433Y211833D01*
X736517Y211167D01*
X736433Y210500D01*
X736100Y209917D01*
X735600Y209583D01*
X735100Y209500D01*
G01X740700D02*
Y214500D01*
G01X747800D02*
Y209500D01*
G01Y210250D02*
X747467Y209833D01*
X746967Y209583D01*
X746383Y209500D01*
X745717Y209667D01*
X745217Y210083D01*
X744883Y210583D01*
X744800Y211167D01*
X744883Y211750D01*
X745217Y212250D01*
X745717Y212667D01*
X746383Y212833D01*
X746967Y212750D01*
X747383Y212583D01*
X747800Y212250D01*
G01X750650Y211750D02*
X753317D01*
X753067Y212333D01*
X752650Y212667D01*
X752067Y212833D01*
X751483Y212750D01*
X750983Y212500D01*
X750650Y211917D01*
X750483Y211417D01*
Y210917D01*
X750650Y210417D01*
X751067Y209917D01*
X751567Y209583D01*
X752150Y209500D01*
X752733Y209667D01*
X753317Y210167D01*
G01X756333Y209500D02*
Y212833D01*
G01Y212167D02*
X756750Y212500D01*
X757167Y212750D01*
X757750Y212833D01*
X758167Y212750D01*
X758667Y212500D01*
G01X766200Y209500D02*
Y212833D01*
G01Y211917D02*
X766450Y212333D01*
X766867Y212667D01*
X767450Y212833D01*
X768033Y212667D01*
X768450Y212333D01*
X768700Y211917D01*
Y209500D01*
G01Y211917D02*
X768950Y212333D01*
X769367Y212667D01*
X769950Y212833D01*
X770533Y212667D01*
X770950Y212333D01*
X771200Y211833D01*
Y209500D01*
G01X775800D02*
Y212833D01*
G01Y212250D02*
X775467Y212583D01*
X774967Y212750D01*
X774383Y212833D01*
X773800Y212667D01*
X773300Y212333D01*
X772967Y211833D01*
X772800Y211167D01*
X772967Y210500D01*
X773300Y210000D01*
X773800Y209667D01*
X774383Y209500D01*
X774967Y209583D01*
X775467Y209833D01*
X775800Y210167D01*
G01X778650Y210083D02*
X779067Y209750D01*
X779650Y209500D01*
X780150D01*
X780650Y209667D01*
X780983Y209917D01*
X781150Y210250D01*
X781067Y210750D01*
X780733Y211000D01*
X779233Y211500D01*
X778900Y212083D01*
X779067Y212500D01*
X779400Y212750D01*
X779900Y212833D01*
X780400Y212750D01*
X780900Y212500D01*
G01X784083Y209500D02*
Y214500D01*
G01X786750Y212833D02*
X784083Y210917D01*
G01X785167Y211667D02*
X786917Y209500D01*
G01X587000Y231833D02*
X588500Y228500D01*
X590000Y231833D01*
G01X594100D02*
Y228500D01*
G01Y233167D02*
X593933Y233250D01*
Y233417D01*
X594100Y233500D01*
X594267Y233417D01*
Y233250D01*
X594100Y233167D01*
G01X601200Y228500D02*
Y231833D01*
G01Y231250D02*
X600867Y231583D01*
X600367Y231750D01*
X599783Y231833D01*
X599200Y231667D01*
X598700Y231333D01*
X598367Y230833D01*
X598200Y230167D01*
X598367Y229500D01*
X598700Y229000D01*
X599200Y228667D01*
X599783Y228500D01*
X600367Y228583D01*
X600867Y228833D01*
X601200Y229167D01*
G01X609650Y229083D02*
X610067Y228750D01*
X610650Y228500D01*
X611150D01*
X611650Y228667D01*
X611983Y228917D01*
X612150Y229250D01*
X612067Y229750D01*
X611733Y230000D01*
X610233Y230500D01*
X609900Y231083D01*
X610067Y231500D01*
X610400Y231750D01*
X610900Y231833D01*
X611400Y231750D01*
X611900Y231500D01*
G01X615083Y228500D02*
Y233500D01*
G01Y231083D02*
X615500Y231500D01*
X615917Y231750D01*
X616583Y231833D01*
X617083Y231750D01*
X617667Y231417D01*
X617917Y230917D01*
Y228500D01*
G01X623600D02*
Y231833D01*
G01Y231250D02*
X623267Y231583D01*
X622767Y231750D01*
X622183Y231833D01*
X621600Y231667D01*
X621100Y231333D01*
X620767Y230833D01*
X620600Y230167D01*
X620767Y229500D01*
X621100Y229000D01*
X621600Y228667D01*
X622183Y228500D01*
X622767Y228583D01*
X623267Y228833D01*
X623600Y229167D01*
G01X627700Y228500D02*
Y233500D01*
G01X633300Y228500D02*
Y233500D01*
G01X643000Y228500D02*
Y233500D01*
G01Y231000D02*
X643417Y231500D01*
X643917Y231750D01*
X644417Y231833D01*
X645167Y231667D01*
X645667Y231333D01*
X646000Y230750D01*
Y230083D01*
X645833Y229417D01*
X645500Y228917D01*
X644917Y228583D01*
X644417Y228500D01*
X643917Y228583D01*
X643417Y228833D01*
X643000Y229250D01*
G01X648850Y230750D02*
X651517D01*
X651267Y231333D01*
X650850Y231667D01*
X650267Y231833D01*
X649683Y231750D01*
X649183Y231500D01*
X648850Y230917D01*
X648683Y230417D01*
Y229917D01*
X648850Y229417D01*
X649267Y228917D01*
X649767Y228583D01*
X650350Y228500D01*
X650933Y228667D01*
X651517Y229167D01*
G01X659800Y226833D02*
Y231833D01*
G01Y231083D02*
X660217Y231500D01*
X660633Y231750D01*
X661300Y231833D01*
X661883Y231750D01*
X662467Y231333D01*
X662717Y230750D01*
X662800Y230167D01*
X662717Y229583D01*
X662467Y229000D01*
X661967Y228667D01*
X661300Y228500D01*
X660717Y228583D01*
X660133Y228833D01*
X659800Y229167D01*
G01X666900Y228500D02*
Y233500D01*
G01X671083Y231833D02*
Y229500D01*
X671417Y228917D01*
X671917Y228583D01*
X672500Y228500D01*
X673083Y228583D01*
X673583Y228917D01*
X673917Y229500D01*
G01Y228500D02*
Y231833D01*
G01X676933Y227250D02*
X677517Y226917D01*
X678183Y226833D01*
X678767Y226917D01*
X679267Y227333D01*
X679600Y227917D01*
Y231833D01*
G01Y231167D02*
X679267Y231500D01*
X678767Y231750D01*
X678183Y231833D01*
X677517Y231667D01*
X677100Y231333D01*
X676767Y230750D01*
X676600Y230167D01*
X676683Y229667D01*
X677017Y229083D01*
X677517Y228667D01*
X678183Y228500D01*
X678683Y228583D01*
X679267Y228917D01*
X679600Y229250D01*
G01X682533Y227250D02*
X683117Y226917D01*
X683783Y226833D01*
X684367Y226917D01*
X684867Y227333D01*
X685200Y227917D01*
Y231833D01*
G01Y231167D02*
X684867Y231500D01*
X684367Y231750D01*
X683783Y231833D01*
X683117Y231667D01*
X682700Y231333D01*
X682367Y230750D01*
X682200Y230167D01*
X682283Y229667D01*
X682617Y229083D01*
X683117Y228667D01*
X683783Y228500D01*
X684283Y228583D01*
X684867Y228917D01*
X685200Y229250D01*
G01X688050Y230750D02*
X690717D01*
X690467Y231333D01*
X690050Y231667D01*
X689467Y231833D01*
X688883Y231750D01*
X688383Y231500D01*
X688050Y230917D01*
X687883Y230417D01*
Y229917D01*
X688050Y229417D01*
X688467Y228917D01*
X688967Y228583D01*
X689550Y228500D01*
X690133Y228667D01*
X690717Y229167D01*
G01X696400Y233500D02*
Y228500D01*
G01Y229250D02*
X696067Y228833D01*
X695567Y228583D01*
X694983Y228500D01*
X694317Y228667D01*
X693817Y229083D01*
X693483Y229583D01*
X693400Y230167D01*
X693483Y230750D01*
X693817Y231250D01*
X694317Y231667D01*
X694983Y231833D01*
X695567Y231750D01*
X695983Y231583D01*
X696400Y231250D01*
G01X704017Y231833D02*
X705017Y228500D01*
X706100Y231833D01*
X707183Y228500D01*
X708183Y231833D01*
G01X711700D02*
Y228500D01*
G01Y233167D02*
X711533Y233250D01*
Y233417D01*
X711700Y233500D01*
X711867Y233417D01*
Y233250D01*
X711700Y233167D01*
G01X717300Y233500D02*
Y228500D01*
G01X716133Y231833D02*
X718467D01*
G01X721483Y228500D02*
Y233500D01*
G01Y231083D02*
X721900Y231500D01*
X722317Y231750D01*
X722983Y231833D01*
X723483Y231750D01*
X724067Y231417D01*
X724317Y230917D01*
Y228500D01*
G01X735767D02*
X732433Y230167D01*
X735767Y231833D01*
G01X743467Y229250D02*
X743967Y228833D01*
X744550Y228583D01*
X745300Y228500D01*
X746050Y228667D01*
X746633Y229000D01*
X747050Y229583D01*
X747133Y230250D01*
X746967Y230917D01*
X746550Y231333D01*
X745967Y231667D01*
X745383Y231750D01*
X744800Y231667D01*
X744050Y231333D01*
X744300Y233500D01*
X746550D01*
G01X750900D02*
X750233Y233333D01*
X749733Y232917D01*
X749400Y232417D01*
X749150Y231750D01*
X749067Y231000D01*
X749150Y230250D01*
X749400Y229583D01*
X749733Y229083D01*
X750233Y228667D01*
X750900Y228500D01*
X751567Y228667D01*
X752067Y229083D01*
X752400Y229583D01*
X752650Y230250D01*
X752733Y231000D01*
X752650Y231750D01*
X752400Y232417D01*
X752067Y232917D01*
X751567Y233333D01*
X750900Y233500D01*
G01X760600Y228333D02*
X763600Y233500D01*
G01X760600D02*
X760100Y233333D01*
X759850Y233083D01*
X759683Y232583D01*
X759850Y232083D01*
X760100Y231833D01*
X760600Y231667D01*
X761100Y231833D01*
X761350Y232083D01*
X761517Y232583D01*
X761350Y233083D01*
X761100Y233333D01*
X760600Y233500D01*
G01X763600Y230167D02*
X763100Y230000D01*
X762850Y229750D01*
X762683Y229250D01*
X762850Y228750D01*
X763100Y228500D01*
X763600Y228333D01*
X764100Y228500D01*
X764350Y228750D01*
X764517Y229250D01*
X764350Y229750D01*
X764100Y230000D01*
X763600Y230167D01*
G01X772050Y229083D02*
X772467Y228750D01*
X773050Y228500D01*
X773550D01*
X774050Y228667D01*
X774383Y228917D01*
X774550Y229250D01*
X774467Y229750D01*
X774133Y230000D01*
X772633Y230500D01*
X772300Y231083D01*
X772467Y231500D01*
X772800Y231750D01*
X773300Y231833D01*
X773800Y231750D01*
X774300Y231500D01*
G01X778900Y228500D02*
X778400Y228583D01*
X777900Y228917D01*
X777567Y229500D01*
X777400Y230167D01*
X777567Y230833D01*
X777900Y231417D01*
X778400Y231750D01*
X778900Y231833D01*
X779400Y231750D01*
X779900Y231417D01*
X780233Y230833D01*
X780317Y230167D01*
X780233Y229500D01*
X779900Y228917D01*
X779400Y228583D01*
X778900Y228500D01*
G01X784500D02*
Y233500D01*
G01X791600D02*
Y228500D01*
G01Y229250D02*
X791267Y228833D01*
X790767Y228583D01*
X790183Y228500D01*
X789517Y228667D01*
X789017Y229083D01*
X788683Y229583D01*
X788600Y230167D01*
X788683Y230750D01*
X789017Y231250D01*
X789517Y231667D01*
X790183Y231833D01*
X790767Y231750D01*
X791183Y231583D01*
X791600Y231250D01*
G01X794450Y230750D02*
X797117D01*
X796867Y231333D01*
X796450Y231667D01*
X795867Y231833D01*
X795283Y231750D01*
X794783Y231500D01*
X794450Y230917D01*
X794283Y230417D01*
Y229917D01*
X794450Y229417D01*
X794867Y228917D01*
X795367Y228583D01*
X795950Y228500D01*
X796533Y228667D01*
X797117Y229167D01*
G01X800133Y228500D02*
Y231833D01*
G01Y231167D02*
X800550Y231500D01*
X800967Y231750D01*
X801550Y231833D01*
X801967Y231750D01*
X802467Y231500D01*
G01X810000Y228500D02*
Y231833D01*
G01Y230917D02*
X810250Y231333D01*
X810667Y231667D01*
X811250Y231833D01*
X811833Y231667D01*
X812250Y231333D01*
X812500Y230917D01*
Y228500D01*
G01Y230917D02*
X812750Y231333D01*
X813167Y231667D01*
X813750Y231833D01*
X814333Y231667D01*
X814750Y231333D01*
X815000Y230833D01*
Y228500D01*
G01X819600D02*
Y231833D01*
G01Y231250D02*
X819267Y231583D01*
X818767Y231750D01*
X818183Y231833D01*
X817600Y231667D01*
X817100Y231333D01*
X816767Y230833D01*
X816600Y230167D01*
X816767Y229500D01*
X817100Y229000D01*
X817600Y228667D01*
X818183Y228500D01*
X818767Y228583D01*
X819267Y228833D01*
X819600Y229167D01*
G01X822450Y229083D02*
X822867Y228750D01*
X823450Y228500D01*
X823950D01*
X824450Y228667D01*
X824783Y228917D01*
X824950Y229250D01*
X824867Y229750D01*
X824533Y230000D01*
X823033Y230500D01*
X822700Y231083D01*
X822867Y231500D01*
X823200Y231750D01*
X823700Y231833D01*
X824200Y231750D01*
X824700Y231500D01*
G01X827883Y228500D02*
Y233500D01*
G01X830550Y231833D02*
X827883Y229917D01*
G01X828967Y230667D02*
X830717Y228500D01*
G01X834733Y227583D02*
X835067Y228667D01*
G01X630993Y-168300D02*
Y-173300D01*
X634327D01*
G01X637010Y-169967D02*
X639510Y-173300D01*
G01Y-169967D02*
X637010Y-173300D01*
G01X643860Y-173467D02*
X643693Y-173383D01*
Y-173217D01*
X643860Y-173133D01*
X644027Y-173217D01*
Y-173383D01*
X643860Y-173467D01*
G01Y-171217D02*
X643693Y-171133D01*
Y-170967D01*
X643860Y-170883D01*
X644027Y-170967D01*
Y-171133D01*
X643860Y-171217D01*
G01X652560Y-173300D02*
Y-169967D01*
G01Y-170883D02*
X652810Y-170467D01*
X653227Y-170133D01*
X653810Y-169967D01*
X654393Y-170133D01*
X654810Y-170467D01*
X655060Y-170883D01*
Y-173300D01*
G01Y-170883D02*
X655310Y-170467D01*
X655727Y-170133D01*
X656310Y-169967D01*
X656893Y-170133D01*
X657310Y-170467D01*
X657560Y-170967D01*
Y-173300D01*
G01X659243Y-169967D02*
Y-172300D01*
X659577Y-172883D01*
X660077Y-173217D01*
X660660Y-173300D01*
X661243Y-173217D01*
X661743Y-172883D01*
X662077Y-172300D01*
G01Y-173300D02*
Y-169967D01*
G01X665010Y-172717D02*
X665427Y-173050D01*
X666010Y-173300D01*
X666510D01*
X667010Y-173133D01*
X667343Y-172883D01*
X667510Y-172550D01*
X667427Y-172050D01*
X667093Y-171800D01*
X665593Y-171300D01*
X665260Y-170717D01*
X665427Y-170300D01*
X665760Y-170050D01*
X666260Y-169967D01*
X666760Y-170050D01*
X667260Y-170300D01*
G01X671860Y-168300D02*
Y-173300D01*
G01X670693Y-169967D02*
X673027D01*
G01X681560Y-173300D02*
Y-168300D01*
G01Y-170800D02*
X681977Y-170300D01*
X682477Y-170050D01*
X682977Y-169967D01*
X683727Y-170133D01*
X684227Y-170467D01*
X684560Y-171050D01*
Y-171717D01*
X684393Y-172383D01*
X684060Y-172883D01*
X683477Y-173217D01*
X682977Y-173300D01*
X682477Y-173217D01*
X681977Y-172967D01*
X681560Y-172550D01*
G01X687410Y-171050D02*
X690077D01*
X689827Y-170467D01*
X689410Y-170133D01*
X688827Y-169967D01*
X688243Y-170050D01*
X687743Y-170300D01*
X687410Y-170883D01*
X687243Y-171383D01*
Y-171883D01*
X687410Y-172383D01*
X687827Y-172883D01*
X688327Y-173217D01*
X688910Y-173300D01*
X689493Y-173133D01*
X690077Y-172633D01*
G01X698360Y-173300D02*
Y-168300D01*
G01Y-170800D02*
X698777Y-170300D01*
X699277Y-170050D01*
X699777Y-169967D01*
X700527Y-170133D01*
X701027Y-170467D01*
X701360Y-171050D01*
Y-171717D01*
X701193Y-172383D01*
X700860Y-172883D01*
X700277Y-173217D01*
X699777Y-173300D01*
X699277Y-173217D01*
X698777Y-172967D01*
X698360Y-172550D01*
G01X704293Y-173300D02*
Y-169967D01*
G01Y-170633D02*
X704710Y-170300D01*
X705127Y-170050D01*
X705710Y-169967D01*
X706127Y-170050D01*
X706627Y-170300D01*
G01X711060Y-173300D02*
X710560Y-173217D01*
X710060Y-172883D01*
X709727Y-172300D01*
X709560Y-171633D01*
X709727Y-170967D01*
X710060Y-170383D01*
X710560Y-170050D01*
X711060Y-169967D01*
X711560Y-170050D01*
X712060Y-170383D01*
X712393Y-170967D01*
X712477Y-171633D01*
X712393Y-172300D01*
X712060Y-172883D01*
X711560Y-173217D01*
X711060Y-173300D01*
G01X715243D02*
Y-168300D01*
G01X717910Y-169967D02*
X715243Y-171883D01*
G01X716327Y-171133D02*
X718077Y-173300D01*
G01X721010Y-171050D02*
X723677D01*
X723427Y-170467D01*
X723010Y-170133D01*
X722427Y-169967D01*
X721843Y-170050D01*
X721343Y-170300D01*
X721010Y-170883D01*
X720843Y-171383D01*
Y-171883D01*
X721010Y-172383D01*
X721427Y-172883D01*
X721927Y-173217D01*
X722510Y-173300D01*
X723093Y-173133D01*
X723677Y-172633D01*
G01X726443Y-173300D02*
Y-169967D01*
G01Y-170800D02*
X726777Y-170383D01*
X727277Y-170050D01*
X727943Y-169967D01*
X728527Y-170050D01*
X729027Y-170383D01*
X729277Y-170967D01*
Y-173300D01*
G01X739060D02*
Y-168300D01*
G01X746160Y-173300D02*
Y-169967D01*
G01Y-170550D02*
X745827Y-170217D01*
X745327Y-170050D01*
X744743Y-169967D01*
X744160Y-170133D01*
X743660Y-170467D01*
X743327Y-170967D01*
X743160Y-171633D01*
X743327Y-172300D01*
X743660Y-172800D01*
X744160Y-173133D01*
X744743Y-173300D01*
X745327Y-173217D01*
X745827Y-172967D01*
X746160Y-172633D01*
G01X748510Y-174800D02*
X749010Y-174967D01*
X749677Y-174800D01*
X750093Y-174467D01*
X750427Y-174050D01*
X750927Y-172717D01*
X752010Y-169967D01*
G01X749343D02*
X750927Y-172717D01*
G01X754610Y-171050D02*
X757277D01*
X757027Y-170467D01*
X756610Y-170133D01*
X756027Y-169967D01*
X755443Y-170050D01*
X754943Y-170300D01*
X754610Y-170883D01*
X754443Y-171383D01*
Y-171883D01*
X754610Y-172383D01*
X755027Y-172883D01*
X755527Y-173217D01*
X756110Y-173300D01*
X756693Y-173133D01*
X757277Y-172633D01*
G01X760293Y-173300D02*
Y-169967D01*
G01Y-170633D02*
X760710Y-170300D01*
X761127Y-170050D01*
X761710Y-169967D01*
X762127Y-170050D01*
X762627Y-170300D01*
G01X630393Y-155800D02*
Y-160800D01*
X633727D01*
G01X636243D02*
Y-157467D01*
G01Y-158300D02*
X636577Y-157883D01*
X637077Y-157550D01*
X637743Y-157467D01*
X638327Y-157550D01*
X638827Y-157883D01*
X639077Y-158467D01*
Y-160800D01*
G01X643260Y-160967D02*
X643093Y-160883D01*
Y-160717D01*
X643260Y-160633D01*
X643427Y-160717D01*
Y-160883D01*
X643260Y-160967D01*
G01Y-158717D02*
X643093Y-158633D01*
Y-158467D01*
X643260Y-158383D01*
X643427Y-158467D01*
Y-158633D01*
X643260Y-158717D01*
G01X655793Y-157883D02*
X655210Y-157550D01*
X654710Y-157467D01*
X654043Y-157633D01*
X653543Y-157967D01*
X653210Y-158550D01*
X653127Y-159133D01*
X653210Y-159717D01*
X653543Y-160217D01*
X654043Y-160633D01*
X654710Y-160800D01*
X655293Y-160633D01*
X655793Y-160300D01*
G01X661560Y-160800D02*
Y-157467D01*
G01Y-158050D02*
X661227Y-157717D01*
X660727Y-157550D01*
X660143Y-157467D01*
X659560Y-157633D01*
X659060Y-157967D01*
X658727Y-158467D01*
X658560Y-159133D01*
X658727Y-159800D01*
X659060Y-160300D01*
X659560Y-160633D01*
X660143Y-160800D01*
X660727Y-160717D01*
X661227Y-160467D01*
X661560Y-160133D01*
G01X664243Y-160800D02*
Y-157467D01*
G01Y-158300D02*
X664577Y-157883D01*
X665077Y-157550D01*
X665743Y-157467D01*
X666327Y-157550D01*
X666827Y-157883D01*
X667077Y-158467D01*
Y-160800D01*
G01X671260Y-157467D02*
X672093Y-156425D01*
Y-155800D01*
X671468D01*
Y-156425D01*
X672093D01*
G01X676860Y-155800D02*
Y-160800D01*
G01X675693Y-157467D02*
X678027D01*
G01X686560Y-160800D02*
Y-155800D01*
G01Y-158300D02*
X686977Y-157800D01*
X687477Y-157550D01*
X687977Y-157467D01*
X688727Y-157633D01*
X689227Y-157967D01*
X689560Y-158550D01*
Y-159217D01*
X689393Y-159883D01*
X689060Y-160383D01*
X688477Y-160717D01*
X687977Y-160800D01*
X687477Y-160717D01*
X686977Y-160467D01*
X686560Y-160050D01*
G01X692410Y-158550D02*
X695077D01*
X694827Y-157967D01*
X694410Y-157633D01*
X693827Y-157467D01*
X693243Y-157550D01*
X692743Y-157800D01*
X692410Y-158383D01*
X692243Y-158883D01*
Y-159383D01*
X692410Y-159883D01*
X692827Y-160383D01*
X693327Y-160717D01*
X693910Y-160800D01*
X694493Y-160633D01*
X695077Y-160133D01*
G01X703360Y-160800D02*
Y-155800D01*
G01Y-158300D02*
X703777Y-157800D01*
X704277Y-157550D01*
X704777Y-157467D01*
X705527Y-157633D01*
X706027Y-157967D01*
X706360Y-158550D01*
Y-159217D01*
X706193Y-159883D01*
X705860Y-160383D01*
X705277Y-160717D01*
X704777Y-160800D01*
X704277Y-160717D01*
X703777Y-160467D01*
X703360Y-160050D01*
G01X709293Y-160800D02*
Y-157467D01*
G01Y-158133D02*
X709710Y-157800D01*
X710127Y-157550D01*
X710710Y-157467D01*
X711127Y-157550D01*
X711627Y-157800D01*
G01X716060Y-160800D02*
X715560Y-160717D01*
X715060Y-160383D01*
X714727Y-159800D01*
X714560Y-159133D01*
X714727Y-158467D01*
X715060Y-157883D01*
X715560Y-157550D01*
X716060Y-157467D01*
X716560Y-157550D01*
X717060Y-157883D01*
X717393Y-158467D01*
X717477Y-159133D01*
X717393Y-159800D01*
X717060Y-160383D01*
X716560Y-160717D01*
X716060Y-160800D01*
G01X720243D02*
Y-155800D01*
G01X722910Y-157467D02*
X720243Y-159383D01*
G01X721327Y-158633D02*
X723077Y-160800D01*
G01X726010Y-158550D02*
X728677D01*
X728427Y-157967D01*
X728010Y-157633D01*
X727427Y-157467D01*
X726843Y-157550D01*
X726343Y-157800D01*
X726010Y-158383D01*
X725843Y-158883D01*
Y-159383D01*
X726010Y-159883D01*
X726427Y-160383D01*
X726927Y-160717D01*
X727510Y-160800D01*
X728093Y-160633D01*
X728677Y-160133D01*
G01X731443Y-160800D02*
Y-157467D01*
G01Y-158300D02*
X731777Y-157883D01*
X732277Y-157550D01*
X732943Y-157467D01*
X733527Y-157550D01*
X734027Y-157883D01*
X734277Y-158467D01*
Y-160800D01*
G01X744060D02*
Y-155800D01*
G01X751160Y-160800D02*
Y-157467D01*
G01Y-158050D02*
X750827Y-157717D01*
X750327Y-157550D01*
X749743Y-157467D01*
X749160Y-157633D01*
X748660Y-157967D01*
X748327Y-158467D01*
X748160Y-159133D01*
X748327Y-159800D01*
X748660Y-160300D01*
X749160Y-160633D01*
X749743Y-160800D01*
X750327Y-160717D01*
X750827Y-160467D01*
X751160Y-160133D01*
G01X753510Y-162300D02*
X754010Y-162467D01*
X754677Y-162300D01*
X755093Y-161967D01*
X755427Y-161550D01*
X755927Y-160217D01*
X757010Y-157467D01*
G01X754343D02*
X755927Y-160217D01*
G01X759610Y-158550D02*
X762277D01*
X762027Y-157967D01*
X761610Y-157633D01*
X761027Y-157467D01*
X760443Y-157550D01*
X759943Y-157800D01*
X759610Y-158383D01*
X759443Y-158883D01*
Y-159383D01*
X759610Y-159883D01*
X760027Y-160383D01*
X760527Y-160717D01*
X761110Y-160800D01*
X761693Y-160633D01*
X762277Y-160133D01*
G01X765293Y-160800D02*
Y-157467D01*
G01Y-158133D02*
X765710Y-157800D01*
X766127Y-157550D01*
X766710Y-157467D01*
X767127Y-157550D01*
X767627Y-157800D01*
G01X629167Y-149000D02*
Y-144000D01*
X630833D01*
X631500Y-144250D01*
X632000Y-144583D01*
X632417Y-145083D01*
X632750Y-145667D01*
X632833Y-146500D01*
X632750Y-147333D01*
X632417Y-147917D01*
X632000Y-148417D01*
X631500Y-148750D01*
X630833Y-149000D01*
X629167D01*
G01X635433D02*
Y-145667D01*
G01Y-146333D02*
X635850Y-146000D01*
X636267Y-145750D01*
X636850Y-145667D01*
X637267Y-145750D01*
X637767Y-146000D01*
G01X642200Y-145667D02*
Y-149000D01*
G01Y-144333D02*
X642033Y-144250D01*
Y-144083D01*
X642200Y-144000D01*
X642367Y-144083D01*
Y-144250D01*
X642200Y-144333D01*
G01X647800Y-149000D02*
Y-144000D01*
G01X653400Y-149000D02*
Y-144000D01*
G01X663017Y-149000D02*
Y-144000D01*
X666183D01*
G01X665017Y-146417D02*
X663017D01*
G01X669033Y-149000D02*
Y-145667D01*
G01Y-146333D02*
X669450Y-146000D01*
X669867Y-145750D01*
X670450Y-145667D01*
X670867Y-145750D01*
X671367Y-146000D01*
G01X675800Y-149000D02*
X675300Y-148917D01*
X674800Y-148583D01*
X674467Y-148000D01*
X674300Y-147333D01*
X674467Y-146667D01*
X674800Y-146083D01*
X675300Y-145750D01*
X675800Y-145667D01*
X676300Y-145750D01*
X676800Y-146083D01*
X677133Y-146667D01*
X677217Y-147333D01*
X677133Y-148000D01*
X676800Y-148583D01*
X676300Y-148917D01*
X675800Y-149000D01*
G01X678900D02*
Y-145667D01*
G01Y-146583D02*
X679150Y-146167D01*
X679567Y-145833D01*
X680150Y-145667D01*
X680733Y-145833D01*
X681150Y-146167D01*
X681400Y-146583D01*
Y-149000D01*
G01Y-146583D02*
X681650Y-146167D01*
X682067Y-145833D01*
X682650Y-145667D01*
X683233Y-145833D01*
X683650Y-146167D01*
X683900Y-146667D01*
Y-149000D01*
G01X708983Y-150667D02*
X708150Y-149833D01*
X707733Y-149000D01*
Y-145667D01*
X708150Y-144833D01*
X708983Y-144000D01*
G01X715667Y-146333D02*
X716000Y-146083D01*
X716250Y-145667D01*
X716417Y-145083D01*
X716250Y-144583D01*
X715917Y-144250D01*
X715333Y-144000D01*
X713083D01*
Y-149000D01*
X715833D01*
X716417Y-148667D01*
X716750Y-148167D01*
X716917Y-147583D01*
X716750Y-147000D01*
X716250Y-146500D01*
X715667Y-146333D01*
X713083D01*
G01X720600Y-149000D02*
X719933Y-148917D01*
X719350Y-148583D01*
X718850Y-148083D01*
X718517Y-147500D01*
X718350Y-146833D01*
Y-146167D01*
X718517Y-145500D01*
X718850Y-144917D01*
X719350Y-144417D01*
X719933Y-144083D01*
X720600Y-144000D01*
X721267Y-144083D01*
X721850Y-144417D01*
X722350Y-144917D01*
X722683Y-145500D01*
X722850Y-146167D01*
Y-146833D01*
X722683Y-147500D01*
X722350Y-148083D01*
X721850Y-148583D01*
X721267Y-148917D01*
X720600Y-149000D01*
G01X726200Y-144000D02*
Y-149000D01*
G01X724283Y-144000D02*
X728117D01*
G01X731800D02*
Y-149000D01*
G01X729883Y-144000D02*
X733717D01*
G01X737400Y-149000D02*
X736733Y-148917D01*
X736150Y-148583D01*
X735650Y-148083D01*
X735317Y-147500D01*
X735150Y-146833D01*
Y-146167D01*
X735317Y-145500D01*
X735650Y-144917D01*
X736150Y-144417D01*
X736733Y-144083D01*
X737400Y-144000D01*
X738067Y-144083D01*
X738650Y-144417D01*
X739150Y-144917D01*
X739483Y-145500D01*
X739650Y-146167D01*
Y-146833D01*
X739483Y-147500D01*
X739150Y-148083D01*
X738650Y-148583D01*
X738067Y-148917D01*
X737400Y-149000D01*
G01X740833D02*
Y-144000D01*
X743000Y-148167D01*
X745167Y-144000D01*
Y-149000D01*
G01X749017Y-150667D02*
X749850Y-149833D01*
X750267Y-149000D01*
Y-145667D01*
X749850Y-144833D01*
X749017Y-144000D01*
G01X759800D02*
Y-149000D01*
G01X758633Y-145667D02*
X760967D01*
G01X765400Y-149000D02*
X764900Y-148917D01*
X764400Y-148583D01*
X764067Y-148000D01*
X763900Y-147333D01*
X764067Y-146667D01*
X764400Y-146083D01*
X764900Y-145750D01*
X765400Y-145667D01*
X765900Y-145750D01*
X766400Y-146083D01*
X766733Y-146667D01*
X766817Y-147333D01*
X766733Y-148000D01*
X766400Y-148583D01*
X765900Y-148917D01*
X765400Y-149000D01*
G01X774933Y-144000D02*
Y-149000D01*
X778267D01*
G01X780950Y-145667D02*
X783450Y-149000D01*
G01Y-145667D02*
X780950Y-149000D01*
G01X647917Y462500D02*
X650000Y457500D01*
X652083Y462500D01*
G01X654600D02*
X656600D01*
G01X655600D02*
Y457500D01*
G01X654600D02*
X656600D01*
G01X659533D02*
Y462500D01*
X661533D01*
X662200Y462250D01*
X662700Y461667D01*
X662867Y461000D01*
X662700Y460333D01*
X662283Y459833D01*
X661533Y459583D01*
X659533D01*
G01X651333Y317500D02*
Y322500D01*
X653333D01*
X654000Y322250D01*
X654500Y321667D01*
X654667Y321000D01*
X654500Y320333D01*
X654083Y319833D01*
X653333Y319583D01*
X651333D01*
G01X658600Y317500D02*
Y322500D01*
G01X662783Y320833D02*
Y318500D01*
X663117Y317917D01*
X663617Y317583D01*
X664200Y317500D01*
X664783Y317583D01*
X665283Y317917D01*
X665617Y318500D01*
G01Y317500D02*
Y320833D01*
G01X668633Y316250D02*
X669217Y315917D01*
X669883Y315833D01*
X670467Y315917D01*
X670967Y316333D01*
X671300Y316917D01*
Y320833D01*
G01Y320167D02*
X670967Y320500D01*
X670467Y320750D01*
X669883Y320833D01*
X669217Y320667D01*
X668800Y320333D01*
X668467Y319750D01*
X668300Y319167D01*
X668383Y318667D01*
X668717Y318083D01*
X669217Y317667D01*
X669883Y317500D01*
X670383Y317583D01*
X670967Y317917D01*
X671300Y318250D01*
G01X674233Y316250D02*
X674817Y315917D01*
X675483Y315833D01*
X676067Y315917D01*
X676567Y316333D01*
X676900Y316917D01*
Y320833D01*
G01Y320167D02*
X676567Y320500D01*
X676067Y320750D01*
X675483Y320833D01*
X674817Y320667D01*
X674400Y320333D01*
X674067Y319750D01*
X673900Y319167D01*
X673983Y318667D01*
X674317Y318083D01*
X674817Y317667D01*
X675483Y317500D01*
X675983Y317583D01*
X676567Y317917D01*
X676900Y318250D01*
G01X681000Y320833D02*
Y317500D01*
G01Y322167D02*
X680833Y322250D01*
Y322417D01*
X681000Y322500D01*
X681167Y322417D01*
Y322250D01*
X681000Y322167D01*
G01X685183Y317500D02*
Y320833D01*
G01Y320000D02*
X685517Y320417D01*
X686017Y320750D01*
X686683Y320833D01*
X687267Y320750D01*
X687767Y320417D01*
X688017Y319833D01*
Y317500D01*
G01X691033Y316250D02*
X691617Y315917D01*
X692283Y315833D01*
X692867Y315917D01*
X693367Y316333D01*
X693700Y316917D01*
Y320833D01*
G01Y320167D02*
X693367Y320500D01*
X692867Y320750D01*
X692283Y320833D01*
X691617Y320667D01*
X691200Y320333D01*
X690867Y319750D01*
X690700Y319167D01*
X690783Y318667D01*
X691117Y318083D01*
X691617Y317667D01*
X692283Y317500D01*
X692783Y317583D01*
X693367Y317917D01*
X693700Y318250D01*
G01X704733Y320417D02*
X704150Y320750D01*
X703650Y320833D01*
X702983Y320667D01*
X702483Y320333D01*
X702150Y319750D01*
X702067Y319167D01*
X702150Y318583D01*
X702483Y318083D01*
X702983Y317667D01*
X703650Y317500D01*
X704233Y317667D01*
X704733Y318000D01*
G01X707833Y317500D02*
Y320833D01*
G01Y320167D02*
X708250Y320500D01*
X708667Y320750D01*
X709250Y320833D01*
X709667Y320750D01*
X710167Y320500D01*
G01X714600Y320833D02*
Y317500D01*
G01Y322167D02*
X714433Y322250D01*
Y322417D01*
X714600Y322500D01*
X714767Y322417D01*
Y322250D01*
X714600Y322167D01*
G01X720200Y322500D02*
Y317500D01*
G01X719033Y320833D02*
X721367D01*
G01X724550Y319750D02*
X727217D01*
X726967Y320333D01*
X726550Y320667D01*
X725967Y320833D01*
X725383Y320750D01*
X724883Y320500D01*
X724550Y319917D01*
X724383Y319417D01*
Y318917D01*
X724550Y318417D01*
X724967Y317917D01*
X725467Y317583D01*
X726050Y317500D01*
X726633Y317667D01*
X727217Y318167D01*
G01X730233Y317500D02*
Y320833D01*
G01Y320167D02*
X730650Y320500D01*
X731067Y320750D01*
X731650Y320833D01*
X732067Y320750D01*
X732567Y320500D01*
G01X737000Y320833D02*
Y317500D01*
G01Y322167D02*
X736833Y322250D01*
Y322417D01*
X737000Y322500D01*
X737167Y322417D01*
Y322250D01*
X737000Y322167D01*
G01X744100Y317500D02*
Y320833D01*
G01Y320250D02*
X743767Y320583D01*
X743267Y320750D01*
X742683Y320833D01*
X742100Y320667D01*
X741600Y320333D01*
X741267Y319833D01*
X741100Y319167D01*
X741267Y318500D01*
X741600Y318000D01*
X742100Y317667D01*
X742683Y317500D01*
X743267Y317583D01*
X743767Y317833D01*
X744100Y318167D01*
G01X677667Y-115300D02*
Y-110300D01*
X679333D01*
X680000Y-110550D01*
X680500Y-110883D01*
X680917Y-111383D01*
X681250Y-111967D01*
X681333Y-112800D01*
X681250Y-113633D01*
X680917Y-114217D01*
X680500Y-114717D01*
X680000Y-115050D01*
X679333Y-115300D01*
X677667D01*
G01X683517Y-111133D02*
X684017Y-110633D01*
X684600Y-110383D01*
X685267Y-110300D01*
X686100Y-110467D01*
X686683Y-110883D01*
X686850Y-111383D01*
X686767Y-111883D01*
X686433Y-112300D01*
X684767Y-113133D01*
X684017Y-113717D01*
X683517Y-114550D01*
X683350Y-115300D01*
X686850D01*
G01X676667Y42700D02*
Y47700D01*
X678333D01*
X679000Y47450D01*
X679500Y47117D01*
X679917Y46617D01*
X680250Y46033D01*
X680333Y45200D01*
X680250Y44367D01*
X679917Y43783D01*
X679500Y43283D01*
X679000Y42950D01*
X678333Y42700D01*
X676667D01*
G01X684100D02*
Y47700D01*
X683100Y46700D01*
G01Y42700D02*
X685100D01*
G01X678333Y346917D02*
X677750Y347250D01*
X677250Y347333D01*
X676583Y347167D01*
X676083Y346833D01*
X675750Y346250D01*
X675667Y345667D01*
X675750Y345083D01*
X676083Y344583D01*
X676583Y344167D01*
X677250Y344000D01*
X677833Y344167D01*
X678333Y344500D01*
G01X682600Y344000D02*
X682100Y344083D01*
X681600Y344417D01*
X681267Y345000D01*
X681100Y345667D01*
X681267Y346333D01*
X681600Y346917D01*
X682100Y347250D01*
X682600Y347333D01*
X683100Y347250D01*
X683600Y346917D01*
X683933Y346333D01*
X684017Y345667D01*
X683933Y345000D01*
X683600Y344417D01*
X683100Y344083D01*
X682600Y344000D01*
G01X686700Y342333D02*
Y347333D01*
G01Y346583D02*
X687117Y347000D01*
X687533Y347250D01*
X688200Y347333D01*
X688783Y347250D01*
X689367Y346833D01*
X689617Y346250D01*
X689700Y345667D01*
X689617Y345083D01*
X689367Y344500D01*
X688867Y344167D01*
X688200Y344000D01*
X687617Y344083D01*
X687033Y344333D01*
X686700Y344667D01*
G01X692300Y342333D02*
Y347333D01*
G01Y346583D02*
X692717Y347000D01*
X693133Y347250D01*
X693800Y347333D01*
X694383Y347250D01*
X694967Y346833D01*
X695217Y346250D01*
X695300Y345667D01*
X695217Y345083D01*
X694967Y344500D01*
X694467Y344167D01*
X693800Y344000D01*
X693217Y344083D01*
X692633Y344333D01*
X692300Y344667D01*
G01X698150Y346250D02*
X700817D01*
X700567Y346833D01*
X700150Y347167D01*
X699567Y347333D01*
X698983Y347250D01*
X698483Y347000D01*
X698150Y346417D01*
X697983Y345917D01*
Y345417D01*
X698150Y344917D01*
X698567Y344417D01*
X699067Y344083D01*
X699650Y344000D01*
X700233Y344167D01*
X700817Y344667D01*
G01X703833Y344000D02*
Y347333D01*
G01Y346667D02*
X704250Y347000D01*
X704667Y347250D01*
X705250Y347333D01*
X705667Y347250D01*
X706167Y347000D01*
G01X726167Y-122633D02*
X726500Y-122383D01*
X726750Y-121967D01*
X726917Y-121383D01*
X726750Y-120883D01*
X726417Y-120550D01*
X725833Y-120300D01*
X723583D01*
Y-125300D01*
X726333D01*
X726917Y-124967D01*
X727250Y-124467D01*
X727417Y-123883D01*
X727250Y-123300D01*
X726750Y-122800D01*
X726167Y-122633D01*
X723583D01*
G01X729017Y-125300D02*
X731100Y-120300D01*
X733183Y-125300D01*
G01X732433Y-123550D02*
X729767D01*
G01X738533Y-120717D02*
X738033Y-120467D01*
X737450Y-120300D01*
X736783D01*
X736033Y-120550D01*
X735450Y-120967D01*
X735033Y-121467D01*
X734700Y-122300D01*
X734617Y-123050D01*
X734783Y-123800D01*
X735033Y-124300D01*
X735533Y-124800D01*
X736117Y-125133D01*
X736700Y-125300D01*
X737283D01*
X737867Y-125133D01*
X738367Y-124883D01*
X738783Y-124550D01*
G01X740467Y-125300D02*
Y-120300D01*
G01X743633D02*
X740467Y-123383D01*
G01X744133Y-125300D02*
X741883Y-121967D01*
G01X751667Y-125300D02*
Y-120300D01*
X753333D01*
X754000Y-120550D01*
X754500Y-120883D01*
X754917Y-121383D01*
X755250Y-121967D01*
X755333Y-122800D01*
X755250Y-123633D01*
X754917Y-124217D01*
X754500Y-124717D01*
X754000Y-125050D01*
X753333Y-125300D01*
X751667D01*
G01X757433D02*
Y-120300D01*
X759517D01*
X760183Y-120550D01*
X760600Y-120883D01*
X760767Y-121550D01*
X760600Y-122217D01*
X760100Y-122633D01*
X759517Y-122883D01*
X757433D01*
G01X759517D02*
X760767Y-125300D01*
G01X763700Y-120300D02*
X765700D01*
G01X764700D02*
Y-125300D01*
G01X763700D02*
X765700D01*
G01X768633Y-120300D02*
Y-125300D01*
X771967D01*
G01X774233Y-120300D02*
Y-125300D01*
X777567D01*
G01X801400D02*
Y-121967D01*
G01Y-122883D02*
X801650Y-122467D01*
X802067Y-122133D01*
X802650Y-121967D01*
X803233Y-122133D01*
X803650Y-122467D01*
X803900Y-122883D01*
Y-125300D01*
G01Y-122883D02*
X804150Y-122467D01*
X804567Y-122133D01*
X805150Y-121967D01*
X805733Y-122133D01*
X806150Y-122467D01*
X806400Y-122967D01*
Y-125300D01*
G01X809500Y-121967D02*
Y-125300D01*
G01Y-120633D02*
X809333Y-120550D01*
Y-120383D01*
X809500Y-120300D01*
X809667Y-120383D01*
Y-120550D01*
X809500Y-120633D01*
G01X815100Y-125300D02*
Y-120300D01*
G01X819450Y-124717D02*
X819867Y-125050D01*
X820450Y-125300D01*
X820950D01*
X821450Y-125133D01*
X821783Y-124883D01*
X821950Y-124550D01*
X821867Y-124050D01*
X821533Y-123800D01*
X820033Y-123300D01*
X819700Y-122717D01*
X819867Y-122300D01*
X820200Y-122050D01*
X820700Y-121967D01*
X821200Y-122050D01*
X821700Y-122300D01*
G01X825883Y-126967D02*
X825050Y-126133D01*
X824633Y-125300D01*
Y-121967D01*
X825050Y-121133D01*
X825883Y-120300D01*
G01X829983Y-125300D02*
Y-120300D01*
X833817Y-125300D01*
Y-120300D01*
G01X835833Y-125300D02*
Y-120300D01*
X837833D01*
X838500Y-120550D01*
X839000Y-121133D01*
X839167Y-121800D01*
X839000Y-122467D01*
X838583Y-122967D01*
X837833Y-123217D01*
X835833D01*
G01X843100Y-120300D02*
Y-125300D01*
G01X841183Y-120300D02*
X845017D01*
G01X846950Y-125300D02*
Y-120300D01*
G01X850450D02*
Y-125300D01*
G01Y-122800D02*
X846950D01*
G01X854717Y-126967D02*
X855550Y-126133D01*
X855967Y-125300D01*
Y-121967D01*
X855550Y-121133D01*
X854717Y-120300D01*
G01X720250Y42500D02*
Y47500D01*
G01X723750D02*
Y42500D01*
G01Y45000D02*
X720250D01*
G01X727600Y42500D02*
X726933Y42583D01*
X726350Y42917D01*
X725850Y43417D01*
X725517Y44000D01*
X725350Y44667D01*
Y45333D01*
X725517Y46000D01*
X725850Y46583D01*
X726350Y47083D01*
X726933Y47417D01*
X727600Y47500D01*
X728267Y47417D01*
X728850Y47083D01*
X729350Y46583D01*
X729683Y46000D01*
X729850Y45333D01*
Y44667D01*
X729683Y44000D01*
X729350Y43417D01*
X728850Y42917D01*
X728267Y42583D01*
X727600Y42500D01*
G01X731533Y47500D02*
Y42500D01*
X734867D01*
G01X740467D02*
X737133D01*
Y47500D01*
X740467D01*
G01X739133Y45083D02*
X737133D01*
G01X764300Y42500D02*
Y45833D01*
G01Y44917D02*
X764550Y45333D01*
X764967Y45667D01*
X765550Y45833D01*
X766133Y45667D01*
X766550Y45333D01*
X766800Y44917D01*
Y42500D01*
G01Y44917D02*
X767050Y45333D01*
X767467Y45667D01*
X768050Y45833D01*
X768633Y45667D01*
X769050Y45333D01*
X769300Y44833D01*
Y42500D01*
G01X772400Y45833D02*
Y42500D01*
G01Y47167D02*
X772233Y47250D01*
Y47417D01*
X772400Y47500D01*
X772567Y47417D01*
Y47250D01*
X772400Y47167D01*
G01X778000Y42500D02*
Y47500D01*
G01X782350Y43083D02*
X782767Y42750D01*
X783350Y42500D01*
X783850D01*
X784350Y42667D01*
X784683Y42917D01*
X784850Y43250D01*
X784767Y43750D01*
X784433Y44000D01*
X782933Y44500D01*
X782600Y45083D01*
X782767Y45500D01*
X783100Y45750D01*
X783600Y45833D01*
X784100Y45750D01*
X784600Y45500D01*
G01X788783Y40833D02*
X787950Y41667D01*
X787533Y42500D01*
Y45833D01*
X787950Y46667D01*
X788783Y47500D01*
G01X793133Y42500D02*
Y47500D01*
X795133D01*
X795800Y47250D01*
X796300Y46667D01*
X796467Y46000D01*
X796300Y45333D01*
X795883Y44833D01*
X795133Y44583D01*
X793133D01*
G01X800400Y47500D02*
Y42500D01*
G01X798483Y47500D02*
X802317D01*
G01X804250Y42500D02*
Y47500D01*
G01X807750D02*
Y42500D01*
G01Y45000D02*
X804250D01*
G01X812017Y40833D02*
X812850Y41667D01*
X813267Y42500D01*
Y45833D01*
X812850Y46667D01*
X812017Y47500D01*
G01X721917Y461500D02*
X724000Y456500D01*
X726083Y461500D01*
G01X729600Y456500D02*
X728933Y456583D01*
X728350Y456917D01*
X727850Y457417D01*
X727517Y458000D01*
X727350Y458667D01*
Y459333D01*
X727517Y460000D01*
X727850Y460583D01*
X728350Y461083D01*
X728933Y461417D01*
X729600Y461500D01*
X730267Y461417D01*
X730850Y461083D01*
X731350Y460583D01*
X731683Y460000D01*
X731850Y459333D01*
Y458667D01*
X731683Y458000D01*
X731350Y457417D01*
X730850Y456917D01*
X730267Y456583D01*
X729600Y456500D01*
G01X733533D02*
Y461500D01*
X735533D01*
X736200Y461250D01*
X736700Y460667D01*
X736867Y460000D01*
X736700Y459333D01*
X736283Y458833D01*
X735533Y458583D01*
X733533D01*
G01X748833Y-12500D02*
Y-17500D01*
X752167D01*
G01X754683D02*
Y-14167D01*
G01Y-15000D02*
X755017Y-14583D01*
X755517Y-14250D01*
X756183Y-14167D01*
X756767Y-14250D01*
X757267Y-14583D01*
X757517Y-15167D01*
Y-17500D01*
G01X751833Y-54300D02*
Y-59300D01*
X755167D01*
G01X757850Y-55967D02*
X760350Y-59300D01*
G01Y-55967D02*
X757850Y-59300D01*
G01X759750Y8583D02*
X760167Y8250D01*
X760750Y8000D01*
X761250D01*
X761750Y8167D01*
X762083Y8417D01*
X762250Y8750D01*
X762167Y9250D01*
X761833Y9500D01*
X760333Y10000D01*
X760000Y10583D01*
X760167Y11000D01*
X760500Y11250D01*
X761000Y11333D01*
X761500Y11250D01*
X762000Y11000D01*
G01X766600Y13000D02*
Y8000D01*
G01X765433Y11333D02*
X767767D01*
G01X770783D02*
Y9000D01*
X771117Y8417D01*
X771617Y8083D01*
X772200Y8000D01*
X772783Y8083D01*
X773283Y8417D01*
X773617Y9000D01*
G01Y8000D02*
Y11333D01*
G01X776300Y8000D02*
Y13000D01*
G01Y10500D02*
X776717Y11000D01*
X777217Y11250D01*
X777717Y11333D01*
X778467Y11167D01*
X778967Y10833D01*
X779300Y10250D01*
Y9583D01*
X779133Y8917D01*
X778800Y8417D01*
X778217Y8083D01*
X777717Y8000D01*
X777217Y8083D01*
X776717Y8333D01*
X776300Y8750D01*
G01X789000Y8000D02*
Y13000D01*
G01X793350Y10250D02*
X796017D01*
X795767Y10833D01*
X795350Y11167D01*
X794767Y11333D01*
X794183Y11250D01*
X793683Y11000D01*
X793350Y10417D01*
X793183Y9917D01*
Y9417D01*
X793350Y8917D01*
X793767Y8417D01*
X794267Y8083D01*
X794850Y8000D01*
X795433Y8167D01*
X796017Y8667D01*
G01X798783Y8000D02*
Y11333D01*
G01Y10500D02*
X799117Y10917D01*
X799617Y11250D01*
X800283Y11333D01*
X800867Y11250D01*
X801367Y10917D01*
X801617Y10333D01*
Y8000D01*
G01X804633Y6750D02*
X805217Y6417D01*
X805883Y6333D01*
X806467Y6417D01*
X806967Y6833D01*
X807300Y7417D01*
Y11333D01*
G01Y10667D02*
X806967Y11000D01*
X806467Y11250D01*
X805883Y11333D01*
X805217Y11167D01*
X804800Y10833D01*
X804467Y10250D01*
X804300Y9667D01*
X804383Y9167D01*
X804717Y8583D01*
X805217Y8167D01*
X805883Y8000D01*
X806383Y8083D01*
X806967Y8417D01*
X807300Y8750D01*
G01X811400Y13000D02*
Y8000D01*
G01X810233Y11333D02*
X812567D01*
G01X815583Y8000D02*
Y13000D01*
G01Y10583D02*
X816000Y11000D01*
X816417Y11250D01*
X817083Y11333D01*
X817583Y11250D01*
X818167Y10917D01*
X818417Y10417D01*
Y8000D01*
G01X821517Y8917D02*
X823683D01*
G01Y10417D02*
X821517D01*
G01X826617Y10083D02*
X827200Y10667D01*
X827700Y11000D01*
X828367Y11167D01*
X828950Y11000D01*
X829367Y10667D01*
X829700Y10167D01*
X829783Y9583D01*
X829700Y9083D01*
X829367Y8583D01*
X828867Y8167D01*
X828283Y8000D01*
X827617Y8167D01*
X827033Y8667D01*
X826700Y9417D01*
X826617Y10250D01*
X826783Y11333D01*
X827033Y11917D01*
X827450Y12500D01*
X828033Y12917D01*
X828617Y13000D01*
X829200Y12833D01*
X829617Y12417D01*
G01X832883Y9667D02*
X834883D01*
G01X833800Y10750D02*
Y8583D01*
G01X837900Y7833D02*
X840900Y13000D01*
G01X843917Y9667D02*
X846083D01*
G01X848767Y8750D02*
X849267Y8333D01*
X849850Y8083D01*
X850600Y8000D01*
X851350Y8167D01*
X851933Y8500D01*
X852350Y9083D01*
X852433Y9750D01*
X852267Y10417D01*
X851850Y10833D01*
X851267Y11167D01*
X850683Y11250D01*
X850100Y11167D01*
X849350Y10833D01*
X849600Y13000D01*
X851850D01*
G01X853700Y8000D02*
Y11333D01*
G01Y10417D02*
X853950Y10833D01*
X854367Y11167D01*
X854950Y11333D01*
X855533Y11167D01*
X855950Y10833D01*
X856200Y10417D01*
Y8000D01*
G01Y10417D02*
X856450Y10833D01*
X856867Y11167D01*
X857450Y11333D01*
X858033Y11167D01*
X858450Y10833D01*
X858700Y10333D01*
Y8000D01*
G01X861800Y11333D02*
Y8000D01*
G01Y12667D02*
X861633Y12750D01*
Y12917D01*
X861800Y13000D01*
X861967Y12917D01*
Y12750D01*
X861800Y12667D01*
G01X867400Y8000D02*
Y13000D01*
G01X784293Y512443D02*
X783460Y513277D01*
X783043Y514110D01*
Y517443D01*
X783460Y518277D01*
X784293Y519110D01*
G01X790310Y514110D02*
Y519110D01*
X789310Y518110D01*
G01Y514110D02*
X791310D01*
G01X795910Y513943D02*
X795743Y514027D01*
Y514193D01*
X795910Y514277D01*
X796077Y514193D01*
Y514027D01*
X795910Y513943D01*
G01X799927Y518277D02*
X800427Y518777D01*
X801010Y519027D01*
X801677Y519110D01*
X802510Y518943D01*
X803093Y518527D01*
X803260Y518027D01*
X803177Y517527D01*
X802843Y517110D01*
X801177Y516277D01*
X800427Y515693D01*
X799927Y514860D01*
X799760Y514110D01*
X803260D01*
G01X804610D02*
Y517443D01*
G01Y516527D02*
X804860Y516943D01*
X805277Y517277D01*
X805860Y517443D01*
X806443Y517277D01*
X806860Y516943D01*
X807110Y516527D01*
Y514110D01*
G01Y516527D02*
X807360Y516943D01*
X807777Y517277D01*
X808360Y517443D01*
X808943Y517277D01*
X809360Y516943D01*
X809610Y516443D01*
Y514110D01*
G01X810210D02*
Y517443D01*
G01Y516527D02*
X810460Y516943D01*
X810877Y517277D01*
X811460Y517443D01*
X812043Y517277D01*
X812460Y516943D01*
X812710Y516527D01*
Y514110D01*
G01Y516527D02*
X812960Y516943D01*
X813377Y517277D01*
X813960Y517443D01*
X814543Y517277D01*
X814960Y516943D01*
X815210Y516443D01*
Y514110D01*
G01X821743D02*
Y519110D01*
X823910Y514943D01*
X826077Y519110D01*
Y514110D01*
G01X831010D02*
Y517443D01*
G01Y516860D02*
X830677Y517193D01*
X830177Y517360D01*
X829593Y517443D01*
X829010Y517277D01*
X828510Y516943D01*
X828177Y516443D01*
X828010Y515777D01*
X828177Y515110D01*
X828510Y514610D01*
X829010Y514277D01*
X829593Y514110D01*
X830177Y514193D01*
X830677Y514443D01*
X831010Y514777D01*
G01X833860Y517443D02*
X836360Y514110D01*
G01Y517443D02*
X833860Y514110D01*
G01X841127Y512443D02*
X841960Y513277D01*
X842377Y514110D01*
Y517443D01*
X841960Y518277D01*
X841127Y519110D01*
G01X786377Y524230D02*
X783043Y525897D01*
X786377Y527563D01*
G01X789227Y525147D02*
X791393D01*
G01Y526647D02*
X789227D01*
G01X795910Y529230D02*
X795243Y529063D01*
X794743Y528647D01*
X794410Y528147D01*
X794160Y527480D01*
X794077Y526730D01*
X794160Y525980D01*
X794410Y525313D01*
X794743Y524813D01*
X795243Y524397D01*
X795910Y524230D01*
X796577Y524397D01*
X797077Y524813D01*
X797410Y525313D01*
X797660Y525980D01*
X797743Y526730D01*
X797660Y527480D01*
X797410Y528147D01*
X797077Y528647D01*
X796577Y529063D01*
X795910Y529230D01*
G01X801510Y524063D02*
X801343Y524147D01*
Y524313D01*
X801510Y524397D01*
X801677Y524313D01*
Y524147D01*
X801510Y524063D01*
G01X806943Y524230D02*
X807110Y525313D01*
X807360Y526230D01*
X807693Y527063D01*
X808110Y527980D01*
X808777Y529230D01*
X805443D01*
G01X810877Y524980D02*
X811377Y524563D01*
X811960Y524313D01*
X812710Y524230D01*
X813460Y524397D01*
X814043Y524730D01*
X814460Y525313D01*
X814543Y525980D01*
X814377Y526647D01*
X813960Y527063D01*
X813377Y527397D01*
X812793Y527480D01*
X812210Y527397D01*
X811460Y527063D01*
X811710Y529230D01*
X813960D01*
G01X816810Y524063D02*
X819810Y529230D01*
G01X816810D02*
X816310Y529063D01*
X816060Y528813D01*
X815893Y528313D01*
X816060Y527813D01*
X816310Y527563D01*
X816810Y527397D01*
X817310Y527563D01*
X817560Y527813D01*
X817727Y528313D01*
X817560Y528813D01*
X817310Y529063D01*
X816810Y529230D01*
G01X819810Y525897D02*
X819310Y525730D01*
X819060Y525480D01*
X818893Y524980D01*
X819060Y524480D01*
X819310Y524230D01*
X819810Y524063D01*
X820310Y524230D01*
X820560Y524480D01*
X820727Y524980D01*
X820560Y525480D01*
X820310Y525730D01*
X819810Y525897D01*
G01X776040Y577500D02*
Y509000D01*
G01X782583Y538667D02*
X784583D01*
G01X783500Y539750D02*
Y537583D01*
G01X787600Y536833D02*
X790600Y542000D01*
G01X793617Y538667D02*
X795783D01*
G01X798717Y541167D02*
X799217Y541667D01*
X799800Y541917D01*
X800467Y542000D01*
X801300Y541833D01*
X801883Y541417D01*
X802050Y540917D01*
X801967Y540417D01*
X801633Y540000D01*
X799967Y539167D01*
X799217Y538583D01*
X798717Y537750D01*
X798550Y537000D01*
X802050D01*
G01X803400D02*
Y540333D01*
G01Y539417D02*
X803650Y539833D01*
X804067Y540167D01*
X804650Y540333D01*
X805233Y540167D01*
X805650Y539833D01*
X805900Y539417D01*
Y537000D01*
G01Y539417D02*
X806150Y539833D01*
X806567Y540167D01*
X807150Y540333D01*
X807733Y540167D01*
X808150Y539833D01*
X808400Y539333D01*
Y537000D01*
G01X811500Y540333D02*
Y537000D01*
G01Y541667D02*
X811333Y541750D01*
Y541917D01*
X811500Y542000D01*
X811667Y541917D01*
Y541750D01*
X811500Y541667D01*
G01X817100Y537000D02*
Y542000D01*
G01X782583Y553667D02*
X784583D01*
G01X783500Y554750D02*
Y552583D01*
G01X787600Y551833D02*
X790600Y557000D01*
G01X793617Y553667D02*
X795783D01*
G01X798467Y552750D02*
X798967Y552333D01*
X799550Y552083D01*
X800300Y552000D01*
X801050Y552167D01*
X801633Y552500D01*
X802050Y553083D01*
X802133Y553750D01*
X801967Y554417D01*
X801550Y554833D01*
X800967Y555167D01*
X800383Y555250D01*
X799800Y555167D01*
X799050Y554833D01*
X799300Y557000D01*
X801550D01*
G01X803400Y552000D02*
Y555333D01*
G01Y554417D02*
X803650Y554833D01*
X804067Y555167D01*
X804650Y555333D01*
X805233Y555167D01*
X805650Y554833D01*
X805900Y554417D01*
Y552000D01*
G01Y554417D02*
X806150Y554833D01*
X806567Y555167D01*
X807150Y555333D01*
X807733Y555167D01*
X808150Y554833D01*
X808400Y554333D01*
Y552000D01*
G01X811500Y555333D02*
Y552000D01*
G01Y556667D02*
X811333Y556750D01*
Y556917D01*
X811500Y557000D01*
X811667Y556917D01*
Y556750D01*
X811500Y556667D01*
G01X817100Y552000D02*
Y557000D01*
G01X782583Y568667D02*
X784583D01*
G01X783500Y569750D02*
Y567583D01*
G01X787600Y566833D02*
X790600Y572000D01*
G01X793617Y568667D02*
X795783D01*
G01X798467Y567750D02*
X798967Y567333D01*
X799550Y567083D01*
X800300Y567000D01*
X801050Y567167D01*
X801633Y567500D01*
X802050Y568083D01*
X802133Y568750D01*
X801967Y569417D01*
X801550Y569833D01*
X800967Y570167D01*
X800383Y570250D01*
X799800Y570167D01*
X799050Y569833D01*
X799300Y572000D01*
X801550D01*
G01X803400Y567000D02*
Y570333D01*
G01Y569417D02*
X803650Y569833D01*
X804067Y570167D01*
X804650Y570333D01*
X805233Y570167D01*
X805650Y569833D01*
X805900Y569417D01*
Y567000D01*
G01Y569417D02*
X806150Y569833D01*
X806567Y570167D01*
X807150Y570333D01*
X807733Y570167D01*
X808150Y569833D01*
X808400Y569333D01*
Y567000D01*
G01X811500Y570333D02*
Y567000D01*
G01Y571667D02*
X811333Y571750D01*
Y571917D01*
X811500Y572000D01*
X811667Y571917D01*
Y571750D01*
X811500Y571667D01*
G01X817100Y567000D02*
Y572000D01*
G01X884500Y577610D02*
Y509110D01*
G54D12*
G01X407352Y362354D02*
X385352D01*
G01D02*
Y439354D01*
G01D02*
X407352D01*
G01X399102Y355479D02*
X414227D01*
G01X399102Y362354D02*
Y355479D01*
G01Y448979D02*
Y442104D01*
G01X414227Y448979D02*
X399102D01*
G01X414227Y355479D02*
Y448979D01*
G01X407352Y439354D02*
Y362354D01*
G01X433477Y355479D02*
X448602D01*
G01X433477Y448979D02*
Y355479D01*
G01X448602Y448979D02*
X433477D01*
G01X448602Y355479D02*
Y362354D01*
G01X440352Y439354D02*
Y362354D01*
G01D02*
X484352D01*
G01Y439354D02*
X440352D01*
G01X448602Y442104D02*
Y448979D01*
G01X476102Y355479D02*
X491227D01*
G01X476102Y362354D02*
Y355479D01*
G01X484352Y362354D02*
Y439354D01*
G01X476102Y448979D02*
Y442104D01*
G01X491227Y448979D02*
X476102D01*
G01X491227Y355479D02*
Y448979D01*
G01X510477Y355479D02*
X525602D01*
G01X510477Y448979D02*
Y355479D01*
G01X517352Y439354D02*
Y362354D01*
G01D02*
X561352D01*
G01Y439354D02*
X517352D01*
G01X525602Y448979D02*
X510477D01*
G01X525602Y355479D02*
Y362354D01*
G01Y442104D02*
Y448979D01*
G01X553102Y355479D02*
X568227D01*
G01X553102Y362354D02*
Y355479D01*
G01X561352Y362354D02*
Y439354D01*
G01X553102Y446229D02*
Y439354D01*
G01X568227Y446229D02*
X553102D01*
G01X568227Y355479D02*
Y446229D01*
G01X587477Y355479D02*
X602602D01*
G01X587477Y446229D02*
Y355479D01*
G01X594352Y439354D02*
Y362354D01*
G01D02*
X638352D01*
G01Y439354D02*
X594352D01*
G01X602602Y446229D02*
X587477D01*
G01X602602Y355479D02*
Y362354D01*
G01Y439354D02*
Y446229D01*
G01X630102Y355479D02*
X664477D01*
G01X630102Y362354D02*
Y355479D01*
G01Y446229D02*
Y439354D01*
G01X645227Y446229D02*
X630102D01*
G01X638352Y362354D02*
Y439354D01*
G01X679602Y446229D02*
X645227D01*
G01X664477Y355479D02*
X679602D01*
G01D02*
Y362354D01*
G01X671352Y439354D02*
Y362354D01*
G01D02*
X715352D01*
G01Y439354D02*
X671352D01*
G01X679602D02*
Y446229D01*
G01X707102Y355479D02*
X722227D01*
G01X707102Y362354D02*
Y355479D01*
G01X715352Y362354D02*
Y439354D01*
G01X707102Y446229D02*
Y439354D01*
G01X722227Y446229D02*
X707102D01*
G01X722227Y355479D02*
Y446229D01*
G01X741477Y355479D02*
X756602D01*
G01X741477Y446229D02*
Y355479D01*
G01X748352Y439354D02*
Y362354D01*
G01D02*
X792352D01*
G01Y439354D02*
X748352D01*
G01X756602Y446229D02*
X741477D01*
G01X756602Y355479D02*
Y362354D01*
G01Y439354D02*
Y446229D01*
G01X792352Y362354D02*
Y439354D01*
G54D13*
G01X-166410Y67830D02*
Y84830D01*
G01X-155410Y46830D02*
Y30830D01*
G01X-116910Y46830D02*
Y30830D01*
G01X-112820Y54680D02*
G02X-108138Y46860I-4190J-7820D01*
G01X-110310Y48780D01*
X-107080Y48950D01*
X-108040Y46850D01*
G01X-102018Y57153D02*
X-106048Y51663D01*
X-101848Y51643D01*
G01X-105910Y67830D02*
Y84830D01*
G01X-18938Y28543D02*
X-22968Y23053D01*
X-18768Y23033D01*
G54D14*
G01X398827Y441387D02*
X395252Y444961D01*
G01X398250Y439629D02*
X395252Y442628D01*
G01X395917Y439629D02*
X395252Y440295D01*
G01X396558Y439629D02*
X398827Y441899D01*
G01X395252Y440657D02*
X398827Y444232D01*
G01X395252Y439629D02*
Y450240D01*
G01X398827Y439629D02*
X395252D01*
G01X398827Y446504D02*
Y439629D01*
G01X397840Y452829D02*
X414425D01*
G01X407985Y446229D02*
X401385Y452829D01*
G01X405651Y446229D02*
X399051Y452829D01*
G01X403318Y446229D02*
X397279Y452267D01*
G01X400985Y446229D02*
X396113Y451101D01*
G01X398827Y446053D02*
X395252Y449628D01*
G01X398827Y443720D02*
X395252Y447295D01*
G01X400823Y446229D02*
X407423Y452829D01*
G01X395252Y442991D02*
X405090Y452829D01*
G01X395252Y445324D02*
X402757Y452829D01*
G01X395252Y447657D02*
X400423Y452829D01*
G01X395252Y449991D02*
X398090Y452829D01*
G01X395252Y450240D02*
X397840Y452829D01*
G01X399102Y446229D02*
X398827Y446504D01*
G01X414502Y446229D02*
X399102D01*
G01X420892Y407653D02*
X414502Y414044D01*
G01X419238Y406974D02*
X414502Y411711D01*
G01X417810Y406069D02*
X414502Y409377D01*
G01X416580Y404966D02*
X414502Y407044D01*
G01X415545Y403668D02*
X414502Y404711D01*
G01X414715Y402163D02*
X414502Y402377D01*
G01Y403905D02*
X433202Y422603D01*
G01X414502Y406238D02*
X433202Y424938D01*
G01X414502Y408571D02*
X433202Y427271D01*
G01X414502Y401644D02*
Y446229D01*
G01Y401645D02*
Y401644D01*
G01X433201Y401645D02*
G03X414503I-9349J-3541D01*
G01X433202Y411678D02*
X414502Y430378D01*
G01X433202Y409345D02*
X414502Y428045D01*
G01X433202Y407012D02*
X414502Y425711D01*
G01Y417905D02*
X433202Y436604D01*
G01X414502Y420238D02*
X433202Y438938D01*
G01X414502Y422572D02*
X433202Y441272D01*
G01X414502Y424906D02*
X433202Y443605D01*
G01Y404678D02*
X414502Y423378D01*
G01X428698Y406848D02*
X414502Y421045D01*
G01X425203Y408010D02*
X414502Y418711D01*
G01X422830Y408049D02*
X414502Y416377D01*
G01Y410905D02*
X433202Y429604D01*
G01X414502Y413238D02*
X433202Y431938D01*
G01X414502Y415571D02*
X433202Y434271D01*
G01Y428013D02*
X408386Y452829D01*
G01X433202Y425679D02*
X414502Y444379D01*
G01X433202Y423346D02*
X414502Y442046D01*
G01X433202Y421013D02*
X414502Y439712D01*
G01X433202Y418679D02*
X414502Y437379D01*
G01X433202Y416346D02*
X414502Y435046D01*
G01X433202Y414012D02*
X414502Y432711D01*
G01Y427239D02*
X433202Y445939D01*
G01X414502Y429572D02*
X437758Y452829D01*
G01X414502Y431906D02*
X435425Y452829D01*
G01X414502Y434239D02*
X426606Y446344D01*
G01X414502Y436572D02*
X423882Y445952D01*
G01X414502Y438907D02*
X421770Y446174D01*
G01X414502Y441240D02*
X419996Y446734D01*
G01X433202Y432679D02*
X418053Y447829D01*
G01X415827Y450054D02*
X413052Y452829D01*
G01X433202Y430346D02*
X410719Y452829D01*
G01X412652Y446229D02*
X406052Y452829D01*
G01X410319Y446229D02*
X403719Y452829D01*
G01X414502Y443573D02*
X418471Y447542D01*
G01X414502Y445907D02*
X417155Y448560D01*
G01X412491Y446229D02*
X416036Y449775D01*
G01X410158Y446229D02*
X415118Y451189D01*
G01X407824Y446229D02*
X414424Y452829D01*
G01X405491Y446229D02*
X412091Y452829D01*
G01X403158Y446229D02*
X409758Y452829D01*
G01X414425D02*
G03X433279I9427J3024D01*
G01X433202Y402345D02*
X432596Y402951D01*
G01X432457Y403193D02*
X433202Y403936D01*
G01X431488Y404557D02*
X433202Y406270D01*
G01X430323Y405725D02*
X433202Y408604D01*
G01X428962Y406697D02*
X433202Y410937D01*
G01X427387Y407455D02*
X433202Y413270D01*
G01X425554Y407956D02*
X433202Y415604D01*
G01X423354Y408089D02*
X433202Y417937D01*
G01Y401644D02*
X433201Y401645D01*
G01X433202Y446229D02*
Y401644D01*
G01X420429Y407497D02*
X433202Y420270D01*
G01Y442014D02*
X428238Y446977D01*
G01X433202Y439680D02*
X426553Y446328D01*
G01X433202Y437347D02*
X424570Y445978D01*
G01X433202Y435014D02*
X422107Y446107D01*
G01X433279Y452829D02*
X491425D01*
G01X440340Y446543D02*
X434053Y452829D01*
G01X438007Y446543D02*
X432842Y451707D01*
G01X435672Y446543D02*
X431994Y450221D01*
G01X433427Y446455D02*
X430940Y448942D01*
G01X433202Y444347D02*
X429691Y447857D01*
G01X433806Y446543D02*
X440092Y452829D01*
G01X433515Y446543D02*
X433202Y446229D01*
G01X448657Y446543D02*
X433515D01*
G01X454254Y439629D02*
X448877Y445006D01*
G01X451921Y439629D02*
X448877Y442673D01*
G01X449586Y439629D02*
X448877Y440339D01*
G01X452561Y439629D02*
X465760Y452829D01*
G01X450227Y439629D02*
X463427Y452829D01*
G01X448877Y440613D02*
X461092Y452828D01*
G01X448877Y439629D02*
Y446504D01*
G01X475827Y439629D02*
X448877D01*
G01X463587D02*
X450387Y452829D01*
G01X461254Y439629D02*
X448054Y452829D01*
G01X458920Y439629D02*
X445721Y452829D01*
G01X456587Y439629D02*
X443387Y452829D01*
G01X447340Y446543D02*
X441054Y452829D01*
G01X445007Y446543D02*
X438721Y452829D01*
G01X442673Y446543D02*
X436386Y452829D01*
G01X448877Y442946D02*
X458759Y452829D01*
G01X448877Y445280D02*
X456426Y452829D01*
G01X447807Y446543D02*
X454092Y452828D01*
G01X445472Y446543D02*
X451759Y452829D01*
G01X443139Y446543D02*
X449426Y452829D01*
G01X440806Y446543D02*
X447093Y452829D01*
G01X438472Y446543D02*
X444758Y452829D01*
G01X436139Y446543D02*
X442425Y452829D01*
G01X448877Y446504D02*
X448657Y446543D01*
G01X470588Y439629D02*
X457388Y452829D01*
G01X468254Y439629D02*
X455054Y452829D01*
G01X468895Y439629D02*
X482095Y452829D01*
G01X466562Y439629D02*
X479760Y452829D01*
G01X464227Y439629D02*
X477427Y452829D01*
G01X461894Y439629D02*
X475094Y452829D01*
G01X459561Y439629D02*
X472760Y452829D01*
G01X457227Y439629D02*
X470427Y452829D01*
G01X454894Y439629D02*
X468093Y452828D01*
G01X465920Y439629D02*
X452721Y452829D01*
G01X475827Y446058D02*
X469055Y452829D01*
G01X475827Y443725D02*
X466722Y452829D01*
G01X475827Y441390D02*
X464388Y452829D01*
G01X475255Y439629D02*
X462055Y452829D01*
G01X472922Y439629D02*
X459722Y452829D01*
G01X488585Y351629D02*
X485010Y355204D01*
G01X475827Y359720D02*
X473467Y362079D01*
G01X475827Y357387D02*
X472252Y360961D01*
G01X474537Y351933D02*
X477807Y355204D01*
G01X473369Y353100D02*
X475827Y355556D01*
G01X472252Y354315D02*
X475827Y357890D01*
G01X472252Y356649D02*
X475827Y360224D01*
G01X472252Y358983D02*
X475348Y362079D01*
G01X475827Y355204D02*
X491502D01*
G01X475827Y362079D02*
Y355204D01*
G01X472252Y354218D02*
Y362079D01*
G01X486250Y351629D02*
X482675Y355204D01*
G01X483917Y351629D02*
X480342Y355204D01*
G01X481584Y351629D02*
X478009Y355204D01*
G01X479250Y351629D02*
X472252Y358627D01*
G01X476917Y351629D02*
X472252Y356294D01*
G01X483566Y351629D02*
X487140Y355203D01*
G01X481233Y351629D02*
X484807Y355204D01*
G01X478899Y351629D02*
X482474Y355203D01*
G01X476566Y351629D02*
X480140Y355203D01*
G01X526862Y351629D02*
X474840D01*
G01D02*
X472252Y354218D01*
G01X475827Y362053D02*
X475800Y362079D01*
G01X472252Y361316D02*
X473015Y362079D01*
G01X472252D02*
X475827D01*
G01X473561Y439629D02*
X475827Y441894D01*
G01X471228Y439629D02*
X475827Y444228D01*
G01Y446504D02*
Y439629D01*
G01X510202Y428017D02*
X485389Y452829D01*
G01X489381Y446504D02*
X483056Y452829D01*
G01X487048Y446504D02*
X480723Y452829D01*
G01X484714Y446504D02*
X478389Y452829D01*
G01X482381Y446504D02*
X476056Y452829D01*
G01X480046Y446504D02*
X473723Y452829D01*
G01X477713Y446504D02*
X471388Y452829D01*
G01X485103Y446504D02*
X491425Y452826D01*
G01X482770Y446504D02*
X489095Y452829D01*
G01X480436Y446504D02*
X486761Y452829D01*
G01X478103Y446504D02*
X484428Y452829D01*
G01X491502Y446504D02*
X475827D01*
G01X491502Y357232D02*
X510202Y375932D01*
G01X491502Y359565D02*
X510202Y378265D01*
G01X491502Y355204D02*
Y446504D01*
G01X509586Y351629D02*
X491502Y369712D01*
G01X507252Y351629D02*
X491502Y367379D01*
G01X504919Y351629D02*
X491502Y365046D01*
G01X502585Y351629D02*
X491502Y362712D01*
G01X500251Y351629D02*
X491502Y360379D01*
G01X497918Y351629D02*
X491502Y358046D01*
G01X495585Y351629D02*
X491502Y355711D01*
G01X493251Y351629D02*
X489676Y355204D01*
G01X499900Y351629D02*
X510202Y361931D01*
G01X497567Y351629D02*
X510202Y364264D01*
G01X495233Y351629D02*
X510202Y366597D01*
G01X492900Y351629D02*
X510202Y368931D01*
G01X490567Y351629D02*
X510202Y371264D01*
G01X488233Y351629D02*
X510202Y373597D01*
G01X490918Y351629D02*
X487343Y355204D01*
G01X485900Y351629D02*
X489475Y355204D01*
G01X510202Y367347D02*
X491502Y386047D01*
G01X510202Y365014D02*
X491502Y383713D01*
G01X510202Y362680D02*
X491502Y381380D01*
G01X510202Y360347D02*
X491502Y379047D01*
G01X510202Y358014D02*
X491502Y376713D01*
G01X510202Y355679D02*
X491502Y374379D01*
G01Y361898D02*
X510202Y380598D01*
G01X491502Y364232D02*
X510202Y382931D01*
G01X491502Y366565D02*
X510202Y385265D01*
G01X491502Y368898D02*
X510202Y387598D01*
G01X491502Y371232D02*
X510202Y389931D01*
G01X491502Y373565D02*
X510202Y392265D01*
G01X491502Y375899D02*
X510202Y394599D01*
G01X511919Y351629D02*
X491502Y372046D01*
G01Y385233D02*
X510202Y403932D01*
G01X491502Y387566D02*
X510202Y406266D01*
G01X491502Y389899D02*
X510202Y408599D01*
G01X491502Y392234D02*
X510202Y410932D01*
G01Y383681D02*
X491502Y402381D01*
G01X510202Y381348D02*
X491502Y400048D01*
G01X510202Y379014D02*
X491502Y397714D01*
G01X510202Y376681D02*
X491502Y395381D01*
G01X510202Y374348D02*
X491502Y393048D01*
G01X510202Y372013D02*
X491502Y390713D01*
G01X510202Y369680D02*
X491502Y388380D01*
G01Y378233D02*
X510202Y396932D01*
G01X491502Y380566D02*
X510202Y399266D01*
G01X491502Y382899D02*
X510202Y401599D01*
G01Y400015D02*
X491502Y418715D01*
G01X510202Y397682D02*
X491502Y416382D01*
G01X510202Y395349D02*
X491502Y414048D01*
G01X510202Y393015D02*
X491502Y411715D01*
G01X510202Y390681D02*
X491502Y409381D01*
G01X510202Y388348D02*
X491502Y407047D01*
G01X510202Y386014D02*
X491502Y404714D01*
G01Y394567D02*
X510202Y413267D01*
G01X491502Y396900D02*
X510202Y415600D01*
G01X491502Y399234D02*
X510202Y417933D01*
G01X491502Y401567D02*
X510202Y420267D01*
G01X491502Y403900D02*
X510202Y422600D01*
G01X491502Y406233D02*
X510202Y424933D01*
G01X491502Y408567D02*
X510202Y427267D01*
G01X491502Y417901D02*
X510202Y436601D01*
G01X491502Y420234D02*
X510202Y438934D01*
G01X491502Y422568D02*
X510202Y441267D01*
G01X491502Y424901D02*
X510202Y443601D01*
G01Y416350D02*
X491502Y435049D01*
G01X510202Y414016D02*
X491502Y432716D01*
G01X510202Y411683D02*
X491502Y430383D01*
G01X510202Y409350D02*
X491502Y428048D01*
G01X510202Y407015D02*
X491502Y425715D01*
G01X510202Y404682D02*
X491502Y423382D01*
G01X510202Y402349D02*
X491502Y421048D01*
G01Y410901D02*
X510202Y429601D01*
G01X491502Y413234D02*
X510202Y431934D01*
G01X491502Y415568D02*
X510202Y434268D01*
G01Y432684D02*
X495067Y447819D01*
G01X510202Y425683D02*
X491502Y444383D01*
G01X510202Y423350D02*
X491502Y442049D01*
G01X510202Y421016D02*
X491502Y439716D01*
G01X510202Y418683D02*
X491502Y437383D01*
G01Y427234D02*
X510202Y445934D01*
G01X491502Y429569D02*
X514762Y452828D01*
G01X491502Y431902D02*
X512429Y452829D01*
G01X491502Y434235D02*
X503612Y446345D01*
G01X491502Y436569D02*
X500886Y445952D01*
G01X491502Y438902D02*
X498773Y446173D01*
G01X491502Y441235D02*
X496999Y446733D01*
G01X510202Y430350D02*
X487722Y452829D01*
G01X510202Y437350D02*
X501573Y445978D01*
G01X510202Y435017D02*
X499113Y446106D01*
G01X492817Y450067D02*
X490056Y452829D01*
G01X491502Y443569D02*
X495474Y447540D01*
G01X491502Y445903D02*
X494157Y448558D01*
G01X489769Y446504D02*
X493039Y449772D01*
G01X491425Y452829D02*
G03X510279I9427J3024D01*
G01X487436Y446504D02*
X492119Y451187D01*
G01X521252Y351629D02*
X517677Y355204D01*
G01X510202D02*
X525877D01*
G01X510202Y446504D02*
Y355204D01*
G01X518919Y351629D02*
X515344Y355204D01*
G01X516585Y351629D02*
X513011Y355204D01*
G01X514252Y351629D02*
X510677Y355204D01*
G01X518568Y351629D02*
X522142Y355204D01*
G01X516234Y351629D02*
X519809Y355204D01*
G01X513901Y351629D02*
X517476Y355204D01*
G01X511568Y351629D02*
X515143Y355204D01*
G01X509234Y351629D02*
X512809Y355204D01*
G01X506901Y351629D02*
X510476Y355204D01*
G01X504568Y351629D02*
X510202Y357263D01*
G01X502233Y351629D02*
X510202Y359597D01*
G01Y442017D02*
X505241Y446978D01*
G01X510202Y439684D02*
X503557Y446329D01*
G01X510279Y452829D02*
X526862D01*
G01X524383Y446504D02*
X518058Y452829D01*
G01X522049Y446504D02*
X515724Y452829D01*
G01X519716Y446504D02*
X513391Y452829D01*
G01X517383Y446504D02*
X511058Y452829D01*
G01X515048Y446504D02*
X509843Y451709D01*
G01X512715Y446504D02*
X508996Y450223D01*
G01X510382Y446504D02*
X507942Y448943D01*
G01X510202Y444350D02*
X506693Y447859D01*
G01X517771Y446504D02*
X524096Y452829D01*
G01X515438Y446504D02*
X521763Y452829D01*
G01X513105Y446504D02*
X519430Y452829D01*
G01X510771Y446504D02*
X517096Y452829D01*
G01X525877Y446504D02*
X510202D01*
G01X529452Y359764D02*
X527137Y362078D01*
G01X529452Y357431D02*
X525877Y361006D01*
G01X529452Y355098D02*
X525877Y358673D01*
G01X528725Y353490D02*
X525877Y356338D01*
G01X527558Y352324D02*
X524678Y355204D01*
G01X525877Y356605D02*
X529452Y360180D01*
G01X525877Y358938D02*
X529017Y362079D01*
G01X529452D02*
Y354218D01*
G01X525877Y355204D02*
Y362079D01*
G01X525920Y351629D02*
X522345Y355204D01*
G01X525569Y351629D02*
X529452Y355512D01*
G01X523235Y351629D02*
X529452Y357845D01*
G01X520902Y351629D02*
X524477Y355204D01*
G01X529452Y354218D02*
X526862Y351629D01*
G01X523586D02*
X520012Y355204D01*
G01X525877Y361272D02*
X526684Y362079D01*
G01X525877D02*
X529452D01*
G01Y441435D02*
X525877Y445009D01*
G01X528924Y439629D02*
X525877Y442676D01*
G01X526591Y439629D02*
X525877Y440343D01*
G01X527231Y439629D02*
X529452Y441850D01*
G01X525877Y440608D02*
X529452Y444183D01*
G01X525877Y439629D02*
Y446504D01*
G01X529452Y439629D02*
X525877D01*
G01X529452Y450240D02*
Y439629D01*
G01Y448436D02*
X525058Y452829D01*
G01X529452Y446102D02*
X522724Y452829D01*
G01X525877Y442942D02*
X529452Y446517D01*
G01X525877Y445276D02*
X529452Y448851D01*
G01X524771Y446504D02*
X528980Y450712D01*
G01X522438Y446504D02*
X527813Y451879D01*
G01X526862Y452829D02*
X529452Y450240D01*
G01Y443769D02*
X520391Y452829D01*
G01X520105Y446504D02*
X526430Y452829D01*
G01X650490Y359879D02*
X664202Y373590D01*
G01X648157Y359879D02*
X664202Y375923D01*
G01X645824Y359879D02*
X664202Y378257D01*
G01X648343Y359879D02*
X645502Y362721D01*
G01X646009Y359879D02*
X645502Y360386D01*
G01X664202Y359879D02*
X645502D01*
G01D02*
Y441829D01*
G01Y361890D02*
X664202Y380590D01*
G01X645502Y364224D02*
X664202Y382923D01*
G01X645502Y366557D02*
X664202Y385257D01*
G01X645502Y368890D02*
X664202Y387590D01*
G01X645502Y371225D02*
X664202Y389924D01*
G01X645502Y373558D02*
X664202Y392258D01*
G01X645502Y375891D02*
X664202Y394591D01*
G01Y360354D02*
X645502Y379054D01*
G01X662344Y359879D02*
X645502Y376720D01*
G01X660010Y359879D02*
X645502Y374387D01*
G01X657677Y359879D02*
X645502Y372054D01*
G01X655344Y359879D02*
X645502Y369720D01*
G01X653009Y359879D02*
X645502Y367387D01*
G01X650676Y359879D02*
X645502Y365054D01*
G01Y385224D02*
X664202Y403924D01*
G01X645502Y387559D02*
X664202Y406259D01*
G01X645502Y389892D02*
X664202Y408592D01*
G01X645502Y392225D02*
X664202Y410925D01*
G01Y379023D02*
X645502Y397721D01*
G01X664202Y376688D02*
X645502Y395388D01*
G01X664202Y374355D02*
X645502Y393055D01*
G01Y378225D02*
X664202Y396924D01*
G01X645502Y380558D02*
X664202Y399258D01*
G01X645502Y382891D02*
X664202Y401591D01*
G01Y372022D02*
X645502Y390721D01*
G01X664202Y369688D02*
X645502Y388388D01*
G01X664202Y367355D02*
X645502Y386055D01*
G01X664202Y365022D02*
X645502Y383721D01*
G01X664202Y362688D02*
X645502Y381388D01*
G01Y394559D02*
X664202Y413258D01*
G01X645502Y396892D02*
X664202Y415592D01*
G01X645502Y399225D02*
X664202Y417925D01*
G01X645502Y401559D02*
X664202Y420258D01*
G01X645502Y403892D02*
X664202Y422592D01*
G01X645502Y406226D02*
X664202Y424926D01*
G01X645502Y408560D02*
X664202Y427259D01*
G01Y395356D02*
X645502Y414056D01*
G01X664202Y393022D02*
X645502Y411722D01*
G01X664202Y390689D02*
X645502Y409389D01*
G01X664202Y388356D02*
X645502Y407056D01*
G01X664202Y386023D02*
X645502Y404722D01*
G01X664202Y383689D02*
X645502Y402389D01*
G01X664202Y381356D02*
X645502Y400056D01*
G01Y417893D02*
X664202Y436593D01*
G01X645502Y420226D02*
X664202Y438926D01*
G01X645502Y422561D02*
X664202Y441259D01*
G01X645502Y424894D02*
X662437Y441829D01*
G01X664202Y411690D02*
X645502Y430390D01*
G01X664202Y409357D02*
X645502Y428056D01*
G01X664202Y407023D02*
X645502Y425723D01*
G01Y410893D02*
X664202Y429593D01*
G01X645502Y413226D02*
X664202Y431926D01*
G01X645502Y415560D02*
X664202Y434259D01*
G01Y404690D02*
X645502Y423390D01*
G01X664202Y402357D02*
X645502Y421057D01*
G01X664202Y400023D02*
X645502Y418723D01*
G01X664202Y397690D02*
X645502Y416390D01*
G01Y427227D02*
X660104Y441829D01*
G01X645502Y429561D02*
X657770Y441829D01*
G01X645502Y431894D02*
X655437Y441829D01*
G01X645502Y434227D02*
X653104Y441829D01*
G01X645502Y436561D02*
X650770Y441829D01*
G01X645502Y438894D02*
X648437Y441829D01*
G01X645502Y441228D02*
X646104Y441829D01*
G01X664202Y428024D02*
X650397Y441829D01*
G01X664202Y425691D02*
X648064Y441829D01*
G01X664202Y423358D02*
X645731Y441829D01*
G01X664202Y421024D02*
X645502Y439724D01*
G01X664202Y418691D02*
X645502Y437391D01*
G01X664202Y416358D02*
X645502Y435057D01*
G01X664202Y414023D02*
X645502Y432723D01*
G01Y441829D02*
X664202D01*
G01X662158Y359879D02*
X664202Y361922D01*
G01X659825Y359879D02*
X664202Y364256D01*
G01X657491Y359879D02*
X664202Y366589D01*
G01X655158Y359879D02*
X664202Y368922D01*
G01X652825Y359879D02*
X664202Y371257D01*
G01Y441829D02*
Y359879D01*
G01Y439692D02*
X662065Y441829D01*
G01X664202Y437359D02*
X659731Y441829D01*
G01X664202Y435025D02*
X657397Y441829D01*
G01X664202Y432692D02*
X655064Y441829D01*
G01X664202Y430358D02*
X652731Y441829D01*
G01X732162Y359879D02*
X741202Y368919D01*
G01X729828Y359879D02*
X741202Y371252D01*
G01X727495Y359879D02*
X741202Y373585D01*
G01X725162Y359879D02*
X741202Y375919D01*
G01X722827Y359879D02*
X741202Y378253D01*
G01X732347Y359879D02*
X722502Y369724D01*
G01X730014Y359879D02*
X722502Y367391D01*
G01X727681Y359879D02*
X722502Y365057D01*
G01X725346Y359879D02*
X722502Y362724D01*
G01X723013Y359879D02*
X722502Y360391D01*
G01X741202Y359879D02*
X722502D01*
G01D02*
Y441829D01*
G01Y361887D02*
X741202Y380586D01*
G01X722502Y364220D02*
X741202Y382920D01*
G01X722502Y366553D02*
X741202Y385253D01*
G01X722502Y368887D02*
X741202Y387586D01*
G01X722502Y371220D02*
X741202Y389920D01*
G01X722502Y373553D02*
X741202Y392253D01*
G01X722502Y375888D02*
X741202Y394586D01*
G01Y367359D02*
X722502Y386058D01*
G01X741202Y365025D02*
X722502Y383725D01*
G01X741202Y362692D02*
X722502Y381392D01*
G01X741202Y360359D02*
X722502Y379058D01*
G01X739347Y359879D02*
X722502Y376725D01*
G01X737014Y359879D02*
X722502Y374392D01*
G01X734681Y359879D02*
X722502Y372057D01*
G01Y385221D02*
X741202Y403921D01*
G01X722502Y387554D02*
X741202Y406254D01*
G01X722502Y389888D02*
X741202Y408587D01*
G01X722502Y392221D02*
X741202Y410921D01*
G01X722502Y378221D02*
X741202Y396921D01*
G01X722502Y380554D02*
X741202Y399254D01*
G01X722502Y382888D02*
X741202Y401587D01*
G01Y383693D02*
X722502Y402393D01*
G01X741202Y381359D02*
X722502Y400059D01*
G01X741202Y379026D02*
X722502Y397726D01*
G01X741202Y376693D02*
X722502Y395393D01*
G01X741202Y374360D02*
X722502Y393059D01*
G01X741202Y372025D02*
X722502Y390725D01*
G01X741202Y369692D02*
X722502Y388392D01*
G01Y394555D02*
X741202Y413255D01*
G01X722502Y396888D02*
X741202Y415588D01*
G01X722502Y399222D02*
X741202Y417922D01*
G01X722502Y401555D02*
X741202Y420255D01*
G01X722502Y403888D02*
X741202Y422588D01*
G01X722502Y406222D02*
X741202Y424922D01*
G01X722502Y408555D02*
X741202Y427255D01*
G01Y400027D02*
X722502Y418727D01*
G01X741202Y397694D02*
X722502Y416393D01*
G01X741202Y395360D02*
X722502Y414060D01*
G01X741202Y393027D02*
X722502Y411727D01*
G01X741202Y390694D02*
X722502Y409392D01*
G01X741202Y388359D02*
X722502Y407059D01*
G01X741202Y386026D02*
X722502Y404726D01*
G01Y417889D02*
X741202Y436589D01*
G01X722502Y420223D02*
X741202Y438922D01*
G01X722502Y422556D02*
X741202Y441256D01*
G01X722502Y424889D02*
X739441Y441829D01*
G01X722502Y410888D02*
X741202Y429588D01*
G01X722502Y413223D02*
X741202Y431922D01*
G01X722502Y415556D02*
X741202Y434256D01*
G01Y416361D02*
X722502Y435061D01*
G01X741202Y414028D02*
X722502Y432728D01*
G01X741202Y411695D02*
X722502Y430394D01*
G01X741202Y409361D02*
X722502Y428061D01*
G01X741202Y407027D02*
X722502Y425727D01*
G01X741202Y404694D02*
X722502Y423393D01*
G01X741202Y402360D02*
X722502Y421060D01*
G01Y427223D02*
X737108Y441829D01*
G01X722502Y429557D02*
X734775Y441829D01*
G01X722502Y431890D02*
X732440Y441829D01*
G01X722502Y434224D02*
X730107Y441829D01*
G01X722502Y436557D02*
X727774Y441829D01*
G01X722502Y438890D02*
X725440Y441829D01*
G01X722502Y441224D02*
X723107Y441829D01*
G01X741202Y432696D02*
X732069Y441829D01*
G01X741202Y430362D02*
X729734Y441829D01*
G01X741202Y428029D02*
X727401Y441829D01*
G01X741202Y425696D02*
X725068Y441829D01*
G01X741202Y423361D02*
X722734Y441829D01*
G01X741202Y421028D02*
X722502Y439728D01*
G01X741202Y418695D02*
X722502Y437394D01*
G01Y441829D02*
X741202D01*
G01X739162Y359879D02*
X741202Y361919D01*
G01X736828Y359879D02*
X741202Y364252D01*
G01X734495Y359879D02*
X741202Y366586D01*
G01Y441829D02*
Y359879D01*
G01Y439695D02*
X739068Y441829D01*
G01X741202Y437362D02*
X736735Y441829D01*
G01X741202Y435029D02*
X734402Y441829D01*
M02*
